G04 ================== begin FILE IDENTIFICATION RECORD ==================*
G04 Layout Name:  15105-sa.brd*
G04 Film Name:    L1*
G04 File Format:  Gerber RS274X*
G04 File Origin:  Cadence Allegro 16.5-S056*
G04 Origin Date:  Wed Nov 16 02:02:11 2016*
G04 *
G04 Layer:  VIA CLASS/TOP*
G04 Layer:  PIN/TOP*
G04 Layer:  ETCH/TOP*
G04 Layer:  DRAWING FORMAT/LAYER_PCB_STORY*
G04 Layer:  DRAWING FORMAT/LAYER_L1*
G04 *
G04 Offset:    (0.00 0.00)*
G04 Mirror:    No*
G04 Mode:      Positive*
G04 Rotation:  0*
G04 FullContactRelief:  No*
G04 UndefLineWidth:     6.00*
G04 ================== end FILE IDENTIFICATION RECORD ====================*
%FSLAX35Y35*MOIN*%
%IR0*IPPOS*OFA0.00000B0.00000*MIA0B0*SFA1.00000B1.00000*%
%AMMACRO41*
4,1,40,.013,.017,
-.013,.017,
-.013695,.016939,
-.014368,.016759,
-.015,.016464,
-.015571,.016064,
-.016064,.015571,
-.016464,.015,
-.016759,.014368,
-.016939,.013695,
-.017,.013,
-.017,-.013,
-.016939,-.013695,
-.016759,-.014368,
-.016464,-.015,
-.016064,-.015571,
-.015571,-.016064,
-.015,-.016464,
-.014368,-.016759,
-.013695,-.016939,
-.013,-.017,
.013,-.017,
.013695,-.016939,
.014368,-.016759,
.015,-.016464,
.015571,-.016064,
.016064,-.015571,
.016464,-.015,
.016759,-.014368,
.016939,-.013695,
.017,-.013,
.017,.013,
.016939,.013695,
.016759,.014368,
.016464,.015,
.016064,.015571,
.015571,.016064,
.015,.016464,
.014368,.016759,
.013695,.016939,
.013,.017,
0.0*
%
%ADD41MACRO41*%
%AMMACRO27*
4,1,40,.017,-.013,
.017,.013,
.016939,.013695,
.016759,.014368,
.016464,.015,
.016064,.015571,
.015571,.016064,
.015,.016464,
.014368,.016759,
.013695,.016939,
.013,.017,
-.013,.017,
-.013695,.016939,
-.014368,.016759,
-.015,.016464,
-.015571,.016064,
-.016064,.015571,
-.016464,.015,
-.016759,.014368,
-.016939,.013695,
-.017,.013,
-.017,-.013,
-.016939,-.013695,
-.016759,-.014368,
-.016464,-.015,
-.016064,-.015571,
-.015571,-.016064,
-.015,-.016464,
-.014368,-.016759,
-.013695,-.016939,
-.013,-.017,
.013,-.017,
.013695,-.016939,
.014368,-.016759,
.015,-.016464,
.015571,-.016064,
.016064,-.015571,
.016464,-.015,
.016759,-.014368,
.016939,-.013695,
.017,-.013,
0.0*
%
%ADD27MACRO27*%
%AMMACRO80*
4,1,15,-.0275,-.115,
-.0275,.02323,
-.02431,.026923,
-.021809,.031114,
-.020074,.035675,
-.019157,.040469,
-.019087,.045348,
-.019865,.050166,
-.021468,.054776,
-.023847,.059037,
-.02693,.06282,
-.0275,.06339,
-.0275,.115,
.0275,.115,
.0275,-.115,
-.0275,-.115,
0.0*
%
%ADD80MACRO80*%
%ADD122R,.045X.11*%
%ADD149R,.055X.11*%
%ADD106R,.111X.028*%
%ADD10C,.01*%
%ADD75R,.012X.008*%
%ADD11C,.02*%
%ADD98R,.085X.104*%
%ADD81C,.022*%
%ADD38C,.04*%
%ADD155C,.05*%
%ADD110C,.032*%
%ADD84C,.014*%
%ADD151R,.008X.06*%
%AMMACRO69*
4,1,40,.004,.007,
-.004,.007,
-.004347,.00697,
-.004684,.006879,
-.005,.006732,
-.005286,.006532,
-.005532,.006286,
-.005732,.006,
-.005879,.005684,
-.00597,.005347,
-.006,.005,
-.006,-.005,
-.00597,-.005347,
-.005879,-.005684,
-.005732,-.006,
-.005532,-.006286,
-.005286,-.006532,
-.005,-.006732,
-.004684,-.006879,
-.004347,-.00697,
-.004,-.007,
.004,-.007,
.004347,-.00697,
.004684,-.006879,
.005,-.006732,
.005286,-.006532,
.005532,-.006286,
.005732,-.006,
.005879,-.005684,
.00597,-.005347,
.006,-.005,
.006,.005,
.00597,.005347,
.005879,.005684,
.005732,.006,
.005532,.006286,
.005286,.006532,
.005,.006732,
.004684,.006879,
.004347,.00697,
.004,.007,
0.0*
%
%ADD69MACRO69*%
%ADD85C,.016*%
%ADD39C,.052*%
%ADD146R,.092X.128*%
%ADD132R,.039X.108*%
%ADD129C,.036*%
%ADD83C,.018*%
%ADD79C,.054*%
%ADD30C,.028*%
%ADD131C,.029*%
%ADD104C,.056*%
%ADD140R,.135X.098*%
%ADD12C,.066*%
%ADD127C,.058*%
%ADD154R,.044X.044*%
%AMMACRO120*
4,1,26,-.47244,-.55118,
-.47244,.55118,
.47244,.55118,
.47244,.19704,
.35433,.19704,
.348829,.196559,
.343495,.195129,
.33849,.192796,
.333966,.189628,
.330062,.185724,
.326894,.1812,
.324561,.176195,
.323131,.170861,
.32265,.16536,
.32265,-.1496,
.323131,-.155103,
.324561,-.160439,
.326896,-.165445,
.330064,-.16997,
.33397,-.173876,
.338495,-.177044,
.343501,-.179379,
.348837,-.180809,
.35433,-.18129,
.47244,-.18129,
.47244,-.55118,
-.47244,-.55118,
0.0*
%
%ADD120MACRO120*%
%AMMACRO32*
4,1,40,.0225,-.007,
.022378,-.008389,
.022018,-.009736,
.021428,-.011,
.020628,-.012142,
.019642,-.013128,
.0185,-.013928,
.017236,-.014518,
.015889,-.014878,
.0145,-.015,
-.0145,-.015,
-.015889,-.014878,
-.017236,-.014518,
-.0185,-.013928,
-.019642,-.013128,
-.020628,-.012142,
-.021428,-.011,
-.022018,-.009736,
-.022378,-.008389,
-.0225,-.007,
-.0225,.007,
-.022378,.008389,
-.022018,.009736,
-.021428,.011,
-.020628,.012142,
-.019642,.013128,
-.0185,.013928,
-.017236,.014518,
-.015889,.014878,
-.0145,.015,
.0145,.015,
.015889,.014878,
.017236,.014518,
.0185,.013928,
.019642,.013128,
.020628,.012142,
.021428,.011,
.022018,.009736,
.022378,.008389,
.0225,.007,
.0225,-.007,
0.0*
%
%ADD32MACRO32*%
%ADD15C,.078*%
%ADD150R,.045X.045*%
%AMMACRO67*
4,1,40,-.007,-.0225,
-.008389,-.022378,
-.009736,-.022018,
-.011,-.021428,
-.012142,-.020628,
-.013128,-.019642,
-.013928,-.0185,
-.014518,-.017236,
-.014878,-.015889,
-.015,-.0145,
-.015,.0145,
-.014878,.015889,
-.014518,.017236,
-.013928,.0185,
-.013128,.019642,
-.012142,.020628,
-.011,.021428,
-.009736,.022018,
-.008389,.022378,
-.007,.0225,
.007,.0225,
.008389,.022378,
.009736,.022018,
.011,.021428,
.012142,.020628,
.013128,.019642,
.013928,.0185,
.014518,.017236,
.014878,.015889,
.015,.0145,
.015,-.0145,
.014878,-.015889,
.014518,-.017236,
.013928,-.0185,
.013128,-.019642,
.012142,-.020628,
.011,-.021428,
.009736,-.022018,
.008389,-.022378,
.007,-.0225,
-.007,-.0225,
0.0*
%
%ADD67MACRO67*%
%AMMACRO33*
4,1,40,.007,.011,
-.007,.011,
-.007695,.010939,
-.008368,.010759,
-.009,.010464,
-.009571,.010064,
-.010064,.009571,
-.010464,.009,
-.010759,.008368,
-.010939,.007695,
-.011,.007,
-.011,-.007,
-.010939,-.007695,
-.010759,-.008368,
-.010464,-.009,
-.010064,-.009571,
-.009571,-.010064,
-.009,-.010464,
-.008368,-.010759,
-.007695,-.010939,
-.007,-.011,
.007,-.011,
.007695,-.010939,
.008368,-.010759,
.009,-.010464,
.009571,-.010064,
.010064,-.009571,
.010464,-.009,
.010759,-.008368,
.010939,-.007695,
.011,-.007,
.011,.007,
.010939,.007695,
.010759,.008368,
.010464,.009,
.010064,.009571,
.009571,.010064,
.009,.010464,
.008368,.010759,
.007695,.010939,
.007,.011,
0.0*
%
%ADD33MACRO33*%
%AMMACRO24*
4,1,40,.011,-.007,
.011,.007,
.010939,.007695,
.010759,.008368,
.010464,.009,
.010064,.009571,
.009571,.010064,
.009,.010464,
.008368,.010759,
.007695,.010939,
.007,.011,
-.007,.011,
-.007695,.010939,
-.008368,.010759,
-.009,.010464,
-.009571,.010064,
-.010064,.009571,
-.010464,.009,
-.010759,.008368,
-.010939,.007695,
-.011,.007,
-.011,-.007,
-.010939,-.007695,
-.010759,-.008368,
-.010464,-.009,
-.010064,-.009571,
-.009571,-.010064,
-.009,-.010464,
-.008368,-.010759,
-.007695,-.010939,
-.007,-.011,
.007,-.011,
.007695,-.010939,
.008368,-.010759,
.009,-.010464,
.009571,-.010064,
.010064,-.009571,
.010464,-.009,
.010759,-.008368,
.010939,-.007695,
.011,-.007,
0.0*
%
%ADD24MACRO24*%
%AMMACRO136*
4,1,40,-.012,.024,
.012,.024,
.013389,.023878,
.014736,.023518,
.016,.022928,
.017142,.022128,
.018128,.021142,
.018928,.02,
.019518,.018736,
.019878,.017389,
.02,.016,
.02,-.016,
.019878,-.017389,
.019518,-.018736,
.018928,-.02,
.018128,-.021142,
.017142,-.022128,
.016,-.022928,
.014736,-.023518,
.013389,-.023878,
.012,-.024,
-.012,-.024,
-.013389,-.023878,
-.014736,-.023518,
-.016,-.022928,
-.017142,-.022128,
-.018128,-.021142,
-.018928,-.02,
-.019518,-.018736,
-.019878,-.017389,
-.02,-.016,
-.02,.016,
-.019878,.017389,
-.019518,.018736,
-.018928,.02,
-.018128,.021142,
-.017142,.022128,
-.016,.022928,
-.014736,.023518,
-.013389,.023878,
-.012,.024,
0.0*
%
%ADD136MACRO136*%
%AMMACRO163*
4,1,45,.43011,.54331,
-.43012,.54331,
-.43012,-.5433,
.43011,-.5433,
.43011,-.19684,
.429811,-.193423,
.428923,-.190109,
.427473,-.187,
.425506,-.18419,
.42308,-.181764,
.42027,-.179797,
.417161,-.178347,
.413847,-.177459,
.41043,-.17716,
.39665,-.17716,
.393231,-.176859,
.389916,-.175969,
.386806,-.174517,
.383996,-.172547,
.38157,-.170119,
.379603,-.167306,
.378154,-.164195,
.377267,-.160879,
.37697,-.15747,
.37697,.15749,
.377269,.160907,
.378157,.164221,
.379607,.16733,
.381574,.17014,
.384,.172566,
.38681,.174533,
.389919,.175983,
.393233,.176871,
.39665,.17717,
.41043,.17717,
.413847,.177469,
.417161,.178357,
.42027,.179807,
.42308,.181774,
.425506,.1842,
.427473,.18701,
.428923,.190119,
.429811,.193433,
.43011,.19685,
.43011,.19686,
.43011,.54331,
0.0*
%
%ADD163MACRO163*%
%AMMACRO52*
4,1,20,.034,-.049,
.0155,-.049,
.0155,-.074,
.0045,-.074,
.0045,-.049,
-.0045,-.049,
-.0045,-.074,
-.0155,-.074,
-.0155,-.049,
-.034,-.049,
-.034,.049,
-.0155,.049,
-.0155,.074,
-.0045,.074,
-.0045,.049,
.0045,.049,
.0045,.074,
.0155,.074,
.0155,.049,
.034,.049,
.034,-.049,
0.0*
%
%ADD52MACRO52*%
%AMMACRO49*
4,1,40,-.012,.008,
-.012,-.008,
-.011939,-.008695,
-.011759,-.009368,
-.011464,-.01,
-.011064,-.010571,
-.010571,-.011064,
-.01,-.011464,
-.009368,-.011759,
-.008695,-.011939,
-.008,-.012,
.008,-.012,
.008695,-.011939,
.009368,-.011759,
.01,-.011464,
.010571,-.011064,
.011064,-.010571,
.011464,-.01,
.011759,-.009368,
.011939,-.008695,
.012,-.008,
.012,.008,
.011939,.008695,
.011759,.009368,
.011464,.01,
.011064,.010571,
.010571,.011064,
.01,.011464,
.009368,.011759,
.008695,.011939,
.008,.012,
-.008,.012,
-.008695,.011939,
-.009368,.011759,
-.01,.011464,
-.010571,.011064,
-.011064,.010571,
-.011464,.01,
-.011759,.009368,
-.011939,.008695,
-.012,.008,
0.0*
%
%ADD49MACRO49*%
%AMMACRO135*
4,1,20,-.049,-.034,
-.049,-.0155,
-.074,-.0155,
-.074,-.0045,
-.049,-.0045,
-.049,.0045,
-.074,.0045,
-.074,.0155,
-.049,.0155,
-.049,.034,
.049,.034,
.049,.0155,
.074,.0155,
.074,.0045,
.049,.0045,
.049,-.0045,
.074,-.0045,
.074,-.0155,
.049,-.0155,
.049,-.034,
-.049,-.034,
0.0*
%
%ADD135MACRO135*%
%AMMACRO13*
4,1,40,.008,.012,
-.008,.012,
-.008695,.011939,
-.009368,.011759,
-.01,.011464,
-.010571,.011064,
-.011064,.010571,
-.011464,.01,
-.011759,.009368,
-.011939,.008695,
-.012,.008,
-.012,-.008,
-.011939,-.008695,
-.011759,-.009368,
-.011464,-.01,
-.011064,-.010571,
-.010571,-.011064,
-.01,-.011464,
-.009368,-.011759,
-.008695,-.011939,
-.008,-.012,
.008,-.012,
.008695,-.011939,
.009368,-.011759,
.01,-.011464,
.010571,-.011064,
.011064,-.010571,
.011464,-.01,
.011759,-.009368,
.011939,-.008695,
.012,-.008,
.012,.008,
.011939,.008695,
.011759,.009368,
.011464,.01,
.011064,.010571,
.010571,.011064,
.01,.011464,
.009368,.011759,
.008695,.011939,
.008,.012,
0.0*
%
%ADD13MACRO13*%
%AMMACRO42*
4,1,40,-.013,-.017,
.013,-.017,
.013695,-.016939,
.014368,-.016759,
.015,-.016464,
.015571,-.016064,
.016064,-.015571,
.016464,-.015,
.016759,-.014368,
.016939,-.013695,
.017,-.013,
.017,.013,
.016939,.013695,
.016759,.014368,
.016464,.015,
.016064,.015571,
.015571,.016064,
.015,.016464,
.014368,.016759,
.013695,.016939,
.013,.017,
-.013,.017,
-.013695,.016939,
-.014368,.016759,
-.015,.016464,
-.015571,.016064,
-.016064,.015571,
-.016464,.015,
-.016759,.014368,
-.016939,.013695,
-.017,.013,
-.017,-.013,
-.016939,-.013695,
-.016759,-.014368,
-.016464,-.015,
-.016064,-.015571,
-.015571,-.016064,
-.015,-.016464,
-.014368,-.016759,
-.013695,-.016939,
-.013,-.017,
0.0*
%
%ADD42MACRO42*%
%AMMACRO137*
4,1,6,-.025,-.0135,
-.005,.0065,
-.005,.0135,
.005,.0135,
.005,.0065,
.025,-.0135,
-.025,-.0135,
0.0*
%
%ADD137MACRO137*%
%AMMACRO19*
4,1,40,-.017,.013,
-.017,-.013,
-.016939,-.013695,
-.016759,-.014368,
-.016464,-.015,
-.016064,-.015571,
-.015571,-.016064,
-.015,-.016464,
-.014368,-.016759,
-.013695,-.016939,
-.013,-.017,
.013,-.017,
.013695,-.016939,
.014368,-.016759,
.015,-.016464,
.015571,-.016064,
.016064,-.015571,
.016464,-.015,
.016759,-.014368,
.016939,-.013695,
.017,-.013,
.017,.013,
.016939,.013695,
.016759,.014368,
.016464,.015,
.016064,.015571,
.015571,.016064,
.015,.016464,
.014368,.016759,
.013695,.016939,
.013,.017,
-.013,.017,
-.013695,.016939,
-.014368,.016759,
-.015,.016464,
-.015571,.016064,
-.016064,.015571,
-.016464,.015,
-.016759,.014368,
-.016939,.013695,
-.017,.013,
0.0*
%
%ADD19MACRO19*%
%AMMACRO113*
4,1,6,.005,.0135,
.005,.0065,
.025,-.0135,
-.025,-.0135,
-.005,.0065,
-.005,.0135,
.005,.0135,
0.0*
%
%ADD113MACRO113*%
%AMMACRO164*
4,1,20,.0655,-.1095,
.051,-.1095,
.051,-.12,
.0375,-.12,
.0375,-.1095,
-.0375,-.1095,
-.0375,-.12,
-.051,-.12,
-.051,-.1095,
-.0655,-.1095,
-.0655,.1095,
-.051,.1095,
-.051,.12,
-.0375,.12,
-.0375,.1095,
.0375,.1095,
.0375,.12,
.051,.12,
.051,.1095,
.0655,.1095,
.0655,-.1095,
0.0*
%
%ADD164MACRO164*%
%AMMACRO61*
4,1,40,.023,-.013,
.023,.013,
.022939,.013695,
.022759,.014368,
.022464,.015,
.022064,.015571,
.021571,.016064,
.021,.016464,
.020368,.016759,
.019695,.016939,
.019,.017,
-.019,.017,
-.019695,.016939,
-.020368,.016759,
-.021,.016464,
-.021571,.016064,
-.022064,.015571,
-.022464,.015,
-.022759,.014368,
-.022939,.013695,
-.023,.013,
-.023,-.013,
-.022939,-.013695,
-.022759,-.014368,
-.022464,-.015,
-.022064,-.015571,
-.021571,-.016064,
-.021,-.016464,
-.020368,-.016759,
-.019695,-.016939,
-.019,-.017,
.019,-.017,
.019695,-.016939,
.020368,-.016759,
.021,-.016464,
.021571,-.016064,
.022064,-.015571,
.022464,-.015,
.022759,-.014368,
.022939,-.013695,
.023,-.013,
0.0*
%
%ADD61MACRO61*%
%AMMACRO34*
4,1,40,.007,.011,
-.007,.011,
-.007695,.010939,
-.008368,.010759,
-.009,.010464,
-.009571,.010064,
-.010064,.009571,
-.010464,.009,
-.010759,.008368,
-.010939,.007695,
-.011,.007,
-.011,-.007,
-.010939,-.007695,
-.010759,-.008368,
-.010464,-.009,
-.010064,-.009571,
-.009571,-.010064,
-.009,-.010464,
-.008368,-.010759,
-.007695,-.010939,
-.007,-.011,
.007,-.011,
.007695,-.010939,
.008368,-.010759,
.009,-.010464,
.009571,-.010064,
.010064,-.009571,
.010464,-.009,
.010759,-.008368,
.010939,-.007695,
.011,-.007,
.011,.007,
.010939,.007695,
.010759,.008368,
.010464,.009,
.010064,.009571,
.009571,.010064,
.009,.010464,
.008368,.010759,
.007695,.010939,
.007,.011,
0.0*
%
%ADD34MACRO34*%
%AMMACRO25*
4,1,40,.011,-.007,
.011,.007,
.010939,.007695,
.010759,.008368,
.010464,.009,
.010064,.009571,
.009571,.010064,
.009,.010464,
.008368,.010759,
.007695,.010939,
.007,.011,
-.007,.011,
-.007695,.010939,
-.008368,.010759,
-.009,.010464,
-.009571,.010064,
-.010064,.009571,
-.010464,.009,
-.010759,.008368,
-.010939,.007695,
-.011,.007,
-.011,-.007,
-.010939,-.007695,
-.010759,-.008368,
-.010464,-.009,
-.010064,-.009571,
-.009571,-.010064,
-.009,-.010464,
-.008368,-.010759,
-.007695,-.010939,
-.007,-.011,
.007,-.011,
.007695,-.010939,
.008368,-.010759,
.009,-.010464,
.009571,-.010064,
.010064,-.009571,
.010464,-.009,
.010759,-.008368,
.010939,-.007695,
.011,-.007,
0.0*
%
%ADD25MACRO25*%
%AMMACRO23*
4,1,40,-.012,.008,
-.012,-.008,
-.011939,-.008695,
-.011759,-.009368,
-.011464,-.01,
-.011064,-.010571,
-.010571,-.011064,
-.01,-.011464,
-.009368,-.011759,
-.008695,-.011939,
-.008,-.012,
.008,-.012,
.008695,-.011939,
.009368,-.011759,
.01,-.011464,
.010571,-.011064,
.011064,-.010571,
.011464,-.01,
.011759,-.009368,
.011939,-.008695,
.012,-.008,
.012,.008,
.011939,.008695,
.011759,.009368,
.011464,.01,
.011064,.010571,
.010571,.011064,
.01,.011464,
.009368,.011759,
.008695,.011939,
.008,.012,
-.008,.012,
-.008695,.011939,
-.009368,.011759,
-.01,.011464,
-.010571,.011064,
-.011064,.010571,
-.011464,.01,
-.011759,.009368,
-.011939,.008695,
-.012,.008,
0.0*
%
%ADD23MACRO23*%
%AMMACRO14*
4,1,40,.008,.012,
-.008,.012,
-.008695,.011939,
-.009368,.011759,
-.01,.011464,
-.010571,.011064,
-.011064,.010571,
-.011464,.01,
-.011759,.009368,
-.011939,.008695,
-.012,.008,
-.012,-.008,
-.011939,-.008695,
-.011759,-.009368,
-.011464,-.01,
-.011064,-.010571,
-.010571,-.011064,
-.01,-.011464,
-.009368,-.011759,
-.008695,-.011939,
-.008,-.012,
.008,-.012,
.008695,-.011939,
.009368,-.011759,
.01,-.011464,
.010571,-.011064,
.011064,-.010571,
.011464,-.01,
.011759,-.009368,
.011939,-.008695,
.012,-.008,
.012,.008,
.011939,.008695,
.011759,.009368,
.011464,.01,
.011064,.010571,
.010571,.011064,
.01,.011464,
.009368,.011759,
.008695,.011939,
.008,.012,
0.0*
%
%ADD14MACRO14*%
%AMMACRO43*
4,1,40,-.013,-.017,
.013,-.017,
.013695,-.016939,
.014368,-.016759,
.015,-.016464,
.015571,-.016064,
.016064,-.015571,
.016464,-.015,
.016759,-.014368,
.016939,-.013695,
.017,-.013,
.017,.013,
.016939,.013695,
.016759,.014368,
.016464,.015,
.016064,.015571,
.015571,.016064,
.015,.016464,
.014368,.016759,
.013695,.016939,
.013,.017,
-.013,.017,
-.013695,.016939,
-.014368,.016759,
-.015,.016464,
-.015571,.016064,
-.016064,.015571,
-.016464,.015,
-.016759,.014368,
-.016939,.013695,
-.017,.013,
-.017,-.013,
-.016939,-.013695,
-.016759,-.014368,
-.016464,-.015,
-.016064,-.015571,
-.015571,-.016064,
-.015,-.016464,
-.014368,-.016759,
-.013695,-.016939,
-.013,-.017,
0.0*
%
%ADD43MACRO43*%
%AMMACRO18*
4,1,40,-.017,.013,
-.017,-.013,
-.016939,-.013695,
-.016759,-.014368,
-.016464,-.015,
-.016064,-.015571,
-.015571,-.016064,
-.015,-.016464,
-.014368,-.016759,
-.013695,-.016939,
-.013,-.017,
.013,-.017,
.013695,-.016939,
.014368,-.016759,
.015,-.016464,
.015571,-.016064,
.016064,-.015571,
.016464,-.015,
.016759,-.014368,
.016939,-.013695,
.017,-.013,
.017,.013,
.016939,.013695,
.016759,.014368,
.016464,.015,
.016064,.015571,
.015571,.016064,
.015,.016464,
.014368,.016759,
.013695,.016939,
.013,.017,
-.013,.017,
-.013695,.016939,
-.014368,.016759,
-.015,.016464,
-.015571,.016064,
-.016064,.015571,
-.016464,.015,
-.016759,.014368,
-.016939,.013695,
-.017,.013,
0.0*
%
%ADD18MACRO18*%
%AMMACRO62*
4,1,40,-.019,-.017,
.019,-.017,
.019695,-.016939,
.020368,-.016759,
.021,-.016464,
.021571,-.016064,
.022064,-.015571,
.022464,-.015,
.022759,-.014368,
.022939,-.013695,
.023,-.013,
.023,.013,
.022939,.013695,
.022759,.014368,
.022464,.015,
.022064,.015571,
.021571,.016064,
.021,.016464,
.020368,.016759,
.019695,.016939,
.019,.017,
-.019,.017,
-.019695,.016939,
-.020368,.016759,
-.021,.016464,
-.021571,.016064,
-.022064,.015571,
-.022464,.015,
-.022759,.014368,
-.022939,.013695,
-.023,.013,
-.023,-.013,
-.022939,-.013695,
-.022759,-.014368,
-.022464,-.015,
-.022064,-.015571,
-.021571,-.016064,
-.021,-.016464,
-.020368,-.016759,
-.019695,-.016939,
-.019,-.017,
0.0*
%
%ADD62MACRO62*%
%ADD159R,.135X.21*%
%ADD76R,.012X.022*%
%ADD145R,.041X.012*%
%ADD143R,.012X.041*%
%ADD31R,.04X.022*%
%ADD125R,.06X.012*%
%ADD94R,.02X.06*%
%ADD51R,.022X.04*%
%ADD82R,.023X.04*%
%ADD59R,.012X.042*%
%ADD57R,.042X.012*%
%ADD114R,.044X.012*%
%ADD109R,.06X.014*%
%ADD108R,.04X.016*%
%ADD54R,.03X.026*%
%ADD126O,.046X.041*%
%ADD123R,.014X.06*%
%ADD118R,.026X.03*%
%ADD55R,.016X.04*%
%ADD47R,.012X.036*%
%ADD46R,.036X.012*%
%ADD147R,.041X.053*%
%ADD144R,.037X.012*%
%ADD141R,.012X.037*%
%ADD130C,.103*%
%ADD101R,.06X.016*%
%ADD77R,.03X.045*%
%ADD58R,.012X.036*%
%ADD56R,.036X.012*%
%ADD48R,.012X.046*%
%ADD45R,.046X.012*%
%ADD160R,.028X.03*%
%ADD121R,.115X.138*%
%ADD100R,.012X.038*%
%ADD99R,.038X.012*%
%ADD87R,.03X.064*%
%ADD86R,.016X.06*%
%ADD115R,.02X.066*%
%ADD92R,.022X.091*%
%ADD139R,.042X.055*%
%ADD107R,.05X.065*%
%ADD97R,.104X.187*%
%ADD91R,.022X.074*%
%ADD152R,.037X.042*%
%ADD103R,.02X.059*%
%ADD78C,.107*%
%ADD74R,.065X.05*%
%ADD153R,.044X.028*%
%ADD117R,.065X.025*%
%ADD102R,.036X.026*%
%ADD37C,.315*%
%ADD158R,.028X.044*%
%ADD88R,.09X.045*%
%ADD71R,.048X.016*%
%ADD70R,.036X.055*%
%ADD53R,.045X.055*%
%ADD50R,.025X.065*%
%ADD142R,.13X.13*%
%ADD89R,.197X.205*%
%ADD68R,.016X.048*%
%ADD26R,.055X.045*%
%ADD134R,.054X.074*%
%ADD95R,.075X.045*%
%ADD44C,.256*%
%ADD96R,.057X.083*%
%ADD93R,.09X.095*%
%ADD90R,.059X.045*%
%ADD65R,.142X.142*%
%ADD64R,.024X.079*%
%ADD22R,.075X.065*%
%AMMACRO128*
4,1,40,-.0225,.007,
-.022378,.008389,
-.022018,.009736,
-.021428,.011,
-.020628,.012142,
-.019642,.013128,
-.0185,.013928,
-.017236,.014518,
-.015889,.014878,
-.0145,.015,
.0145,.015,
.015889,.014878,
.017236,.014518,
.0185,.013928,
.019642,.013128,
.020628,.012142,
.021428,.011,
.022018,.009736,
.022378,.008389,
.0225,.007,
.0225,-.007,
.022378,-.008389,
.022018,-.009736,
.021428,-.011,
.020628,-.012142,
.019642,-.013128,
.0185,-.013928,
.017236,-.014518,
.015889,-.014878,
.0145,-.015,
-.0145,-.015,
-.015889,-.014878,
-.017236,-.014518,
-.0185,-.013928,
-.019642,-.013128,
-.020628,-.012142,
-.021428,-.011,
-.022018,-.009736,
-.022378,-.008389,
-.0225,-.007,
-.0225,.007,
0.0*
%
%ADD128MACRO128*%
%ADD124R,.095X.09*%
%AMMACRO66*
4,1,40,.007,.0225,
.008389,.022378,
.009736,.022018,
.011,.021428,
.012142,.020628,
.013128,.019642,
.013928,.0185,
.014518,.017236,
.014878,.015889,
.015,.0145,
.015,-.0145,
.014878,-.015889,
.014518,-.017236,
.013928,-.0185,
.013128,-.019642,
.012142,-.020628,
.011,-.021428,
.009736,-.022018,
.008389,-.022378,
.007,-.0225,
-.007,-.0225,
-.008389,-.022378,
-.009736,-.022018,
-.011,-.021428,
-.012142,-.020628,
-.013128,-.019642,
-.013928,-.0185,
-.014518,-.017236,
-.014878,-.015889,
-.015,-.0145,
-.015,.0145,
-.014878,.015889,
-.014518,.017236,
-.013928,.0185,
-.013128,.019642,
-.012142,.020628,
-.011,.021428,
-.009736,.022018,
-.008389,.022378,
-.007,.0225,
.007,.0225,
0.0*
%
%ADD66MACRO66*%
%ADD161R,.057X.039*%
%ADD133R,.069X.055*%
%ADD60R,.136X.136*%
%ADD116R,.059X.039*%
%ADD105R,.272X.272*%
%AMMACRO162*
4,1,40,.024,.012,
.024,-.012,
.023878,-.013389,
.023518,-.014736,
.022928,-.016,
.022128,-.017142,
.021142,-.018128,
.02,-.018928,
.018736,-.019518,
.017389,-.019878,
.016,-.02,
-.016,-.02,
-.017389,-.019878,
-.018736,-.019518,
-.02,-.018928,
-.021142,-.018128,
-.022128,-.017142,
-.022928,-.016,
-.023518,-.014736,
-.023878,-.013389,
-.024,-.012,
-.024,.012,
-.023878,.013389,
-.023518,.014736,
-.022928,.016,
-.022128,.017142,
-.021142,.018128,
-.02,.018928,
-.018736,.019518,
-.017389,.019878,
-.016,.02,
.016,.02,
.017389,.019878,
.018736,.019518,
.02,.018928,
.021142,.018128,
.022128,.017142,
.022928,.016,
.023518,.014736,
.023878,.013389,
.024,.012,
0.0*
%
%ADD162MACRO162*%
%AMMACRO157*
4,1,40,.012,-.024,
-.012,-.024,
-.013389,-.023878,
-.014736,-.023518,
-.016,-.022928,
-.017142,-.022128,
-.018128,-.021142,
-.018928,-.02,
-.019518,-.018736,
-.019878,-.017389,
-.02,-.016,
-.02,.016,
-.019878,.017389,
-.019518,.018736,
-.018928,.02,
-.018128,.021142,
-.017142,.022128,
-.016,.022928,
-.014736,.023518,
-.013389,.023878,
-.012,.024,
.012,.024,
.013389,.023878,
.014736,.023518,
.016,.022928,
.017142,.022128,
.018128,.021142,
.018928,.02,
.019518,.018736,
.019878,.017389,
.02,.016,
.02,-.016,
.019878,-.017389,
.019518,-.018736,
.018928,-.02,
.018128,-.021142,
.017142,-.022128,
.016,-.022928,
.014736,-.023518,
.013389,-.023878,
.012,-.024,
0.0*
%
%ADD157MACRO157*%
%ADD156R,.047X.098*%
%ADD148R,.472X.866*%
%AMMACRO119*
4,1,20,-.034,.049,
-.0155,.049,
-.0155,.074,
-.0045,.074,
-.0045,.049,
.0045,.049,
.0045,.074,
.0155,.074,
.0155,.049,
.034,.049,
.034,-.049,
.0155,-.049,
.0155,-.074,
.0045,-.074,
.0045,-.049,
-.0045,-.049,
-.0045,-.074,
-.0155,-.074,
-.0155,-.049,
-.034,-.049,
-.034,.049,
0.0*
%
%ADD119MACRO119*%
%AMMACRO72*
4,1,40,.012,-.008,
.012,.008,
.011939,.008695,
.011759,.009368,
.011464,.01,
.011064,.010571,
.010571,.011064,
.01,.011464,
.009368,.011759,
.008695,.011939,
.008,.012,
-.008,.012,
-.008695,.011939,
-.009368,.011759,
-.01,.011464,
-.010571,.011064,
-.011064,.010571,
-.011464,.01,
-.011759,.009368,
-.011939,.008695,
-.012,.008,
-.012,-.008,
-.011939,-.008695,
-.011759,-.009368,
-.011464,-.01,
-.011064,-.010571,
-.010571,-.011064,
-.01,-.011464,
-.009368,-.011759,
-.008695,-.011939,
-.008,-.012,
.008,-.012,
.008695,-.011939,
.009368,-.011759,
.01,-.011464,
.010571,-.011064,
.011064,-.010571,
.011464,-.01,
.011759,-.009368,
.011939,-.008695,
.012,-.008,
0.0*
%
%ADD72MACRO72*%
%AMMACRO29*
4,1,40,-.007,-.011,
.007,-.011,
.007695,-.010939,
.008368,-.010759,
.009,-.010464,
.009571,-.010064,
.010064,-.009571,
.010464,-.009,
.010759,-.008368,
.010939,-.007695,
.011,-.007,
.011,.007,
.010939,.007695,
.010759,.008368,
.010464,.009,
.010064,.009571,
.009571,.010064,
.009,.010464,
.008368,.010759,
.007695,.010939,
.007,.011,
-.007,.011,
-.007695,.010939,
-.008368,.010759,
-.009,.010464,
-.009571,.010064,
-.010064,.009571,
-.010464,.009,
-.010759,.008368,
-.010939,.007695,
-.011,.007,
-.011,-.007,
-.010939,-.007695,
-.010759,-.008368,
-.010464,-.009,
-.010064,-.009571,
-.009571,-.010064,
-.009,-.010464,
-.008368,-.010759,
-.007695,-.010939,
-.007,-.011,
0.0*
%
%ADD29MACRO29*%
%ADD20R,.089X.096*%
%AMMACRO16*
4,1,40,-.008,-.012,
.008,-.012,
.008695,-.011939,
.009368,-.011759,
.01,-.011464,
.010571,-.011064,
.011064,-.010571,
.011464,-.01,
.011759,-.009368,
.011939,-.008695,
.012,-.008,
.012,.008,
.011939,.008695,
.011759,.009368,
.011464,.01,
.011064,.010571,
.010571,.011064,
.01,.011464,
.009368,.011759,
.008695,.011939,
.008,.012,
-.008,.012,
-.008695,.011939,
-.009368,.011759,
-.01,.011464,
-.010571,.011064,
-.011064,.010571,
-.011464,.01,
-.011759,.009368,
-.011939,.008695,
-.012,.008,
-.012,-.008,
-.011939,-.008695,
-.011759,-.009368,
-.011464,-.01,
-.011064,-.010571,
-.010571,-.011064,
-.01,-.011464,
-.009368,-.011759,
-.008695,-.011939,
-.008,-.012,
0.0*
%
%ADD16MACRO16*%
%AMMACRO35*
4,1,40,-.011,.007,
-.011,-.007,
-.010939,-.007695,
-.010759,-.008368,
-.010464,-.009,
-.010064,-.009571,
-.009571,-.010064,
-.009,-.010464,
-.008368,-.010759,
-.007695,-.010939,
-.007,-.011,
.007,-.011,
.007695,-.010939,
.008368,-.010759,
.009,-.010464,
.009571,-.010064,
.010064,-.009571,
.010464,-.009,
.010759,-.008368,
.010939,-.007695,
.011,-.007,
.011,.007,
.010939,.007695,
.010759,.008368,
.010464,.009,
.010064,.009571,
.009571,.010064,
.009,.010464,
.008368,.010759,
.007695,.010939,
.007,.011,
-.007,.011,
-.007695,.010939,
-.008368,.010759,
-.009,.010464,
-.009571,.010064,
-.010064,.009571,
-.010464,.009,
-.010759,.008368,
-.010939,.007695,
-.011,.007,
0.0*
%
%ADD35MACRO35*%
%AMMACRO112*
4,1,6,.025,.0135,
.005,-.0065,
.005,-.0135,
-.005,-.0135,
-.005,-.0065,
-.025,.0135,
.025,.0135,
0.0*
%
%ADD112MACRO112*%
%AMMACRO40*
4,1,40,.013,.017,
-.013,.017,
-.013695,.016939,
-.014368,.016759,
-.015,.016464,
-.015571,.016064,
-.016064,.015571,
-.016464,.015,
-.016759,.014368,
-.016939,.013695,
-.017,.013,
-.017,-.013,
-.016939,-.013695,
-.016759,-.014368,
-.016464,-.015,
-.016064,-.015571,
-.015571,-.016064,
-.015,-.016464,
-.014368,-.016759,
-.013695,-.016939,
-.013,-.017,
.013,-.017,
.013695,-.016939,
.014368,-.016759,
.015,-.016464,
.015571,-.016064,
.016064,-.015571,
.016464,-.015,
.016759,-.014368,
.016939,-.013695,
.017,-.013,
.017,.013,
.016939,.013695,
.016759,.014368,
.016464,.015,
.016064,.015571,
.015571,.016064,
.015,.016464,
.014368,.016759,
.013695,.016939,
.013,.017,
0.0*
%
%ADD40MACRO40*%
%AMMACRO28*
4,1,40,.017,-.013,
.017,.013,
.016939,.013695,
.016759,.014368,
.016464,.015,
.016064,.015571,
.015571,.016064,
.015,.016464,
.014368,.016759,
.013695,.016939,
.013,.017,
-.013,.017,
-.013695,.016939,
-.014368,.016759,
-.015,.016464,
-.015571,.016064,
-.016064,.015571,
-.016464,.015,
-.016759,.014368,
-.016939,.013695,
-.017,.013,
-.017,-.013,
-.016939,-.013695,
-.016759,-.014368,
-.016464,-.015,
-.016064,-.015571,
-.015571,-.016064,
-.015,-.016464,
-.014368,-.016759,
-.013695,-.016939,
-.013,-.017,
.013,-.017,
.013695,-.016939,
.014368,-.016759,
.015,-.016464,
.015571,-.016064,
.016064,-.015571,
.016464,-.015,
.016759,-.014368,
.016939,-.013695,
.017,-.013,
0.0*
%
%ADD28MACRO28*%
%AMMACRO111*
4,1,20,-.0655,.1095,
-.051,.1095,
-.051,.12,
-.0375,.12,
-.0375,.1095,
.0375,.1095,
.0375,.12,
.051,.12,
.051,.1095,
.0655,.1095,
.0655,-.1095,
.051,-.1095,
.051,-.12,
.0375,-.12,
.0375,-.1095,
-.0375,-.1095,
-.0375,-.12,
-.051,-.12,
-.051,-.1095,
-.0655,-.1095,
-.0655,.1095,
0.0*
%
%ADD111MACRO111*%
%AMMACRO138*
4,1,6,-.005,-.0135,
-.005,-.0065,
-.025,.0135,
.025,.0135,
.005,-.0065,
.005,-.0135,
-.005,-.0135,
0.0*
%
%ADD138MACRO138*%
%AMMACRO73*
4,1,40,.012,-.008,
.012,.008,
.011939,.008695,
.011759,.009368,
.011464,.01,
.011064,.010571,
.010571,.011064,
.01,.011464,
.009368,.011759,
.008695,.011939,
.008,.012,
-.008,.012,
-.008695,.011939,
-.009368,.011759,
-.01,.011464,
-.010571,.011064,
-.011064,.010571,
-.011464,.01,
-.011759,.009368,
-.011939,.008695,
-.012,.008,
-.012,-.008,
-.011939,-.008695,
-.011759,-.009368,
-.011464,-.01,
-.011064,-.010571,
-.010571,-.011064,
-.01,-.011464,
-.009368,-.011759,
-.008695,-.011939,
-.008,-.012,
.008,-.012,
.008695,-.011939,
.009368,-.011759,
.01,-.011464,
.010571,-.011064,
.011064,-.010571,
.011464,-.01,
.011759,-.009368,
.011939,-.008695,
.012,-.008,
0.0*
%
%ADD73MACRO73*%
%AMMACRO63*
4,1,15,-.0275,-.115,
-.0275,.115,
.0275,.115,
.0275,.06339,
.02431,.059697,
.021809,.055506,
.020074,.050945,
.019157,.046151,
.019087,.041272,
.019865,.036454,
.021468,.031844,
.023847,.027583,
.02693,.0238,
.0275,.02323,
.0275,-.115,
-.0275,-.115,
0.0*
%
%ADD63MACRO63*%
%AMMACRO21*
4,1,40,-.007,-.011,
.007,-.011,
.007695,-.010939,
.008368,-.010759,
.009,-.010464,
.009571,-.010064,
.010064,-.009571,
.010464,-.009,
.010759,-.008368,
.010939,-.007695,
.011,-.007,
.011,.007,
.010939,.007695,
.010759,.008368,
.010464,.009,
.010064,.009571,
.009571,.010064,
.009,.010464,
.008368,.010759,
.007695,.010939,
.007,.011,
-.007,.011,
-.007695,.010939,
-.008368,.010759,
-.009,.010464,
-.009571,.010064,
-.010064,.009571,
-.010464,.009,
-.010759,.008368,
-.010939,.007695,
-.011,.007,
-.011,-.007,
-.010939,-.007695,
-.010759,-.008368,
-.010464,-.009,
-.010064,-.009571,
-.009571,-.010064,
-.009,-.010464,
-.008368,-.010759,
-.007695,-.010939,
-.007,-.011,
0.0*
%
%ADD21MACRO21*%
%AMMACRO17*
4,1,40,-.008,-.012,
.008,-.012,
.008695,-.011939,
.009368,-.011759,
.01,-.011464,
.010571,-.011064,
.011064,-.010571,
.011464,-.01,
.011759,-.009368,
.011939,-.008695,
.012,-.008,
.012,.008,
.011939,.008695,
.011759,.009368,
.011464,.01,
.011064,.010571,
.010571,.011064,
.01,.011464,
.009368,.011759,
.008695,.011939,
.008,.012,
-.008,.012,
-.008695,.011939,
-.009368,.011759,
-.01,.011464,
-.010571,.011064,
-.011064,.010571,
-.011464,.01,
-.011759,.009368,
-.011939,.008695,
-.012,.008,
-.012,-.008,
-.011939,-.008695,
-.011759,-.009368,
-.011464,-.01,
-.011064,-.010571,
-.010571,-.011064,
-.01,-.011464,
-.009368,-.011759,
-.008695,-.011939,
-.008,-.012,
0.0*
%
%ADD17MACRO17*%
%AMMACRO36*
4,1,40,-.011,.007,
-.011,-.007,
-.010939,-.007695,
-.010759,-.008368,
-.010464,-.009,
-.010064,-.009571,
-.009571,-.010064,
-.009,-.010464,
-.008368,-.010759,
-.007695,-.010939,
-.007,-.011,
.007,-.011,
.007695,-.010939,
.008368,-.010759,
.009,-.010464,
.009571,-.010064,
.010064,-.009571,
.010464,-.009,
.010759,-.008368,
.010939,-.007695,
.011,-.007,
.011,.007,
.010939,.007695,
.010759,.008368,
.010464,.009,
.010064,.009571,
.009571,.010064,
.009,.010464,
.008368,.010759,
.007695,.010939,
.007,.011,
-.007,.011,
-.007695,.010939,
-.008368,.010759,
-.009,.010464,
-.009571,.010064,
-.010064,.009571,
-.010464,.009,
-.010759,.008368,
-.010939,.007695,
-.011,.007,
0.0*
%
%ADD36MACRO36*%
%ADD165C,.012*%
%ADD166C,.015*%
%ADD167C,.004*%
%ADD168C,.006*%
%ADD169C,.007*%
%ADD170C,.008*%
%ADD171C,.00413*%
%ADD172C,.00474*%
%ADD173C,.00538*%
%ADD174C,.00475*%
%ADD179C,.04404*%
%ADD178C,.07804*%
%ADD177C,.13104*%
%ADD175R,.008X.008*%
%ADD176R,.29602X.29604*%
G75*
%LPD*%
G75*
G36*
G01X7874Y105406D02*
G02X3004Y110276I0J4870D01*
G01Y836614D01*
G02X3937Y837547I933J0D01*
G01X94118D01*
Y832551D01*
X8000D01*
Y110402D01*
X25400D01*
Y105406D01*
X7874D01*
G37*
G36*
G01X41800Y159800D02*
X33672Y167928D01*
Y168112D01*
X33488D01*
X28000Y173600D01*
X22865D01*
G03X22800Y173602I-82J-1599D01*
G01X21200D01*
G03X21135Y173600I17J-1601D01*
G01X20400D01*
X20300Y173500D01*
X17700D01*
X16400Y174800D01*
Y191500D01*
X18400Y193500D01*
X21035D01*
G03X21100Y193498I82J1599D01*
G01X22700D01*
G03X22765Y193500I-17J1601D01*
G01X23800D01*
X24800Y194500D01*
X38800D01*
X42939Y190361D01*
X42805Y190219D01*
G03X41943Y188774I2753J-2622D01*
G02X41183I-380J123D01*
G03Y186422I-3616J-1176D01*
G02X41943I380J-123D01*
G03X46049Y183828I3616J1176D01*
G02X46500Y183431I51J-397D01*
G01Y179806D01*
G03X45979Y178774I3094J-2210D01*
G02X45219I-380J123D01*
G03Y176422I-3616J-1176D01*
G02X45979I380J-123D01*
G03X46465Y175440I3615J1178D01*
G01X46500Y175389D01*
Y175100D01*
X48000Y173600D01*
X75400D01*
X76600Y174800D01*
Y175299D01*
X76639Y175352D01*
G03X77187Y176422I-3068J2246D01*
G02X77947I380J-123D01*
G03Y178774I3616J1176D01*
G02X77187I-380J123D01*
G03X76600Y179896I-3615J-1177D01*
G01Y181700D01*
X78935Y184035D01*
X78975Y184051D01*
G03X81169Y186269I-1368J3547D01*
G01X81361Y186461D01*
G02X82021Y186314I283J-282D01*
G03X87759Y190727I3578J1284D01*
G01X87672Y190787D01*
Y191092D01*
X88118D01*
X89427Y192400D01*
X98849D01*
G03X100100Y191798I1251J999D01*
G01X101700D01*
G03X101780Y191801I-20J1601D01*
G02X102200Y191401I20J-400D01*
G01Y180600D01*
X101801Y180201D01*
X101717D01*
G03X101700Y180202I-102J-1596D01*
G01X100100D01*
G03X100035Y180200I17J-1601D01*
G01X98300D01*
X96900Y178800D01*
Y175700D01*
X81000Y159800D01*
X41800D01*
G37*
G36*
G01X45539Y417961D02*
X45580Y418079D01*
G03X45202Y420200I-2080J723D01*
G01Y421705D01*
X45000Y421906D01*
Y432500D01*
X37500Y440000D01*
X24500D01*
X24000Y440500D01*
Y449500D01*
X25500Y451000D01*
X47500D01*
X51500Y447000D01*
Y443452D01*
X51348D01*
Y435548D01*
X51500D01*
Y431736D01*
X51098D01*
Y429772D01*
Y422228D01*
X57102D01*
Y422242D01*
X58498Y420845D01*
Y419163D01*
G03X58196Y418709I2004J-1660D01*
G01X58182Y418682D01*
X57000Y417500D01*
X46000D01*
X45539Y417961D01*
G37*
G36*
G01X38100Y427500D02*
X37684Y427916D01*
X37670Y427944D01*
G03X36711Y428903I-1961J-1002D01*
G01X36683Y428917D01*
X33700Y431900D01*
X27900D01*
X27100Y432700D01*
X19189D01*
X18502Y433386D01*
Y436908D01*
X18995Y437400D01*
X37500D01*
X43398Y431502D01*
Y429300D01*
X40100D01*
Y428600D01*
X43398D01*
Y427802D01*
X38898D01*
Y427500D01*
X38100D01*
G37*
G36*
G01X70000Y423500D02*
X69580Y423080D01*
X69484Y423091D01*
G03X69300Y423102I-187J-1591D01*
G01X67700D01*
G03X67170Y423011I2J-1602D01*
G01X67138Y423000D01*
X65762D01*
X65730Y423011D01*
G03X65200Y423102I-532J-1511D01*
G01X64555D01*
X59955Y427702D01*
X57102D01*
Y427802D01*
X52702D01*
Y445301D01*
X52900Y445500D01*
X53298D01*
Y445198D01*
X61702D01*
Y445500D01*
X68000D01*
X68500Y445000D01*
Y443334D01*
G03Y443154I2200J-90D01*
G01Y428000D01*
X69848Y426651D01*
Y426548D01*
X69952D01*
X70000Y426500D01*
Y423500D01*
G37*
G36*
G01X63360Y447060D02*
X61702D01*
Y447802D01*
X54400D01*
Y453900D01*
X62131Y461631D01*
X66269D01*
X66850Y461050D01*
Y450550D01*
X63360Y447060D01*
G37*
G36*
G01X57086Y728452D02*
X47852D01*
Y741348D01*
X60748D01*
Y728452D01*
X57086D01*
G37*
G36*
G01X78600Y290800D02*
X64400D01*
Y305000D01*
X78600D01*
Y290800D01*
G37*
G36*
G01X69903Y443941D02*
X70292Y444330D01*
X72485D01*
X75551Y441264D01*
Y435912D01*
X69903D01*
Y443941D01*
G37*
G36*
G01X97200Y762800D02*
X96000Y764000D01*
Y785000D01*
X96500Y785500D01*
X99648D01*
Y785414D01*
X113086D01*
X114500Y784000D01*
Y764500D01*
X112800Y762800D01*
X97200D01*
G37*
G36*
G01X105700Y786800D02*
X105500Y787000D01*
X98000D01*
X96500Y788500D01*
Y807500D01*
X99000Y810000D01*
X99100D01*
X99446Y810346D01*
X99950D01*
Y810850D01*
X100400Y811300D01*
Y815200D01*
X100850Y815650D01*
X122600D01*
X127000Y811250D01*
Y790500D01*
X123300Y786800D01*
X105700D01*
G37*
G36*
G01X419083Y110146D02*
X446708Y82520D01*
Y61531D01*
X446866Y61373D01*
Y61370D01*
X446868Y61369D01*
Y60939D01*
X467531Y40276D01*
Y17559D01*
X479639Y5451D01*
G02X486888Y-7874I-8627J-13328D01*
G01Y-11685D01*
X725272D01*
X727626Y-14040D01*
X752077D01*
X754431Y-11685D01*
X1025971D01*
G03X1029473I1751J2560D01*
G01X1052743D01*
G03X1056245I1751J2560D01*
G01X1298102D01*
Y-3937D01*
G02X1302095Y4972I11937J-1D01*
G01X1303706D01*
G03X1305308Y6574I0J1602D01*
G01Y7022D01*
G02X1306181Y7359I4732J-10959D01*
G01X1309262D01*
X1313958Y12055D01*
Y110276D01*
X1389904D01*
X1392000Y112372D01*
Y832551D01*
X1368504D01*
G02X1355386Y845669I0J13118D01*
G01Y866048D01*
G02X1350496Y869347I2881J9543D01*
G01Y879851D01*
X1352203D01*
X1353298Y878756D01*
Y875420D01*
G03X1358267Y870618I4970J171D01*
G01X1360382D01*
Y845669D01*
G03X1368504Y837547I8122J0D01*
G01X1396063D01*
G02X1396996Y836614I0J-933D01*
G01Y82439D01*
X1396918Y82361D01*
X1396996Y82173D01*
Y77025D01*
G02X1396600Y76626I-400J1D01*
G03X1391681Y71654I54J-4972D01*
G01Y40157D01*
G03X1396600Y35185I4973J0D01*
G02X1396996Y34786I-4J-400D01*
G01Y3937D01*
G02X1396063Y3004I-933J0D01*
G01X1310039D01*
G03X1303098Y-3937I0J-6941D01*
G01Y-15748D01*
G02X1302165Y-16681I-933J0D01*
G01X486762D01*
G02X481892Y-11811I0J4870D01*
G01Y-7874D01*
G03X471014Y3004I-10878J0D01*
G01X212402D01*
G02X207532Y7874I0J4870D01*
G01Y94528D01*
G03X196654Y105406I-10878J0D01*
G01X97766D01*
Y110402D01*
X196654D01*
G02X199493Y110146I0J-15874D01*
G01X209524D01*
X215840Y103830D01*
Y67380D01*
X225390Y57830D01*
X258380D01*
X263240Y62690D01*
Y100323D01*
G03X263502Y101200I-1340J878D01*
G01Y102600D01*
G03X263480Y102860I-1602J-5D01*
G02X264020Y103297I395J64D01*
G03X266413Y106867I797J2053D01*
G02X266420Y107426I290J276D01*
G01X269140Y110146D01*
X419083D01*
G37*
G36*
G01X182020Y129690D02*
X112510D01*
X111950Y130250D01*
Y146450D01*
X116790Y151290D01*
X125730D01*
X129810Y147210D01*
X164100D01*
X168180Y151290D01*
X179350D01*
X182340Y148300D01*
Y130010D01*
X182020Y129690D01*
G37*
G36*
G01X113000Y193702D02*
G03X113311Y197362I-1681J1986D01*
G02X113363Y197929I306J258D01*
G03X113304Y201382I-1396J1703D01*
G02X113256Y201647I121J159D01*
G03X113502Y202500I-1356J853D01*
G01Y204100D01*
G03X113000Y205264I-1602J-1D01*
G01Y205976D01*
X113047Y206031D01*
G03X113000Y209423I-1997J1669D01*
G01Y218100D01*
X115400Y220500D01*
X120400D01*
X122500Y218400D01*
Y172000D01*
X122000Y171500D01*
X114500D01*
X113000Y173000D01*
Y193702D01*
G37*
G36*
G01X130358Y148412D02*
X125180Y153590D01*
Y170110D01*
X124500Y170790D01*
Y218000D01*
X129000Y222500D01*
X149000D01*
X150500Y221000D01*
Y200000D01*
X139500Y189000D01*
Y177565D01*
X139452Y177518D01*
Y150160D01*
X137704Y148412D01*
X130358D01*
G37*
G36*
G01X114934Y272786D02*
G03X112363Y274956I-2201J0D01*
G01X112261Y274939D01*
X111735Y275465D01*
Y276312D01*
X111741Y276336D01*
G03Y277364I-2141J514D01*
G01X111735Y277388D01*
Y278305D01*
X111200Y278840D01*
Y288000D01*
X118000Y294800D01*
X123600D01*
X123698Y294898D01*
X123702D01*
Y294901D01*
X123800Y295000D01*
Y300100D01*
X123900Y300200D01*
X126350D01*
X126450Y300100D01*
Y292550D01*
X125200Y291300D01*
X119500D01*
X118500Y290300D01*
Y282490D01*
G03Y282310I2200J-90D01*
G01Y281160D01*
X119530Y280130D01*
X121930D01*
X122000Y280060D01*
Y267730D01*
X120600Y266330D01*
X117240D01*
X115975Y267595D01*
Y271225D01*
X114934Y272267D01*
Y272786D01*
G37*
G36*
G01X124500Y272800D02*
X123202Y274099D01*
Y280558D01*
X123200Y280559D01*
Y282400D01*
X123800Y283000D01*
Y289600D01*
X124000Y289800D01*
X126300D01*
X126498Y289601D01*
Y284298D01*
X126500D01*
Y283000D01*
X127050Y282450D01*
X132350D01*
X132898Y281901D01*
Y276802D01*
X132900Y276801D01*
Y273650D01*
X132050Y272800D01*
X124500D01*
G37*
G36*
G01X145400Y276500D02*
X134900D01*
X134100Y277300D01*
Y282700D01*
X132100Y284700D01*
X128000D01*
X127700Y285000D01*
Y289700D01*
X128200Y290200D01*
X130900D01*
X132700Y292000D01*
Y297200D01*
X133500Y298000D01*
X143800D01*
X145900Y295900D01*
Y277000D01*
X145400Y276500D01*
G37*
G36*
G01X132019Y651720D02*
X131038Y650739D01*
X130948Y650745D01*
G03X130851Y650748I-98J-1599D01*
G01X129251D01*
G03X128972Y650723I3J-1602D01*
G01X128955Y650720D01*
X120769D01*
X118019Y653470D01*
Y654470D01*
X121019Y657470D01*
X131519D01*
X132019Y656970D01*
Y651720D01*
G37*
G36*
G01X100900Y818500D02*
X100252Y819148D01*
Y819952D01*
X100100D01*
Y832500D01*
X108500Y840900D01*
Y866500D01*
X113000Y871000D01*
Y871459D01*
X113085Y871518D01*
G03X115206Y875590I-2849J4072D01*
G01Y881800D01*
X132000D01*
Y842600D01*
X127600Y838200D01*
Y825500D01*
X120600Y818500D01*
X100900D01*
G37*
G36*
G01X172000Y198000D02*
X159500D01*
X158000Y199500D01*
Y212000D01*
X159500Y213500D01*
X172500D01*
X173500Y212500D01*
Y199500D01*
X172000Y198000D01*
G37*
G36*
G01X150100Y235600D02*
X148650Y237050D01*
Y261050D01*
X149100Y261500D01*
X159500D01*
X162100Y258900D01*
Y246337D01*
G03X161353Y245847I809J-2048D01*
G01X160698Y245192D01*
Y243898D01*
X159500Y242700D01*
Y236600D01*
X158500Y235600D01*
X150100D01*
G37*
G36*
G01X135000Y225000D02*
X133300Y226700D01*
Y260800D01*
X134000Y261500D01*
X135500D01*
X136700Y262700D01*
Y267300D01*
X139200Y269800D01*
X145600D01*
X146500Y268900D01*
Y262300D01*
X147448Y261352D01*
Y236552D01*
X147500Y236501D01*
Y234000D01*
X150000Y231500D01*
Y225500D01*
X149500Y225000D01*
X135000D01*
G37*
G36*
G01X148800Y263000D02*
X148200Y263600D01*
Y270000D01*
X148600Y270400D01*
X152960D01*
Y269922D01*
X161100D01*
Y263500D01*
X160600Y263000D01*
X148800D01*
G37*
G36*
G01X149300Y275000D02*
X148400Y275900D01*
Y301500D01*
X150900Y304000D01*
X163907D01*
X163943Y303846D01*
G03X165200Y302335I2143J505D01*
G01Y275800D01*
X164400Y275000D01*
X149300D01*
G37*
G36*
G01X150304Y306500D02*
Y307299D01*
X150302Y307301D01*
Y309814D01*
X149500Y310616D01*
Y314367D01*
X155266Y320132D01*
Y320400D01*
X162200D01*
X166300Y316300D01*
Y307500D01*
X165300Y306500D01*
X150304D01*
G37*
G36*
G01X158500Y505000D02*
X141500D01*
X141000Y505500D01*
Y522000D01*
X141500Y522500D01*
X158500D01*
X159000Y522000D01*
Y505500D01*
X158500Y505000D01*
G37*
G36*
G01X160551Y576034D02*
G03X160813Y576056I-3J1602D01*
G01X160914Y576073D01*
X161051Y575936D01*
Y574000D01*
X160551Y573500D01*
X151798D01*
X151796Y573502D01*
X132498D01*
X132000Y574000D01*
Y575846D01*
X132273Y576119D01*
X144477D01*
X144508Y576109D01*
G03X145009Y576028I503J1521D01*
G01X146609D01*
G03X147110Y576109I-2J1602D01*
G01X147141Y576119D01*
X158437D01*
X158466Y576110D01*
G03X158951Y576034I488J1526D01*
G01X160551D01*
G37*
G36*
G01X150100Y822700D02*
X132800D01*
X132000Y823500D01*
Y836500D01*
X136500Y841000D01*
Y879000D01*
X134000Y881500D01*
Y882100D01*
X150900D01*
X151000Y882000D01*
Y823600D01*
X150100Y822700D01*
G37*
G36*
G01X221502Y165000D02*
Y165052D01*
X221448D01*
X221000Y165500D01*
Y180500D01*
X221500Y181000D01*
X231500D01*
X232000Y180500D01*
Y166500D01*
X230552Y165052D01*
X225098D01*
Y165000D01*
X221502D01*
G37*
G36*
G01X220920Y182500D02*
Y183226D01*
X219274D01*
X217500Y185000D01*
Y195500D01*
X219000Y197000D01*
X231000D01*
X232000Y196000D01*
Y183500D01*
X231000Y182500D01*
X220920D01*
G37*
G36*
G01X254500Y134500D02*
X253000Y136000D01*
Y140355D01*
X253259D01*
Y163645D01*
X253000D01*
Y164500D01*
X251500Y166000D01*
Y167000D01*
X253000Y168500D01*
Y191500D01*
X261500Y200000D01*
X343500D01*
X346500Y197000D01*
Y186500D01*
X345500Y185500D01*
X275000D01*
X265500Y176000D01*
Y135500D01*
X264500Y134500D01*
X254500D01*
G37*
G36*
G01X246668Y151832D02*
X245500Y153000D01*
X237500D01*
X234500Y156000D01*
Y158480D01*
X235094Y159073D01*
G03X234500Y162610I-1557J1557D01*
G01Y190000D01*
X236000Y191500D01*
X249000D01*
X251000Y189500D01*
Y169500D01*
X250000Y168500D01*
Y164000D01*
X251748Y162252D01*
Y151832D01*
X246668D01*
G37*
G36*
G01X259500Y602200D02*
X259100Y602600D01*
Y624900D01*
X256000Y628000D01*
Y630163D01*
X256202D01*
Y639672D01*
X251328D01*
X249000Y642000D01*
Y647000D01*
X250500Y648500D01*
X264000D01*
X264500Y648000D01*
Y643500D01*
X263000Y642000D01*
Y641636D01*
X262398D01*
Y639672D01*
Y630163D01*
X263000D01*
Y627000D01*
X266000Y624000D01*
X279000D01*
X279500Y623500D01*
Y603500D01*
X278200Y602200D01*
X259500D01*
G37*
G36*
G01X247500Y601500D02*
X246602Y602398D01*
Y610102D01*
X246500D01*
Y630200D01*
X247100Y630800D01*
X249100D01*
X251200Y632900D01*
Y634098D01*
X254698D01*
Y629798D01*
X254798D01*
Y627502D01*
X255000Y627301D01*
Y626400D01*
X256400Y625000D01*
Y602800D01*
X255100Y601500D01*
X247500D01*
G37*
G36*
G01X244000Y597500D02*
X236500D01*
X236000Y598000D01*
Y610000D01*
X237000Y611000D01*
X243439D01*
X243963Y610476D01*
Y601487D01*
X244500Y600950D01*
Y598000D01*
X244000Y597500D01*
G37*
G36*
G01X266200Y625800D02*
X264202Y627798D01*
Y634098D01*
X268402D01*
Y634460D01*
X270140D01*
X272800Y631800D01*
X284100D01*
X284400Y631500D01*
Y626600D01*
X283600Y625800D01*
X266200D01*
G37*
G36*
G01X298500Y157500D02*
X297000Y159000D01*
Y181500D01*
X298000Y182500D01*
X348500D01*
X348698Y182301D01*
Y159798D01*
X349500D01*
Y158000D01*
X349000Y157500D01*
X298500D01*
G37*
G36*
G01X272544Y151732D02*
Y151832D01*
X267668D01*
X267500Y152000D01*
Y174000D01*
X269500Y176000D01*
X286500D01*
X287500Y175000D01*
Y153500D01*
X287000Y153000D01*
X275000D01*
X273732Y151732D01*
X272544D01*
G37*
G36*
G01X293800Y624200D02*
X287100D01*
X286600Y624700D01*
Y634800D01*
X287600Y635800D01*
X293800D01*
X294300Y635300D01*
Y624700D01*
X293800Y624200D01*
G37*
G36*
G01X775536Y204964D02*
X765400Y215100D01*
X761100D01*
X759000Y217200D01*
Y312500D01*
X768500Y322000D01*
X834500D01*
X859500Y297000D01*
X898000D01*
X918000Y317000D01*
Y378500D01*
X908000Y388500D01*
X727000D01*
X698000Y417500D01*
X621700D01*
G02X621300Y417915I0J400D01*
G03X618241Y420028I-2200J85D01*
G02X617688Y420350I-156J368D01*
G03X614324Y418238I-2188J-250D01*
G02X614111Y417500I-213J-338D01*
G01X568487D01*
G03X565813I-1337J-1750D01*
G01X369000D01*
X356500Y430000D01*
Y492500D01*
X328500Y520500D01*
Y554000D01*
X311000Y571500D01*
Y664000D01*
X332500Y685500D01*
X390000D01*
X444000Y739500D01*
X752500D01*
X793500Y698500D01*
X863500D01*
X879500Y682500D01*
Y622500D01*
X919500Y582500D01*
X1085000D01*
X1113000Y610500D01*
X1290500D01*
X1301000Y600000D01*
Y461500D01*
X1277000Y437500D01*
X1193000D01*
X1021500Y266000D01*
X905000D01*
X904500Y265500D01*
X869000D01*
X863000Y259500D01*
Y217500D01*
X863500Y217000D01*
X851464Y204964D01*
X775536D01*
G37*
G36*
G01X352039Y157085D02*
X351000Y158124D01*
Y159798D01*
X351302D01*
Y183302D01*
X352000Y184000D01*
X363500D01*
X364500Y183000D01*
Y162000D01*
X364472Y161972D01*
Y159201D01*
X362356Y157085D01*
X352039D01*
G37*
G36*
G01X517760Y832696D02*
Y832558D01*
G02X517323Y832551I-429J13111D01*
G01X502741D01*
G03X498873I-1934J-1052D01*
G01X491681D01*
X489655Y834576D01*
X477662D01*
X475636Y832551D01*
X455118D01*
G02X442000Y845669I0J13118D01*
G01Y866048D01*
G02X437110Y869347I2881J9543D01*
G01Y874591D01*
X440008D01*
X440045Y874437D01*
G03X444881Y870618I4837J1154D01*
G01X446996D01*
Y845669D01*
G03X455118Y837547I8122J0D01*
G01X517323D01*
G03X525445Y845669I0J8122D01*
G01Y870618D01*
X527560D01*
G03X530568Y871632I-1J4973D01*
G02X531210Y871313I242J-318D01*
G01Y866315D01*
G02X530441Y866048I-3651J9276D01*
G01Y845669D01*
G02X528173Y838297I-13118J1D01*
G03X525834Y837640I-673J-2097D01*
G01X522704D01*
X517760Y832696D01*
G37*
G36*
G01X520052Y186968D02*
Y196630D01*
X525052Y201630D01*
X555613D01*
X556452Y200791D01*
Y187630D01*
X555790Y186968D01*
X527416D01*
G03X525014I-1201J-2968D01*
G01X520052D01*
G37*
G36*
G01X507577Y244440D02*
X506802Y245214D01*
Y272965D01*
X506818Y272982D01*
Y281743D01*
X503757Y284804D01*
Y292663D01*
X504279Y293185D01*
X504383Y293166D01*
G03X504677Y293138I298J1574D01*
G01X506277D01*
G03X506692Y293193I-1J1602D01*
G01X506717Y293200D01*
X507100D01*
X508006Y294106D01*
Y296694D01*
X508819Y297508D01*
X512830D01*
X514638Y295700D01*
Y289522D01*
X514649Y287551D01*
X516550Y285650D01*
X521543D01*
X522077Y285116D01*
Y282962D01*
X522074D01*
Y278924D01*
X520667Y277516D01*
X517928D01*
X516952Y276540D01*
Y270937D01*
X516881Y270866D01*
Y259676D01*
X516781Y259576D01*
Y245476D01*
X515745Y244440D01*
X507577D01*
G37*
G36*
G01X568243Y242425D02*
X564270Y246398D01*
X559676D01*
X557063Y249011D01*
Y287696D01*
X557752Y288385D01*
Y295849D01*
X557063Y296538D01*
Y303952D01*
X558932Y305821D01*
X568598D01*
X569063Y305356D01*
Y267187D01*
X572430Y263820D01*
Y242799D01*
X572056Y242425D01*
X569590D01*
G03X569410I-90J-2200D01*
G01X568243D01*
G37*
G36*
G01X550993Y302608D02*
X546502Y307099D01*
Y318166D01*
X548168Y319832D01*
X549443Y321108D01*
X561263D01*
X562563Y319808D01*
Y308412D01*
X561531Y307380D01*
X558572D01*
X553800Y302608D01*
X550993D01*
G37*
G36*
G01X562679Y321700D02*
X562659Y321704D01*
G03X562387Y321747I-542J-2545D01*
G01X562316Y321754D01*
X561761Y322310D01*
X555156D01*
X554877Y322588D01*
Y329017D01*
X555660Y329800D01*
X561101D01*
X561702Y329198D01*
X573098D01*
Y328598D01*
X581400D01*
Y324900D01*
X578200Y321700D01*
X562679D01*
G37*
G36*
G01X562559Y348341D02*
X562232Y348668D01*
Y348978D01*
X562332D01*
Y353478D01*
X566632D01*
Y353600D01*
X568900D01*
X571203Y351297D01*
X591945D01*
X592274Y350968D01*
Y344673D01*
X590730Y343129D01*
Y342282D01*
Y336878D01*
Y336580D01*
X591400Y335910D01*
Y330900D01*
X590900Y330400D01*
X581502D01*
Y331202D01*
X573098D01*
Y330400D01*
X562200D01*
X560700Y331900D01*
Y339900D01*
X561000Y340200D01*
X563500D01*
X564100Y340800D01*
Y346800D01*
X563841Y347059D01*
X563826Y347097D01*
G03X562597Y348326I-2045J-816D01*
G01X562559Y348341D01*
G37*
G36*
G01X552498Y350002D02*
X552000Y350500D01*
Y360500D01*
X553000Y361500D01*
X554794D01*
Y361178D01*
X564303D01*
X566268D01*
Y361500D01*
X570000D01*
X571500Y363000D01*
X591000D01*
X592000Y362000D01*
Y358836D01*
X592269Y358567D01*
Y354023D01*
X592225Y353979D01*
X591521D01*
X591500Y354000D01*
X571000D01*
X570500Y354500D01*
X569699D01*
X569398Y354802D01*
X566268D01*
Y354982D01*
X564303D01*
X556759D01*
Y350665D01*
X556105Y350012D01*
X556104D01*
X556094Y350002D01*
X552498D01*
G37*
G36*
G01X597464Y258010D02*
X600063Y260608D01*
Y267108D01*
X598963Y268208D01*
Y302744D01*
X601137Y304918D01*
X685753D01*
X686236Y304436D01*
Y283144D01*
X685100Y282008D01*
X620463D01*
X609563Y271108D01*
Y252503D01*
X609004D01*
Y229213D01*
X609563D01*
Y225108D01*
X608063Y223608D01*
X605064D01*
Y223910D01*
X601662D01*
Y223608D01*
X599063D01*
X597063Y225608D01*
Y240909D01*
X597264Y241110D01*
Y255533D01*
G03X597464Y256308I-1402J775D01*
G01Y258010D01*
G37*
G36*
G01X591162Y240690D02*
X589319Y242532D01*
X588140D01*
X587980Y242691D01*
X586341D01*
G03X582703I-1819J-1861D01*
G01X575161D01*
X573915Y243937D01*
Y264756D01*
X570563Y268108D01*
Y315589D01*
X571682Y316708D01*
X592868D01*
X596063Y313513D01*
Y268140D01*
X597381Y266822D01*
Y260485D01*
X596063Y259167D01*
Y253010D01*
X595012D01*
Y240690D01*
X591162D01*
G37*
G36*
G01X597510Y327020D02*
X593220Y331310D01*
Y336878D01*
X593332D01*
Y342502D01*
X593860Y343030D01*
X599510D01*
X601495Y341045D01*
Y332675D01*
X602460Y331710D01*
X609620D01*
X610580Y332670D01*
Y337020D01*
X610830Y337270D01*
X615380D01*
X615640Y337010D01*
Y330440D01*
X612220Y327020D01*
X597510D01*
G37*
G36*
G01X615808Y240608D02*
Y240690D01*
X611063D01*
Y253944D01*
G03Y257272I-2000J1664D01*
G01Y263608D01*
X613063Y265608D01*
X631563D01*
X632563Y264608D01*
Y242108D01*
X631063Y240608D01*
X616808D01*
G03X616628I-90J-2200D01*
G01X615808D01*
G37*
G36*
G01X620500Y344000D02*
X624408Y347908D01*
X626058D01*
Y347959D01*
G02X626400Y348100I200J0D01*
G01X626500Y348000D01*
Y344816D01*
X624583D01*
X622560Y342793D01*
Y339421D01*
G03X621824Y338622I740J-1420D01*
G01X621773Y338500D01*
X620298D01*
G03X620102I-98J-2600D01*
G01X614992D01*
G03X614130Y338752I-862J-1350D01*
G01X611530D01*
G03X611046Y338677I0J-1602D01*
G02X610547Y338926I-122J381D01*
G03X610000Y339837I-2457J-856D01*
G01Y341987D01*
X611912Y343898D01*
X618912D01*
X619013Y344000D01*
X620500D01*
G37*
G36*
G01X657063Y217108D02*
X655063Y219108D01*
Y229608D01*
X657063Y231608D01*
X664063D01*
X672563Y240108D01*
X703900D01*
X705192Y241400D01*
X735700D01*
X739200Y237900D01*
Y227800D01*
X735600Y224200D01*
X696400D01*
X689600Y217400D01*
Y217108D01*
X686525D01*
G03X683475I-1525J-2108D01*
G01X672525D01*
G03X669475I-1525J-2108D01*
G01X657063D01*
G37*
G36*
G01X670869Y241414D02*
X663563Y234108D01*
X652563D01*
X651497Y235174D01*
X651482Y235218D01*
G03X650563Y236370I-2082J-718D01*
G01Y277608D01*
X652063Y279108D01*
X690062D01*
Y278506D01*
X700302D01*
X700600Y278208D01*
Y275202D01*
X699898D01*
Y248798D01*
X700600D01*
Y242314D01*
X699700Y241414D01*
X670869D01*
G37*
G36*
G01X712800Y202200D02*
X696900D01*
X695700Y203400D01*
Y219600D01*
X698800Y222700D01*
X711800D01*
X713800Y220700D01*
Y203200D01*
X712800Y202200D01*
G37*
G36*
G01X704800Y244000D02*
X701802Y246998D01*
Y248798D01*
X702502D01*
Y275202D01*
X701802D01*
Y278706D01*
X701800Y278707D01*
Y281286D01*
X702710Y282196D01*
X739437D01*
X740537Y281096D01*
Y246737D01*
X737800Y244000D01*
X704800D01*
G37*
G36*
G01X688963Y280808D02*
X687463Y282308D01*
Y303508D01*
X688263Y304308D01*
X698392D01*
X700292Y302408D01*
Y281400D01*
X700002Y281110D01*
X690062D01*
Y280808D01*
X688963D01*
G37*
G36*
G01X701939Y283124D02*
X701563Y283500D01*
Y300063D01*
X701900Y300400D01*
X738263D01*
X740063Y298600D01*
Y283663D01*
X739798Y283398D01*
X702212D01*
X701939Y283124D01*
G37*
G36*
G01X686000Y340000D02*
X671000Y355000D01*
Y393000D01*
X672000Y394000D01*
X697000D01*
X719500Y371500D01*
X903000D01*
X903500Y371000D01*
Y368000D01*
X902000Y366500D01*
X899500D01*
X889000Y356000D01*
Y345500D01*
X883500Y340000D01*
X686000D01*
G37*
G36*
G01X753237Y203192D02*
X734337D01*
X732837Y204692D01*
Y218692D01*
X733237Y219092D01*
X749148D01*
X753637Y214603D01*
Y203592D01*
X753237Y203192D01*
G37*
G36*
G01X754737Y192292D02*
X745737D01*
X745237Y192792D01*
Y200292D01*
X746237Y201292D01*
X755237D01*
X755737Y200792D01*
Y193292D01*
X754737Y192292D01*
G37*
G36*
G01X845443Y10657D02*
X843930Y9143D01*
Y8500D01*
X842252D01*
Y8702D01*
X834348D01*
Y8500D01*
X830652D01*
Y8702D01*
X829798D01*
X829500Y9000D01*
X821500D01*
X821000Y9500D01*
Y15000D01*
X821403Y15403D01*
X821490Y15400D01*
G03X821552Y15398I83J1599D01*
G01X822952D01*
G03X823482Y15489I-2J1602D01*
G01X823514Y15500D01*
X824990D01*
X825022Y15489D01*
G03X825552Y15398I532J1511D01*
G01X826952D01*
G03X827482Y15489I-2J1602D01*
G01X827514Y15500D01*
X828990D01*
X829022Y15489D01*
G03X829552Y15398I532J1511D01*
G01X830952D01*
G03X831482Y15489I-2J1602D01*
G01X831514Y15500D01*
X832990D01*
X833022Y15489D01*
G03X833552Y15398I532J1511D01*
G01X834952D01*
G03X835482Y15489I-2J1602D01*
G01X835514Y15500D01*
X836990D01*
X837022Y15489D01*
G03X837552Y15398I532J1511D01*
G01X838952D01*
G03X839482Y15489I-2J1602D01*
G01X839514Y15500D01*
X840990D01*
X841022Y15489D01*
G03X841552Y15398I532J1511D01*
G01X842952D01*
G03X843482Y15489I-2J1602D01*
G01X843514Y15500D01*
X844990D01*
X845022Y15489D01*
G03X845552Y15398I532J1511D01*
G01X846952D01*
G03X846979Y15399I-46J1600D01*
G01X847064Y15400D01*
X847377Y15087D01*
Y11701D01*
G02X846981Y11301I-400J0D01*
G03X845443Y10657I18J-2201D01*
G37*
G36*
G01X996748Y820866D02*
Y650669D01*
G02X983748Y637669I-13000J0D01*
G01X926819D01*
G02X913819Y650669I0J13000D01*
G01Y820866D01*
G03X902134Y832551I-11685J0D01*
G01X872441D01*
G02X859323Y845669I0J13118D01*
G01Y866048D01*
G02X854483Y869286I2881J9543D01*
G01X854498Y869302D01*
X854434Y869366D01*
Y879034D01*
X854500Y879100D01*
X856500D01*
X857232Y878368D01*
Y875590D01*
G03X862204Y870618I4973J1D01*
G01X864319D01*
Y845669D01*
G03X872441Y837547I8122J0D01*
G01X902134D01*
G02X918815Y820866I0J-16681D01*
G01Y650669D01*
G03X926819Y642665I8004J0D01*
G01X983748D01*
G03X991752Y650669I0J8004D01*
G01Y820866D01*
G02X1008433Y837547I16681J0D01*
G01X1013386D01*
G03X1021508Y845669I0J8122D01*
G01Y870618D01*
X1023623D01*
G03X1026657Y871652I-1J4972D01*
G02X1027302Y871335I245J-317D01*
G01Y866326D01*
G02X1026504Y866048I-3676J9266D01*
G01Y845669D01*
G02X1013386Y832551I-13118J0D01*
G01X1008433D01*
G03X996748Y820866I0J-11685D01*
G37*
G36*
G01X876262Y92000D02*
X876230Y92011D01*
G03X875700Y92102I-532J-1511D01*
G01X874300D01*
G03X874038Y92080I3J-1602D01*
G01X873937Y92063D01*
X873500Y92500D01*
Y99000D01*
X874500Y100000D01*
X937500D01*
X939000Y98500D01*
Y92500D01*
X938602Y92102D01*
X937300D01*
G03X936770Y92011I2J-1602D01*
G01X936738Y92000D01*
X934762D01*
X934730Y92011D01*
G03X934200Y92102I-532J-1511D01*
G01X932800D01*
G03X932270Y92011I2J-1602D01*
G01X932238Y92000D01*
X930262D01*
X930230Y92011D01*
G03X929700Y92102I-532J-1511D01*
G01X928300D01*
G03X927770Y92011I2J-1602D01*
G01X927738Y92000D01*
X925762D01*
X925730Y92011D01*
G03X925200Y92102I-532J-1511D01*
G01X923800D01*
G03X923270Y92011I2J-1602D01*
G01X923238Y92000D01*
X921262D01*
X921230Y92011D01*
G03X920700Y92102I-532J-1511D01*
G01X919300D01*
G03X918770Y92011I2J-1602D01*
G01X918738Y92000D01*
X916762D01*
X916730Y92011D01*
G03X916200Y92102I-532J-1511D01*
G01X914800D01*
G03X914270Y92011I2J-1602D01*
G01X914238Y92000D01*
X912262D01*
X912230Y92011D01*
G03X911700Y92102I-532J-1511D01*
G01X910300D01*
G03X909770Y92011I2J-1602D01*
G01X909738Y92000D01*
X907762D01*
X907730Y92011D01*
G03X907200Y92102I-532J-1511D01*
G01X905800D01*
G03X905270Y92011I2J-1602D01*
G01X905238Y92000D01*
X903262D01*
X903230Y92011D01*
G03X902700Y92102I-532J-1511D01*
G01X901300D01*
G03X900770Y92011I2J-1602D01*
G01X900738Y92000D01*
X898762D01*
X898730Y92011D01*
G03X898200Y92102I-532J-1511D01*
G01X896800D01*
G03X896270Y92011I2J-1602D01*
G01X896238Y92000D01*
X894262D01*
X894230Y92011D01*
G03X893700Y92102I-532J-1511D01*
G01X892300D01*
G03X891770Y92011I2J-1602D01*
G01X891738Y92000D01*
X889762D01*
X889730Y92011D01*
G03X889200Y92102I-532J-1511D01*
G01X887800D01*
G03X887270Y92011I2J-1602D01*
G01X887238Y92000D01*
X885262D01*
X885230Y92011D01*
G03X884700Y92102I-532J-1511D01*
G01X883300D01*
G03X882770Y92011I2J-1602D01*
G01X882738Y92000D01*
X880762D01*
X880730Y92011D01*
G03X880200Y92102I-532J-1511D01*
G01X878800D01*
G03X878270Y92011I2J-1602D01*
G01X878238Y92000D01*
X876262D01*
G37*
G36*
G01X921589Y37500D02*
X921385Y37704D01*
Y41839D01*
X920190Y43034D01*
X917500D01*
X912493Y48041D01*
Y56036D01*
X911297Y57232D01*
X910800D01*
Y73900D01*
X911800Y74900D01*
X911900D01*
X914700Y77700D01*
X922100D01*
X923860Y75940D01*
Y75937D01*
X923898Y75899D01*
Y72398D01*
X919300Y67800D01*
Y52200D01*
X921000Y50500D01*
X944000D01*
X945000Y49500D01*
Y38500D01*
X944000Y37500D01*
X921589D01*
G37*
G36*
G01X922000Y52500D02*
X920502Y53998D01*
Y61002D01*
X922500Y63000D01*
X927170D01*
X927347Y62824D01*
X930293D01*
X931500Y61616D01*
Y54000D01*
X930000Y52500D01*
X922000D01*
G37*
G36*
G01X955000Y37000D02*
X954000Y38000D01*
Y51000D01*
X954500Y51500D01*
X987104D01*
X987971Y50633D01*
Y49077D01*
X987970Y49075D01*
Y39776D01*
X987068Y38875D01*
X983921D01*
X982684Y37638D01*
Y37285D01*
X982399Y37000D01*
X955000D01*
G37*
G36*
G01X970636Y25000D02*
X970528Y25108D01*
X969392D01*
X968500Y26000D01*
Y34000D01*
X969000Y34500D01*
X982500D01*
X983000Y34000D01*
Y25500D01*
X982500Y25000D01*
X970636D01*
G37*
G36*
G01X980716Y64500D02*
X983678Y61537D01*
Y54668D01*
X983011Y54000D01*
X968500D01*
X967500Y55000D01*
Y63500D01*
X968500Y64500D01*
X980716D01*
G37*
G36*
G01X954000Y72964D02*
X954702Y73665D01*
Y73678D01*
X954773Y73750D01*
Y75773D01*
X958077Y79077D01*
X989077D01*
X1012857Y102857D01*
X1051643D01*
X1052000Y102500D01*
Y95000D01*
X1050000Y93000D01*
X1025500D01*
X1007500Y75000D01*
Y54000D01*
X1006500Y53000D01*
X998464D01*
X997869Y53595D01*
Y55397D01*
X996830Y56436D01*
X991953D01*
X991779Y56610D01*
Y71721D01*
X990000Y73500D01*
X960912D01*
G03X957128Y71640I-1612J-1500D01*
G01X957144Y71538D01*
X956866Y71260D01*
X956463D01*
X956442Y71265D01*
G03X956100Y71302I-342J-1565D01*
G01X954700D01*
G03X954338Y71260I2J-1602D01*
G01X954240D01*
X954000Y71500D01*
Y72964D01*
G37*
G36*
G01X997154Y27938D02*
X996504Y28589D01*
Y36338D01*
X997475Y37309D01*
X1000352D01*
Y30106D01*
X1002078D01*
X1002209Y29974D01*
Y28301D01*
X1001846Y27938D01*
X997154D01*
G37*
G36*
G01X995000Y161700D02*
X997400Y159300D01*
Y158436D01*
G03Y156524I1025J-956D01*
G01Y154500D01*
G03Y152586I1025J-957D01*
G01Y150562D01*
G03Y148650I1025J-956D01*
G01Y146626D01*
G03Y144712I1025J-957D01*
G01Y142688D01*
G03Y140776I1025J-956D01*
G01Y138752D01*
G03Y136838I1025J-957D01*
G01Y136200D01*
X1001300Y132300D01*
Y131400D01*
X1000900Y131000D01*
X999319D01*
G03X997531I-894J-1079D01*
G01X995382D01*
G03X993594I-894J-1079D01*
G01X992800D01*
X992000Y131800D01*
Y138016D01*
G02X992427Y138415I400J0D01*
G03X992337Y141104I91J1349D01*
G01X992239Y141090D01*
X992000Y141329D01*
Y157651D01*
G02X992426Y158051I400J1D01*
G03X993510Y160440I93J1398D01*
G01X993175Y160775D01*
X994100Y161700D01*
X995000D01*
G37*
G36*
G01X1017323Y50500D02*
G03X1015878Y51410I-1445J-692D01*
G01X1014478D01*
G03X1013478Y51060I-1J-1601D01*
G03X1012478Y51410I-999J-1251D01*
G01X1011078D01*
G03X1010905Y51401I-3J-1601D01*
G01X1010809Y51391D01*
X1010200Y52000D01*
Y66700D01*
X1010500Y67000D01*
X1030000D01*
X1030500Y66500D01*
Y51000D01*
X1030000Y50500D01*
X1017323D01*
G37*
G36*
G01X1018000Y68500D02*
X1017500Y69000D01*
Y75500D01*
X1019500Y77500D01*
X1033000D01*
X1034500Y76000D01*
Y69000D01*
X1034063Y68563D01*
X1033962Y68580D01*
G03X1033700Y68602I-265J-1580D01*
G01X1032300D01*
G03X1031770Y68511I2J-1602D01*
G01X1031738Y68500D01*
X1018000D01*
G37*
G36*
G01X1067000Y609000D02*
X1042500D01*
X1035500Y616000D01*
Y821716D01*
X1036974Y823190D01*
X1160254D01*
X1162500Y820944D01*
Y704500D01*
X1067000Y609000D01*
G37*
G36*
G01X1217883Y132738D02*
X1217613Y132468D01*
X1211669D01*
X1211512Y132625D01*
Y135702D01*
X1209627Y137587D01*
Y154154D01*
G02X1210083Y154550I400J0D01*
G03X1208921Y158370I308J2180D01*
G01X1208780Y158244D01*
X1208298Y158726D01*
X1207241D01*
X1207229Y158727D01*
G03X1206992Y158742I-245J-1997D01*
G01X1203791D01*
G03X1203553Y158727I7J-2012D01*
G01X1203541Y158726D01*
X1201420D01*
G03X1199362I-1029J-1947D01*
G01X1189613D01*
X1175586Y144699D01*
X1174799D01*
X1173600Y143500D01*
Y141500D01*
X1175586Y139514D01*
Y132800D01*
X1175186Y132400D01*
X1174656D01*
X1174629Y132408D01*
G03X1174179Y132472I-448J-1537D01*
G01X1172779D01*
G03X1172329Y132408I-2J-1601D01*
G01X1172302Y132400D01*
X1170660D01*
X1170632Y132409D01*
G03X1170167Y132478I-465J-1532D01*
G01X1168767D01*
G03X1168302Y132409I0J-1601D01*
G01X1168274Y132400D01*
X1167500D01*
X1167100Y132800D01*
Y139811D01*
X1166171Y140740D01*
Y156488D01*
X1177088Y167405D01*
X1232618D01*
X1238865Y161158D01*
X1268286D01*
X1275826Y153618D01*
Y146420D01*
X1270146Y140740D01*
Y139012D01*
X1271468Y137690D01*
Y134535D01*
G03X1271464Y134422I1597J-113D01*
G01Y132962D01*
X1270999Y132498D01*
X1270902Y132510D01*
G03X1270705Y132522I-196J-1589D01*
G01X1269305D01*
G03X1268308Y132174I0J-1602D01*
G01X1268254Y132131D01*
X1267750D01*
X1267695Y132175D01*
G03X1266697Y132524I-998J-1252D01*
G01X1265297D01*
G03X1264897Y132473I1J-1602D01*
G01X1264786Y132444D01*
X1263912Y133318D01*
Y140964D01*
G03X1264961Y143627I-1032J1945D01*
G01X1264921Y143746D01*
X1266799Y145624D01*
Y147837D01*
X1263880Y150756D01*
X1261371D01*
X1261362Y150748D01*
X1259037Y153073D01*
X1247152D01*
X1246046Y151967D01*
Y146623D01*
X1246028Y146584D01*
G03X1245882Y145917I1456J-668D01*
G01Y144517D01*
G03X1245915Y144197I1602J3D01*
G01X1245936Y144092D01*
X1245304Y143460D01*
X1245245Y143448D01*
G03X1244120Y142563I323J-1569D01*
G01X1244066Y142448D01*
X1240886D01*
X1238784Y144549D01*
X1237782D01*
X1237758Y144555D01*
G03X1236680I-539J-2135D01*
G01X1236656Y144549D01*
X1228711D01*
X1228681Y144559D01*
G03X1227317I-682J-2094D01*
G01X1227287Y144549D01*
X1220991D01*
X1216347Y139905D01*
Y136891D01*
X1217883Y135355D01*
Y132738D01*
G37*
G36*
G01X1326844Y247076D02*
X1330702Y250933D01*
Y251605D01*
X1330759D01*
Y274895D01*
X1330500D01*
Y278500D01*
X1332000Y280000D01*
X1341500D01*
X1343000Y278500D01*
Y243952D01*
X1342848D01*
Y237848D01*
X1339000Y234000D01*
Y189087D01*
X1337944Y188031D01*
X1328969D01*
X1327500Y189500D01*
X1220600D01*
X1206700Y203400D01*
X1169100D01*
X1164100Y208400D01*
Y223300D01*
X1165000Y224200D01*
X1214900D01*
X1216798Y222302D01*
Y222198D01*
X1216902D01*
X1225100Y214000D01*
X1265500D01*
X1265550Y213950D01*
X1265800Y214200D01*
X1324300D01*
X1325800Y215700D01*
Y229300D01*
X1326844Y230344D01*
Y247076D01*
G37*
G36*
G01X1217600Y223200D02*
X1217300Y223500D01*
Y224500D01*
X1216150Y225650D01*
X1214850D01*
X1214800Y225700D01*
X1165500D01*
X1164100Y227100D01*
Y268900D01*
X1165800Y270600D01*
X1218600D01*
X1219100Y270100D01*
Y267400D01*
X1219198Y267302D01*
Y223498D01*
X1218900Y223200D01*
X1217600D01*
G37*
G36*
G01X1164700Y272300D02*
X1164100Y272901D01*
Y296097D01*
X1165503Y297500D01*
X1262000D01*
X1264500Y295000D01*
Y273500D01*
X1263300Y272300D01*
X1224202D01*
Y272602D01*
X1216798D01*
Y272300D01*
X1164700D01*
G37*
G36*
G01X1225300Y215563D02*
X1221500Y219363D01*
Y222198D01*
X1221802D01*
Y270301D01*
X1222400Y270900D01*
X1278100D01*
X1282000Y267000D01*
Y220500D01*
X1277063Y215563D01*
X1225300D01*
G37*
G36*
G01X1220000Y669000D02*
X1212000Y677000D01*
Y819119D01*
X1214456Y821575D01*
X1288676D01*
X1290500Y819751D01*
Y728113D01*
G03Y724121I928J-1996D01*
G01Y690500D01*
X1269000Y669000D01*
X1220000D01*
G37*
G36*
G01X1308000Y232000D02*
X1307000Y233000D01*
Y263000D01*
X1308000Y264000D01*
X1323956D01*
Y263418D01*
X1329248D01*
Y251180D01*
X1325389Y247320D01*
Y233269D01*
X1324120Y232000D01*
X1308000D01*
G37*
G36*
G01X1342000Y188500D02*
X1341000Y189500D01*
Y234000D01*
X1344500Y237500D01*
Y251098D01*
X1344752D01*
Y263418D01*
X1350044D01*
Y263456D01*
X1351500Y262000D01*
X1358094D01*
X1358095Y261998D01*
X1359500D01*
X1360261Y261238D01*
X1360263D01*
X1360343Y261157D01*
X1360345Y261155D01*
G03X1360455Y261045I1894J1784D01*
G01X1360457Y261043D01*
X1362500Y259000D01*
Y190500D01*
X1360500Y188500D01*
X1342000D01*
G37*
G36*
G01X1372300Y199300D02*
X1365700D01*
X1365000Y200000D01*
Y251000D01*
X1366000Y252000D01*
X1377000D01*
X1378500Y250500D01*
Y202500D01*
X1376500Y200500D01*
X1373500D01*
X1372300Y199300D01*
G37*
G36*
G01X1384959Y187927D02*
X1383532Y186500D01*
X1382678D01*
X1382426Y186752D01*
X1379819D01*
G03X1378960Y187002I-859J-1351D01*
G01X1377360D01*
G03X1376195Y186500I-1J-1601D01*
G01X1367579D01*
G03X1366186Y187366I-1776J-1303D01*
G01X1366123Y187377D01*
X1366000Y187500D01*
Y195900D01*
X1371300D01*
X1373300Y197900D01*
X1375687D01*
X1377918Y200131D01*
X1384071D01*
X1384959Y199243D01*
Y187927D01*
G37*
%LPC*%
G75*
G36*
G01X19398Y185200D02*
G02X19598Y185975I1602J0D01*
G01Y188100D01*
G02X24002I2202J0D01*
G01Y185975D01*
G02X24202Y185200I-1402J-775D01*
G01Y183600D01*
G02X22600Y181998I-1602J0D01*
G01X21000D01*
G02X19398Y183600I0J1602D01*
G01Y185200D01*
G37*
G36*
G01X365945Y76624D02*
G02X370914Y71654I-1J-4970D01*
G01Y40157D01*
G02X365945Y35188I-4969J0D01*
G01X356102D01*
G02X351132Y40157I0J4970D01*
G01Y71654D01*
G02X356102Y76624I4970J0D01*
G01X365945D01*
G37*
G36*
G01X823303Y285362D02*
Y285265D01*
X823298Y285172D01*
G02Y285546I-4007J187D01*
G01X823302Y285455D01*
X823303Y285364D01*
Y285362D01*
G37*
G36*
G01Y265362D02*
Y265265D01*
X823298Y265172D01*
G02Y265546I-4007J187D01*
G01X823302Y265455D01*
X823303Y265364D01*
Y265362D01*
G37*
G36*
G01X683600Y376706D02*
X680099D01*
G02X680100Y380730I1J2012D01*
G01X683600D01*
G02X685612Y378728I0J-2012D01*
G01Y378631D01*
X685604Y378544D01*
G02X683600Y376706I-2004J173D01*
G37*
G54D179*
X604400Y421200D03*
X579900Y427400D03*
G54D178*
X134251Y153543D03*
G54D177*
X122165Y142874D03*
X173897D03*
G54D175*
X20800Y176000D03*
X23200D03*
X20600Y179600D03*
X23000D03*
X99700Y182600D03*
Y189400D03*
X20700Y191100D03*
X23100D03*
X23300Y433600D03*
X26700D03*
X65600Y425300D03*
X67300Y425500D03*
X180138Y133711D03*
X116064Y133799D03*
X120500Y174200D03*
Y175800D03*
Y178200D03*
Y179800D03*
Y182200D03*
Y183800D03*
Y186200D03*
Y187800D03*
Y190200D03*
X126500Y171800D03*
Y174200D03*
Y175800D03*
Y178200D03*
Y179800D03*
Y182200D03*
Y183800D03*
Y186200D03*
Y187800D03*
Y190200D03*
X116832Y270520D03*
X120232D03*
X128851Y653146D03*
X125800Y833300D03*
Y836700D03*
X138900Y263100D03*
X140750Y263350D03*
X145250D03*
X138900Y265500D03*
X140750Y268850D03*
X152850D03*
X134800Y836700D03*
Y833300D03*
X226950Y188750D03*
X239050Y183250D03*
Y188750D03*
X262300Y646200D03*
X281200Y628500D03*
X290200Y631900D03*
Y628500D03*
X506677Y290740D03*
X562831Y333880D03*
Y336080D03*
X563031Y337780D03*
X598463Y255908D03*
X601863D03*
Y259308D03*
X592863Y255908D03*
Y259308D03*
X602970Y329340D03*
X605370D03*
X606990Y329560D03*
X609190D03*
X614530Y334150D03*
Y339750D03*
X823352Y13200D03*
X825152D03*
X827352D03*
X829152D03*
X831352D03*
X833152D03*
X835352D03*
X837152D03*
X839352D03*
X841152D03*
X843352D03*
X845152D03*
X876100Y94300D03*
X878400D03*
X880600D03*
X882900D03*
X885100D03*
X887400D03*
X889600D03*
X891900D03*
X894100D03*
X896400D03*
X898600D03*
X900900D03*
X903100D03*
X905400D03*
X907600D03*
X909900D03*
X912100D03*
X914400D03*
X916600D03*
X918900D03*
X921100D03*
X923400D03*
X925600D03*
X927900D03*
X930100D03*
X932400D03*
X934600D03*
X936900D03*
X956500Y73500D03*
X1014848Y100700D03*
X1017048D03*
X1018900D03*
X1021100D03*
X1022900D03*
X1025100D03*
X1026900D03*
X1029100D03*
X1031400D03*
X1033600D03*
X1035900D03*
X1038100D03*
X1040400D03*
X1042600D03*
X1044900D03*
X1047100D03*
X1049400D03*
X1026800Y63500D03*
X1031900Y70800D03*
X1026800Y72500D03*
X1030200D03*
X1213848Y134615D03*
X1215652D03*
X1172379Y134671D03*
X1174579D03*
X1168367Y134676D03*
X1170567D03*
X1268905Y134721D03*
X1264897Y134722D03*
X1267097D03*
X1243684Y144117D03*
Y146317D03*
X1339500Y244800D03*
Y248200D03*
X1348500Y244800D03*
Y248200D03*
G54D176*
X242129Y41754D03*
%LPD*%
G75*
G54D100*
X145965Y380050D03*
X140047Y395950D03*
Y380050D03*
X145953Y395950D03*
G54D101*
X161050Y734560D03*
Y737120D03*
Y739680D03*
Y742240D03*
X153850Y789660D03*
Y792220D03*
Y794780D03*
Y797340D03*
X193350Y710660D03*
Y713220D03*
Y715780D03*
Y718340D03*
X177350Y742240D03*
Y739680D03*
Y737120D03*
Y734560D03*
X193350Y766160D03*
Y768720D03*
Y771280D03*
Y773840D03*
X170150Y797340D03*
Y794780D03*
Y792220D03*
Y789660D03*
X209650Y713220D03*
Y710660D03*
Y718340D03*
Y715780D03*
Y773840D03*
Y771280D03*
Y768720D03*
Y766160D03*
X470050Y374460D03*
Y377020D03*
Y379580D03*
Y382140D03*
X486350Y377020D03*
Y374460D03*
Y382140D03*
Y379580D03*
G54D110*
X223500Y601500D03*
X906500Y316500D03*
G54D111*
X259500Y152000D03*
X602763Y240858D03*
G54D102*
X167484Y186086D03*
Y182286D03*
X174084Y186086D03*
Y182286D03*
G54D120*
X320669Y55118D03*
G54D112*
X259500Y134250D03*
X1337000Y282750D03*
G54D103*
X196018Y209858D03*
X191018D03*
Y241354D03*
X196018D03*
X206018Y209858D03*
X201018D03*
Y241354D03*
X206018D03*
X534526Y248913D03*
X529526D03*
X524526D03*
X519526D03*
Y280409D03*
X524526D03*
X529526D03*
X534526D03*
G54D121*
X302943Y166500D03*
X281057D03*
X938457Y44100D03*
X960343D03*
G54D130*
X535962Y37520D03*
X579269D03*
X622577D03*
X665884D03*
X1138324D03*
X1181631D03*
X1224939D03*
X1268246D03*
G54D10*
G01X25500Y420000D02*
X25250Y420250D01*
Y424000D01*
G01D02*
X27086D01*
X27286Y423800D01*
X31000D01*
G01X54083Y294947D02*
X58383D01*
G01X54083Y300853D02*
X48886D01*
X47991Y299958D01*
G01X56736Y315317D02*
Y316764D01*
X55750Y317750D01*
Y320500D01*
X54600Y321650D01*
G01X31000Y423800D02*
X35964D01*
X36194Y424030D01*
X41900D01*
G01Y422065D02*
X42435D01*
X43500Y421000D01*
Y418802D01*
G01Y414000D02*
X47500D01*
G01X43500Y418802D02*
Y414000D01*
G01X64500Y420750D02*
X59250Y426000D01*
X54100D01*
G01Y424030D02*
X57720D01*
X60200Y421550D01*
Y417800D01*
X60500Y417500D01*
G01D02*
X61000Y417000D01*
X64750D01*
G01X84600Y303000D02*
X85828D01*
X86007Y302821D01*
X88917D01*
G01X68500Y420750D02*
X72500D01*
G01X64500D02*
X68500D01*
G01X91450Y707650D02*
Y702150D01*
G01X128800Y306400D02*
X125400D01*
X124300Y305300D01*
G01X128850Y298100D02*
Y300750D01*
X124300Y305300D01*
G01X128180Y310964D02*
X126930Y309714D01*
X123680D01*
G01X121350Y298100D02*
Y307384D01*
X123680Y309714D01*
G01X132430Y311214D02*
X128430D01*
X128180Y310964D01*
G01X129547Y537342D02*
X128041Y535836D01*
Y535826D01*
X127996Y535781D01*
G01X118600Y762500D02*
Y767600D01*
X119500Y768500D01*
G01X134800Y306400D02*
Y303200D01*
X135700Y302300D01*
X137200D01*
G01D02*
X138500D01*
X139300Y303100D01*
Y306400D01*
G01X246500Y139000D02*
Y133153D01*
X244655Y131308D01*
X236222D01*
X231270Y136260D01*
Y140880D01*
G01D02*
Y143482D01*
X232400Y144612D01*
X235505D01*
G01X243618Y143381D02*
X240899Y140662D01*
Y140649D01*
X239750Y139500D01*
G01X246500Y139000D02*
Y139500D01*
X249157Y142157D01*
X249857D01*
G01X242634Y134760D02*
X243000Y135126D01*
Y139000D01*
G01D02*
Y139793D01*
X247333Y144126D01*
X249857D01*
G01Y146094D02*
X246331D01*
X243618Y143381D01*
G01X239600Y149650D02*
X239981Y150031D01*
X249857D01*
G01X239600Y149650D02*
X237043D01*
X235505Y148112D01*
G01D02*
X233770Y149847D01*
Y152909D01*
G01X265400Y637870D02*
X267250D01*
X269000Y639620D01*
Y640400D01*
X272700Y644100D01*
X276300D01*
G01X265400Y639835D02*
X267050Y641485D01*
Y647400D01*
G01X241300Y639150D02*
X237300D01*
G01X245300D02*
X246651D01*
X249901Y635900D01*
X253200D01*
G01X245300Y639150D02*
X241300D01*
G01X245050Y643400D02*
X250580Y637870D01*
X253200D01*
G01X245050Y647100D02*
Y643400D01*
G01X292000Y126000D02*
Y130000D01*
G01X281250D02*
X285500D01*
G01X277750Y126000D02*
Y130000D01*
G01X273250Y126000D02*
X277750D01*
G01Y122000D02*
Y126000D01*
G01X269143Y142157D02*
Y135886D01*
X275029Y130000D01*
X277750D01*
G01X286000Y126000D02*
Y123380D01*
X284420Y121800D01*
X281450D01*
X281250Y122000D01*
G01Y126000D02*
Y122000D01*
G01X302943Y166500D02*
X294500D01*
X293500Y165500D01*
Y153500D01*
X294500Y152500D01*
G01X281057Y166500D02*
X290900D01*
X291900Y165500D01*
Y153800D01*
X291100Y153000D01*
X291000D01*
X290500Y152500D01*
G01X280957Y166500D02*
X281057D01*
G01X285290Y149350D02*
X280050D01*
G01D02*
X277900D01*
X277219Y150031D01*
X269143D01*
G01Y148063D02*
X273937D01*
X274500Y147500D01*
X275000D01*
G01X282050Y643900D02*
X282500Y644350D01*
Y647700D01*
G01X276300Y644100D02*
X276500Y643900D01*
X282050D01*
G01X267050Y647400D02*
X269700D01*
X270800Y648500D01*
Y652900D01*
G01D02*
X267800D01*
X266800Y651900D01*
G01X303043Y166500D02*
X302943D01*
G01X345341Y327915D02*
X351515D01*
G01X558281Y342980D02*
Y346781D01*
X560531Y349031D01*
Y351980D01*
G01X558281Y338980D02*
Y334980D01*
G01Y342980D02*
Y338980D01*
G01X548928Y347157D02*
Y344832D01*
X550910Y342850D01*
X554400D01*
G01X558561Y364180D02*
Y374850D01*
X558331Y375080D01*
G01D02*
X554500Y378911D01*
Y380500D01*
G01X548531Y362580D02*
X551120D01*
X552720Y364180D01*
G01D02*
X556596D01*
G01X569200Y375000D02*
X568800Y374600D01*
Y373700D01*
X562501Y367401D01*
Y364180D01*
G01X569200Y375000D02*
Y376700D01*
X573500Y381000D01*
G01X564466Y364180D02*
Y365966D01*
X569700Y371200D01*
Y374500D01*
X569200Y375000D01*
G01X558561Y351980D02*
Y350061D01*
X556810Y348310D01*
X556809D01*
X556799Y348300D01*
X550071D01*
X548928Y347157D01*
G01X558531Y380830D02*
X554830D01*
X554500Y380500D01*
G01X573500Y381000D02*
X570420Y384080D01*
X569531D01*
G01X587438Y230850D02*
X587700Y231112D01*
Y232073D01*
X588363Y232736D01*
Y232771D01*
X588427Y232835D01*
Y233072D01*
X590307Y234952D01*
X593120D01*
G01X587438Y230850D02*
X586377Y229789D01*
Y229223D01*
X585762Y228608D01*
X584813D01*
G01X572350Y238400D02*
X571584Y237634D01*
Y227361D01*
X573637Y225308D01*
X589833D01*
X592563Y228038D01*
Y228308D01*
G01X593120Y231015D02*
Y228865D01*
X592563Y228308D01*
G01X593120Y232984D02*
X590839D01*
X589963Y232108D01*
Y232073D01*
X589920Y232030D01*
Y228365D01*
X588963Y227408D01*
G01X593120Y236921D02*
X588679D01*
X587400Y238200D01*
G01X580178Y238969D02*
X582039Y240830D01*
X584522D01*
G01D02*
X588615D01*
X590558Y238889D01*
X593120D01*
G01X575850Y238400D02*
X579609D01*
X580178Y238969D01*
G01X640400Y218200D02*
Y217445D01*
X632363Y209408D01*
X630913D01*
G01X615613Y213608D02*
Y210797D01*
X617302Y209108D01*
X619313D01*
X619813Y209608D01*
G01X630913Y213508D02*
X633063D01*
X635863Y216308D01*
G01X635190Y219641D02*
X634649Y219100D01*
X633855D01*
X632363Y217608D01*
X630913D01*
G01X623113Y221608D02*
X629563D01*
X629663Y221708D01*
G01X612406Y236921D02*
X615676D01*
X616718Y237963D01*
Y238408D01*
G01X619613Y217608D02*
Y221608D01*
G01X619813Y213608D02*
Y217408D01*
X619613Y217608D01*
G01X619813Y209608D02*
Y213608D01*
G01X612406Y231015D02*
Y226565D01*
X617363Y221608D01*
X619613D01*
G01X627413Y217608D02*
X623113D01*
G01X627413Y213508D02*
Y209408D01*
G01Y213508D02*
Y217608D01*
G01X623313Y213608D02*
Y217408D01*
X623113Y217608D01*
G01X624934Y257608D02*
X638963D01*
X639963Y256608D01*
Y242608D01*
X638963Y241608D01*
G01X623207Y355616D02*
X619384D01*
X618600Y356400D01*
Y357100D01*
G01D02*
X619100D01*
X619584Y357584D01*
X623207D01*
G01X656592Y257608D02*
X642700D01*
X641563Y256471D01*
Y242508D01*
X642463Y241608D01*
G01X643000Y343000D02*
X642000D01*
X639890Y345110D01*
Y346607D01*
G01Y366593D02*
Y367390D01*
X642000Y369500D01*
X643000D01*
G01X642793Y357584D02*
X646084D01*
X646931Y358431D01*
X648792D01*
G01D02*
X649623Y357600D01*
X652500D01*
G01X974803Y188976D02*
Y188197D01*
X976000Y187000D01*
X1025500D01*
X1028500Y190000D01*
Y257500D01*
G01X1273486Y243500D02*
X1289900D01*
X1290900Y244500D01*
Y270100D01*
X1290000Y271000D01*
G01X1314514Y243500D02*
X1294000D01*
X1292500Y245000D01*
Y270000D01*
X1293500Y271000D01*
G01X1315250Y274500D02*
X1312900D01*
X1312200Y275200D01*
G01X1313000Y293250D02*
X1310750D01*
X1309900Y292400D01*
G01X1327357Y267187D02*
X1322887D01*
X1322500Y266800D01*
G01X1320750Y286500D02*
X1327183D01*
X1328568Y285115D01*
Y275904D01*
X1327357Y274693D01*
Y273093D01*
G01X1317300Y301650D02*
Y304584D01*
X1317026Y304858D01*
G01X1317250Y286500D02*
X1314000D01*
G01X1320750Y290000D02*
Y286500D01*
G01Y294000D02*
Y297500D01*
X1321400Y298150D01*
G01X1320750Y290000D02*
Y294000D01*
G01X1325250Y290500D02*
Y297178D01*
X1324278Y298150D01*
X1321400D01*
G01X1317250Y294000D02*
Y290000D01*
G01D02*
X1317000Y289750D01*
X1313000D01*
G01X1317250Y294000D02*
Y298100D01*
X1317300Y298150D01*
G01X1355066Y275228D02*
X1355275Y275437D01*
Y277025D01*
X1356750Y278500D01*
G01X1346643Y269156D02*
X1351656D01*
X1354300Y271800D01*
Y274462D01*
X1355066Y275228D01*
G01X1361500Y270250D02*
Y273500D01*
G01X1346643Y273093D02*
Y274643D01*
X1348500Y276500D01*
G01X1346643Y271124D02*
X1350624D01*
X1352000Y272500D01*
Y276700D01*
G01D02*
Y278226D01*
X1350186Y280040D01*
G01X1346643Y267187D02*
X1352313D01*
X1352500Y267000D01*
G01X1361500Y266750D02*
X1362239Y266011D01*
Y262939D01*
G01D02*
X1360966D01*
X1360205Y263700D01*
X1358800D01*
X1357000Y265500D01*
G01D02*
X1356400Y264900D01*
X1351630D01*
X1351311Y265219D01*
X1346643D01*
G01X1356750Y278500D02*
X1356400Y278850D01*
Y282400D01*
X700Y19100D03*
X16200Y120100D03*
X27200Y821800D03*
X33800Y872600D03*
X42587Y151614D03*
X80579D03*
X92990Y252362D03*
X116790D03*
X526215Y184000D03*
X565585D03*
X1027722Y-9125D03*
X1054494D03*
X1301120Y173278D03*
Y183908D03*
X1384200Y122800D03*
X1373200Y823500D03*
X1415100Y-36700D03*
X1389800Y879000D03*
G54D20*
X28400Y270875D03*
Y287925D03*
G54D113*
X259500Y131750D03*
X1337000Y280250D03*
G54D140*
X624934Y257608D03*
X656592D03*
G54D104*
X193900Y274372D03*
X183900D03*
X213900D03*
X203900D03*
X302500Y207200D03*
X292500D03*
X326200D03*
X336200D03*
X312500D03*
X346200D03*
X465485Y200680D03*
Y190680D03*
Y180680D03*
X488462Y180761D03*
Y190761D03*
Y200761D03*
X501742Y215594D03*
X511742D03*
X521742D03*
X531742D03*
X772300Y16200D03*
X762300D03*
X752300D03*
X785300Y16100D03*
X795300D03*
X805300D03*
X819291Y265354D03*
Y285354D03*
X1075197Y92126D03*
Y112126D03*
X1348785Y161642D03*
X1323195D03*
X1348785Y179358D03*
X1323195D03*
G54D131*
X533010Y69803D03*
X530057Y67048D03*
X535962Y64292D03*
X524151Y69803D03*
X527104Y64292D03*
X535962Y49331D03*
X527104D03*
X530057Y52087D03*
X533010Y54843D03*
X524151D03*
X533010Y99725D03*
X530057Y96969D03*
X535962Y94213D03*
X524151Y99725D03*
X527104Y94213D03*
X533010Y84764D03*
X530057Y82008D03*
X535962Y79252D03*
X524151Y84764D03*
X527104Y79252D03*
X567458Y54843D03*
X570411Y49331D03*
Y64292D03*
X567458Y69803D03*
X541868D03*
X538915Y67048D03*
X547773D03*
X544821Y64292D03*
Y49331D03*
X547773Y52087D03*
X538915D03*
X541868Y54843D03*
X570411Y79252D03*
Y94213D03*
X567458Y84764D03*
Y99725D03*
X541868D03*
X538915Y96969D03*
X547773D03*
X544821Y94213D03*
X541868Y84764D03*
X538915Y82008D03*
X547773D03*
X544821Y79252D03*
X576317Y54843D03*
X585175D03*
X573364Y52087D03*
X582222D03*
X591080D03*
X579269Y49331D03*
X588128D03*
X576317Y69803D03*
X585175D03*
X573364Y67048D03*
X582222D03*
X591080D03*
X579269Y64292D03*
X588128D03*
X579269Y79252D03*
X588128D03*
X582222Y82008D03*
X591080D03*
X585175Y84764D03*
X576317D03*
X573364Y82008D03*
X576317Y99725D03*
X585175D03*
X573364Y96969D03*
X582222D03*
X579269Y94213D03*
X588128D03*
X591080Y96969D03*
X619624Y54843D03*
X628482D03*
X616671Y52087D03*
X625529D03*
X634388D03*
X622577Y49331D03*
X631435D03*
X619624Y69803D03*
X628482D03*
X616671Y67048D03*
X625529D03*
X634388D03*
X622577Y64292D03*
X631435D03*
X610766Y54843D03*
X613718Y49331D03*
Y64292D03*
X610766Y69803D03*
X622577Y79252D03*
X631435D03*
X625529Y82008D03*
X634388D03*
X628482Y84764D03*
X619624D03*
X616671Y82008D03*
X619624Y99725D03*
X628482D03*
X616671Y96969D03*
X625529D03*
X622577Y94213D03*
X631435D03*
X634388Y96969D03*
X613718Y79252D03*
Y94213D03*
X610766Y84764D03*
Y99725D03*
X662931Y54843D03*
X671789D03*
X659978Y52087D03*
X668836D03*
X665884Y49331D03*
X662931Y69803D03*
X671789D03*
X659978Y67048D03*
X668836D03*
X665884Y64292D03*
X654073Y54843D03*
X657025Y49331D03*
Y64292D03*
X654073Y69803D03*
X665884Y79252D03*
X668836Y82008D03*
X671789Y84764D03*
X662931D03*
X659978Y82008D03*
X662931Y99725D03*
X671789D03*
X659978Y96969D03*
X668836D03*
X665884Y94213D03*
X657025Y79252D03*
Y94213D03*
X654073Y84764D03*
Y99725D03*
X677695Y52087D03*
X674742Y49331D03*
X677695Y67048D03*
X674742Y64292D03*
Y79252D03*
X677695Y82008D03*
X674742Y94213D03*
X677695Y96969D03*
X1135372Y69803D03*
X1144230D03*
X1132419Y67048D03*
X1141277D03*
X1138324Y64292D03*
X1126513Y69803D03*
X1129466Y64292D03*
X1138324Y49331D03*
X1129466D03*
X1141277Y52087D03*
X1132419D03*
X1144230Y54843D03*
X1135372D03*
X1126513D03*
X1135372Y99725D03*
X1144230D03*
X1132419Y96969D03*
X1141277D03*
X1138324Y94213D03*
X1126513Y99725D03*
X1129466Y94213D03*
X1135372Y84764D03*
X1144230D03*
X1132419Y82008D03*
X1141277D03*
X1138324Y79252D03*
X1126513Y84764D03*
X1129466Y79252D03*
X1178679Y54843D03*
X1175726Y52087D03*
X1178679Y69803D03*
X1175726Y67048D03*
X1169820Y54843D03*
X1172773Y49331D03*
Y64292D03*
X1169820Y69803D03*
X1150135Y67048D03*
X1147183Y64292D03*
Y49331D03*
X1150135Y52087D03*
X1178679Y84764D03*
X1175726Y82008D03*
X1178679Y99725D03*
X1175726Y96969D03*
X1172773Y79252D03*
Y94213D03*
X1169820Y84764D03*
Y99725D03*
X1150135Y96969D03*
X1147183Y94213D03*
X1150135Y82008D03*
X1147183Y79252D03*
X1187537Y54843D03*
X1184584Y52087D03*
X1193442D03*
X1181631Y49331D03*
X1190490D03*
X1187537Y69803D03*
X1184584Y67048D03*
X1193442D03*
X1181631Y64292D03*
X1190490D03*
X1181631Y79252D03*
X1190490D03*
X1184584Y82008D03*
X1193442D03*
X1187537Y84764D03*
Y99725D03*
X1184584Y96969D03*
X1181631Y94213D03*
X1190490D03*
X1193442Y96969D03*
X1221986Y54843D03*
X1230844D03*
X1219033Y52087D03*
X1227891D03*
X1236750D03*
X1224939Y49331D03*
X1233797D03*
X1221986Y69803D03*
X1230844D03*
X1219033Y67048D03*
X1227891D03*
X1236750D03*
X1224939Y64292D03*
X1233797D03*
X1213128Y54843D03*
X1216080Y49331D03*
Y64292D03*
X1213128Y69803D03*
X1224939Y79252D03*
X1233797D03*
X1227891Y82008D03*
X1236750D03*
X1230844Y84764D03*
X1221986D03*
X1219033Y82008D03*
X1221986Y99725D03*
X1230844D03*
X1219033Y96969D03*
X1227891D03*
X1224939Y94213D03*
X1233797D03*
X1236750Y96969D03*
X1216080Y79252D03*
Y94213D03*
X1213128Y84764D03*
Y99725D03*
X1265293Y54843D03*
X1274151D03*
X1262340Y52087D03*
X1271198D03*
X1280057D03*
X1268246Y49331D03*
X1277104D03*
X1265293Y69803D03*
X1274151D03*
X1262340Y67048D03*
X1271198D03*
X1280057D03*
X1268246Y64292D03*
X1277104D03*
X1256435Y54843D03*
X1259387Y49331D03*
Y64292D03*
X1256435Y69803D03*
X1268246Y79252D03*
X1277104D03*
X1271198Y82008D03*
X1280057D03*
X1274151Y84764D03*
X1265293D03*
X1262340Y82008D03*
X1265293Y99725D03*
X1274151D03*
X1262340Y96969D03*
X1271198D03*
X1268246Y94213D03*
X1277104D03*
X1280057Y96969D03*
X1259387Y79252D03*
Y94213D03*
X1256435Y84764D03*
Y99725D03*
G54D11*
G01X22000Y171250D02*
Y167200D01*
G01X21900Y195850D02*
Y199700D01*
G01X21800Y184350D02*
Y188100D01*
G01X23100Y220450D02*
Y224500D01*
G01X27300Y223200D02*
Y229000D01*
G01X44029Y272572D02*
X44100D01*
Y272600D01*
X43600D01*
X38500Y267500D01*
Y265900D01*
X35400Y262800D01*
X28400D01*
G01X18000Y271600D02*
Y289400D01*
G01Y271600D02*
Y265100D01*
X20300Y262800D01*
X28400D01*
G01X42900Y284500D02*
X38500Y288900D01*
Y294100D01*
X36500Y296100D01*
X28200D01*
G01D02*
X20000D01*
X18000Y294100D01*
Y289400D01*
G01X28098Y310872D02*
X26172D01*
X24000Y308700D01*
G01D02*
X26026Y306674D01*
X28162D01*
G01X21400Y341000D02*
Y327900D01*
G01Y354000D02*
Y341000D01*
G01X26300Y317600D02*
X39600D01*
G01X21400Y327900D02*
Y320800D01*
X24600Y317600D01*
X26300D01*
G01X28050Y321200D02*
X24678D01*
X24639Y321239D01*
G01X28050Y321200D02*
Y326650D01*
X27470Y327230D01*
Y330307D01*
G01X31500Y366900D02*
X24500D01*
X22900Y365300D01*
G01D02*
X21400Y363800D01*
Y354000D01*
G01X20713Y410087D02*
X26402Y404398D01*
X63272D01*
X81872Y385798D01*
X86904D01*
G01X31000Y416200D02*
Y412684D01*
X31324Y412360D01*
Y410800D01*
G01X29250Y429000D02*
X25500D01*
X25000Y429500D01*
G01X21300D02*
X25000D01*
G01X20713Y418326D02*
Y419878D01*
X21750Y420915D01*
Y424000D01*
G01X31550Y695275D02*
X27125D01*
G01X53300Y705600D02*
X48200Y700500D01*
X34100D01*
X31200Y703400D01*
Y709150D01*
G01X25050Y746900D02*
Y750150D01*
X24000Y751200D01*
G01X25050Y720400D02*
Y716900D01*
G01X24000Y751200D02*
Y751400D01*
X27000Y754400D01*
G01X41603Y173596D02*
Y177598D01*
G01X31400Y204900D02*
Y209190D01*
G01X63250Y200100D02*
Y205050D01*
G01X46750Y200100D02*
X42800D01*
G01X47900Y204900D02*
Y208017D01*
X46760Y209157D01*
G01X37567Y183596D02*
Y187598D01*
G01D02*
Y191600D01*
G01X33565Y187598D02*
X37567D01*
G01X41603Y177598D02*
Y181600D01*
G01X37601Y177598D02*
X41603D01*
G01X31500Y220450D02*
Y224400D01*
G01X44426Y267408D02*
X46558D01*
X48400Y269250D01*
G01X41500Y265250D02*
X42318D01*
X44318Y267250D01*
Y267300D01*
X44426Y267408D01*
G01X38500Y273250D02*
X35150D01*
G01X44900Y261750D02*
X53650D01*
X60800Y254600D01*
X67700D01*
X68100Y255000D01*
G01X41500Y261750D02*
X44900D01*
G01X38500Y284350D02*
X35150D01*
G01X39600Y317600D02*
X46450D01*
X48450Y319600D01*
Y322728D01*
X49100Y323378D01*
Y328300D01*
G01X54600Y325150D02*
Y328600D01*
G01X49100Y328300D02*
Y346500D01*
X49300Y346700D01*
G01X31550Y321200D02*
X34800D01*
G01X41550Y321400D02*
X38500D01*
G01X58300Y330950D02*
X58100Y331150D01*
Y334600D01*
G01X62800Y330650D02*
Y334100D01*
X62400Y334500D01*
G01X67600Y327350D02*
X66850D01*
X63550Y330650D01*
X62800D01*
G01X54600Y321650D02*
X51050D01*
G01X43262Y350307D02*
Y357062D01*
G01X49300Y346700D02*
X48512Y347488D01*
Y356488D01*
G01X53422Y354364D02*
Y353158D01*
X55907Y350673D01*
G01X60610Y381665D02*
Y377296D01*
X61799Y376107D01*
G01X44866Y384307D02*
Y389366D01*
X46850Y391350D01*
Y394400D01*
G01X44866Y384307D02*
Y378634D01*
G01X39866Y384307D02*
Y388934D01*
X39300Y389500D01*
Y389557D01*
G01X39150Y394100D02*
X43050D01*
X43350Y394400D01*
G01X39300Y389557D02*
Y390500D01*
X39150Y390650D01*
Y394100D01*
G01X53200Y477750D02*
X55350D01*
X59250Y481650D01*
Y483000D01*
G01X36750Y466000D02*
Y462900D01*
G01X53200Y466650D02*
Y462500D01*
G01X63519Y505320D02*
Y502220D01*
G01X59250Y502000D02*
X59470Y502220D01*
X63519D01*
G01X55261Y507391D02*
Y506737D01*
X59250Y502748D01*
Y502000D01*
G01X62298Y484200D02*
X60450D01*
X59250Y483000D01*
G01X35700Y488500D02*
X37250Y486950D01*
Y484500D01*
G01X60200Y564500D02*
X55950D01*
G01X60200Y572500D02*
X55950D01*
G01X57200Y682950D02*
X59850D01*
X60700Y682100D01*
G01X47300Y709650D02*
Y704400D01*
G01X37300Y704600D02*
X42000D01*
X42300Y704900D01*
G01D02*
X43300Y705900D01*
Y709650D01*
G01X57200Y694050D02*
X54825D01*
X54700Y694175D01*
X51450D01*
G01X57200Y694050D02*
X60650D01*
G01X58850Y708900D02*
Y705850D01*
X59100Y705600D01*
G01D02*
X53300D01*
G01D02*
X51300Y707600D01*
Y709650D01*
G01X37700Y693500D02*
X38640Y694440D01*
X42130D01*
G01X63222Y720600D02*
X65500Y718322D01*
Y717400D01*
G01X73400Y741700D02*
X73300Y741600D01*
X70600D01*
G01X52300Y766650D02*
X49550Y769400D01*
X47800D01*
G01D02*
Y772900D01*
G01X35000Y766850D02*
Y769900D01*
G01X39000Y766850D02*
Y769900D01*
G01X42900Y766750D02*
Y769900D01*
X42800Y770000D01*
G01X53150Y770800D02*
Y774650D01*
X52500Y775300D01*
G01D02*
Y779600D01*
G01X127746Y-260199D02*
X95746D01*
G01X81563Y173596D02*
Y177598D01*
G01X82150Y199400D02*
X81150D01*
X78050Y196300D01*
G01X67600Y204800D02*
Y209500D01*
G01X98650Y199400D02*
Y197166D01*
X96584Y195100D01*
G01X84100Y204800D02*
Y207361D01*
X82676Y208785D01*
G01X85599Y183596D02*
Y187598D01*
G01D02*
X89601D01*
G01X81563Y177598D02*
Y181600D01*
G01Y177598D02*
X85565D01*
G01X71870Y257120D02*
X74120D01*
X76170Y259170D01*
G01X93672Y270153D02*
X90780Y273045D01*
Y273800D01*
G01X72300Y261950D02*
Y257550D01*
X71870Y257120D01*
G01X87280Y273800D02*
Y275380D01*
X89400Y277500D01*
Y279300D01*
G01X80300Y259150D02*
Y258100D01*
X78000Y255800D01*
X77527D01*
G01X97016Y257066D02*
Y262185D01*
X94530Y264671D01*
G01X68100Y259300D02*
Y255000D01*
G01X93700Y303100D02*
X97300Y306700D01*
X100850D01*
G01X91600Y344150D02*
X95559D01*
X95670Y344261D01*
G01X76055Y357145D02*
Y354545D01*
X80800Y349800D01*
X92681D01*
X95670Y346811D01*
Y344261D01*
G01X70591Y359309D02*
Y354739D01*
X70593Y354737D01*
G01X71794Y377639D02*
X72844Y378689D01*
X75915D01*
X75917Y378687D01*
G01X75256Y370303D02*
X74749Y370810D01*
X70654D01*
G01X70591Y363149D02*
Y359309D01*
G01X97843Y371207D02*
Y368246D01*
X99128Y366961D01*
G01X76055Y360727D02*
Y357145D01*
G01X79600Y399200D02*
X80891D01*
X81000Y399091D01*
X84274D01*
G01X95223Y388954D02*
Y385704D01*
G01X80000Y406950D02*
Y409452D01*
X79267Y410185D01*
G01X80940Y392665D02*
Y395989D01*
G01X95223Y392454D02*
X93560D01*
X86904Y385798D01*
G01X79164Y426221D02*
X79147D01*
X77176Y424250D01*
X72500D01*
G01X73300Y430500D02*
X77238D01*
X77859Y429879D01*
G01X68250Y417000D02*
X72529D01*
X72533Y416996D01*
G01X105303Y419497D02*
X98462D01*
X96046Y421913D01*
Y423280D01*
G01X96043Y434193D02*
X92752D01*
G01X89400Y470400D02*
X89500Y470500D01*
Y471900D01*
X90850Y473250D01*
X92500D01*
G01X74250Y506500D02*
X77381D01*
X77413Y506468D01*
G01X79519Y513090D02*
X80369Y512240D01*
Y511368D01*
X80394Y511343D01*
Y508831D01*
G01X79519Y517090D02*
Y513090D01*
G01X80394Y508831D02*
X79826Y509399D01*
X77331D01*
X76230Y510500D01*
X74250D01*
G01X80394Y508831D02*
Y504831D01*
G01X77700Y502500D02*
X78393D01*
X80394Y504501D01*
Y504831D01*
G01X88573Y503935D02*
X90034Y505187D01*
X90334D01*
X91147Y506000D01*
X92250D01*
G01X84450Y529300D02*
X88400D01*
X89200Y528500D01*
G01X92250Y518500D02*
X89400D01*
X89200Y518700D01*
G01X92250Y538500D02*
Y534500D01*
G01D02*
Y530500D01*
G01D02*
Y526500D01*
G01Y522500D02*
Y518500D01*
G01Y522500D02*
Y526500D01*
G01D02*
X91000D01*
X89300Y528200D01*
Y528400D01*
X89200Y528500D01*
G01X67670Y531831D02*
Y535931D01*
G01D02*
X68400Y536661D01*
Y540400D01*
X65600Y543200D01*
G01X75600Y518600D02*
Y516400D01*
X74250Y515050D01*
Y514500D01*
G01X81000Y579000D02*
Y582250D01*
G01X95252Y576388D02*
Y571638D01*
G01X74000Y561250D02*
X72750Y560000D01*
X71105D01*
X71000Y559895D01*
X70800D01*
G01X80500Y562750D02*
X77250D01*
G01X80500Y574250D02*
X80150D01*
X77400Y577000D01*
G01X74000Y575750D02*
X71450Y578300D01*
X71400D01*
G01X84000Y574250D02*
X87200D01*
G01X80750Y558500D02*
X80250Y559000D01*
X77400D01*
G01X90500Y587000D02*
Y580100D01*
G01D02*
Y573900D01*
X92762Y571638D01*
X95252D01*
G01X87555Y561085D02*
X85890Y562750D01*
X84000D01*
G01X67800Y572500D02*
X73750D01*
X74000Y572250D01*
G01X80500Y570750D02*
X75500D01*
X74000Y572250D01*
G01X84000Y570750D02*
X80500D01*
G01X87337Y569268D02*
X85855Y570750D01*
X84000D01*
G01X67800Y564500D02*
X73750D01*
X74000Y564750D01*
G01X80500Y566250D02*
X75500D01*
X74000Y564750D01*
G01X80500Y566250D02*
X84000D01*
G01X87200Y565785D02*
X84465D01*
X84000Y566250D01*
G01X81000Y582250D02*
X77500D01*
X77250Y582000D01*
G01X84850Y590300D02*
X84200D01*
X82000Y592500D01*
G01X66000Y601750D02*
Y604800D01*
G01X88000Y610350D02*
Y613600D01*
G01X81000Y589000D02*
Y585750D01*
G01D02*
X80750Y586000D01*
X77250D01*
G01X81500Y634250D02*
X78300D01*
G01Y637750D02*
X81500D01*
G01D02*
X85750Y642000D01*
X86750D01*
G01X79850Y681900D02*
X75800D01*
G01X94950D02*
X90950D01*
G01X94950Y677850D02*
Y681900D01*
G01X69700Y695200D02*
Y690300D01*
G01X89825Y687900D02*
Y692875D01*
G01X75450Y694150D02*
X76450Y695150D01*
Y699150D01*
G01X66700Y713500D02*
X65500Y714700D01*
Y717400D01*
G01X91500Y744900D02*
X92700Y743700D01*
Y727100D01*
X96400Y723400D01*
Y712600D01*
X91450Y707650D01*
G01X85900Y749300D02*
X89300D01*
X89400Y749200D01*
G01X85800Y736400D02*
X89200D01*
X89300Y736300D01*
G01X79250Y719300D02*
Y716050D01*
G01X91800Y719650D02*
Y716100D01*
G01X79550Y740900D02*
Y736650D01*
X79800Y736400D01*
G01D02*
X76384D01*
X74796Y737988D01*
Y740304D01*
X73400Y741700D01*
G01X91500Y744900D02*
Y746700D01*
X93000Y748200D01*
Y763000D01*
X91300Y764700D01*
Y766900D01*
G01X83050Y744900D02*
X91500D01*
G01X83050Y740900D02*
Y744900D01*
G01X74300Y766150D02*
Y769950D01*
G01X83050Y753700D02*
X89500D01*
X89800Y753400D01*
G01X69800Y768900D02*
Y772700D01*
G01X83050Y757900D02*
X86900D01*
G01X85800Y762400D02*
X89400D01*
G01X64900Y776900D02*
Y780500D01*
G01X83050Y766900D02*
X91300D01*
G01X100300Y829400D02*
X91800D01*
X87403Y825003D01*
Y778178D01*
X91300Y774281D01*
Y766900D01*
G01X127746Y-276199D02*
Y-356199D01*
G01D02*
X1310146D01*
G01X127746Y-311699D02*
X1310146D01*
G01X123746Y-260199D02*
G02I-12000J0D01*
G01X118596D02*
G02I-6850J0D01*
G01X111746Y-276199D02*
Y-244199D01*
G01X127746Y-276199D02*
X1310146D01*
G01X122165Y136122D02*
Y142874D01*
G01X104050Y131710D02*
Y128380D01*
X104000Y128330D01*
G01X114364Y126299D02*
Y122054D01*
G01X122165Y142874D02*
Y149626D01*
G01X115413Y142874D02*
X122165D01*
G01D02*
X128917D01*
G01X100900Y177850D02*
Y173800D01*
G01X108224Y164387D02*
Y168429D01*
X108631Y168836D01*
G01X130149Y153543D02*
X134251D01*
G01X107550Y203300D02*
X106200D01*
X103700Y200800D01*
G01X100900Y194150D02*
X101350Y194600D01*
X104100D01*
G01X120700Y211500D02*
X116000D01*
G01X112764Y257066D02*
Y264218D01*
G01X101250Y276300D02*
X105650D01*
X106500Y277150D01*
G01D02*
X109300D01*
X109600Y276850D01*
G01X112732Y268820D02*
Y272786D01*
G01X106400Y312200D02*
X106350D01*
X104400Y310250D01*
Y306750D01*
X104350Y306700D01*
G01X101630Y312236D02*
X101000Y311606D01*
Y310757D01*
X100730Y310487D01*
Y306820D01*
X100850Y306700D01*
G01X108500Y287150D02*
Y284000D01*
G01X107213Y301192D02*
X107077D01*
X105369Y302900D01*
X104250D01*
G01D02*
Y298900D01*
G01D02*
X105000Y298150D01*
X108500D01*
G01X103617Y336265D02*
X106052D01*
X106717Y335600D01*
G01X129189Y324436D02*
X118767Y324467D01*
X117700Y323400D01*
G01X137167Y333265D02*
Y337733D01*
X134100Y340800D01*
X131500D01*
G01X129189Y335436D02*
Y338489D01*
X131500Y340800D01*
G01X126800Y362500D02*
X124314Y360014D01*
X121799D01*
G01X112396Y362064D02*
Y363691D01*
X117761Y369056D01*
G01D02*
X118611Y368206D01*
X122405D01*
X122645Y367966D01*
G01D02*
X122663Y367948D01*
Y364378D01*
X121799Y363514D01*
G01X104372Y378656D02*
X108200D01*
G01X108400Y388450D02*
Y385217D01*
X108453Y385164D01*
G01X115750Y388600D02*
Y384339D01*
X115951Y384138D01*
G01X108400Y391950D02*
X111850D01*
X111950Y392050D01*
G01X104507Y388684D02*
Y384268D01*
X104204Y383965D01*
Y383661D01*
G01X127400Y408350D02*
Y410300D01*
X129500Y412400D01*
G01X116235Y447785D02*
Y444665D01*
G01X115684Y441150D02*
Y444114D01*
X116235Y444665D01*
G01X100079Y423267D02*
X103179D01*
G01X100076Y434180D02*
X103176D01*
G01X115500Y457750D02*
Y454700D01*
G01X111500Y457750D02*
Y454700D01*
G01X103500Y457750D02*
X107500D01*
G01X103500Y454700D02*
Y457750D01*
G01X118351Y574686D02*
X121601D01*
G01X113851D02*
X118351D01*
G01X104461Y571715D02*
X106200Y573454D01*
Y588500D01*
X104400Y590300D01*
G01X98500Y598250D02*
X101250D01*
X102000Y599000D01*
G01X98500Y601750D02*
X101250D01*
X102000Y602500D01*
G01X101750Y595600D02*
Y592500D01*
G01D02*
X101748Y592498D01*
Y585612D01*
G01X112301Y638436D02*
Y640686D01*
X116551Y644936D01*
G01X124051Y647136D02*
Y642436D01*
X125051Y641436D01*
X125581D01*
G01X108801Y638436D02*
Y645686D01*
X109051Y645936D01*
G01X105950Y681900D02*
X109800D01*
G01X127650Y714300D02*
X130900D01*
G01X127650Y710800D02*
X130900D01*
G01X103825Y687900D02*
X107700D01*
X107950Y687650D01*
G01X116150Y714300D02*
Y716450D01*
X115000Y717600D01*
G01X124150Y710800D02*
Y707050D01*
G01X111400Y738300D02*
Y741800D01*
G01Y721800D02*
Y718300D01*
G01X106900Y735550D02*
Y738600D01*
G01Y724550D02*
Y721300D01*
G01X128700Y761300D02*
X132200D01*
G01X128700Y756300D02*
X132200D01*
G01X121750Y775000D02*
Y770750D01*
X119500Y768500D01*
G01X112700Y775300D02*
X113000Y775000D01*
G01D02*
X118250D01*
G01X121500Y881500D02*
X121654Y881654D01*
G01X116000Y881000D02*
X115355Y881645D01*
G01X118500Y881500D02*
X118504Y881504D01*
G01X125000Y881500D02*
X124803Y881697D01*
G01X128000Y880900D02*
G02X127953Y881013I113J113D01*
G01X130700Y880400D02*
G03X131103Y881373I-973J973D01*
G01X115355Y881645D02*
Y887970D01*
G01X121654Y881654D02*
Y887970D01*
G01X118504Y881504D02*
Y887970D01*
G01X124803Y881697D02*
Y887970D01*
G01X127953Y881013D02*
Y887970D01*
G01X131103Y881373D02*
Y887970D01*
G01X149380Y181131D02*
Y176010D01*
G01X138735Y166375D02*
X147965D01*
X149380Y167790D01*
Y170531D01*
G01X134251Y149441D02*
Y153543D01*
G01D02*
Y157645D01*
G01Y153543D02*
X138353D01*
G01X153000Y219500D02*
Y225000D01*
G01X162900Y241040D02*
Y244280D01*
X162910Y244290D01*
G01X134150Y264300D02*
X134120Y264330D01*
Y267630D01*
G01X145300Y302200D02*
Y306400D01*
G01Y302200D02*
Y299300D01*
X140069Y294069D01*
G01D02*
Y286183D01*
G01X135930Y311214D02*
X139286D01*
G01X159935Y335686D02*
X155891Y339730D01*
G01X143000Y342900D02*
X144667Y341233D01*
Y337140D01*
G01X144595Y312861D02*
X144881D01*
X153064Y321044D01*
Y322277D01*
G01X157550Y399100D02*
Y402200D01*
G01X141687Y407034D02*
Y404515D01*
X142608Y403594D01*
G01X155700Y406250D02*
X158795D01*
X158800Y406255D01*
G01X146105Y403610D02*
X145187Y404528D01*
Y407034D01*
G01D02*
Y409181D01*
X145501Y409495D01*
Y411131D01*
G01X151600Y406250D02*
X148745D01*
X146105Y403610D01*
G01X146748Y420306D02*
X150431D01*
G01X146431Y450028D02*
Y445142D01*
X146165Y444876D01*
G01X133000Y457750D02*
Y454700D01*
G01X166077Y447721D02*
X166534Y448178D01*
Y450821D01*
G01X137000Y454700D02*
Y457750D01*
G01X159751Y574886D02*
X161886D01*
X165500Y578500D01*
Y589413D01*
G01X146819Y640420D02*
X149920D01*
X150000Y640500D01*
X150069D01*
G01X146819Y636620D02*
X150280D01*
G01X146801Y648436D02*
X150464D01*
X150600Y648300D01*
G01X146801Y643936D02*
X150264D01*
X150316Y643884D01*
X150409D01*
G01X132400Y738300D02*
X136400D01*
G01X132400Y721800D02*
X136400D01*
G01X161200Y727900D02*
Y723900D01*
G01X150200Y732650D02*
Y729400D01*
G01X153700Y732650D02*
Y729400D01*
G01X161200Y748900D02*
X157700D01*
G01X153700Y744150D02*
X150450D01*
G01X132450Y745200D02*
X135700D01*
G01X150200Y736150D02*
X146450D01*
G01X154000Y783000D02*
Y779000D01*
G01X163950Y753400D02*
X160700D01*
G01X143000Y787750D02*
Y784500D01*
G01X146500Y787750D02*
Y784500D01*
G01X154000Y804000D02*
X150500D01*
G01X146500Y799250D02*
X143250D01*
G01X156750Y808500D02*
X153500D01*
G01X143000Y791250D02*
X139250D01*
G01X146500Y881500D02*
X146851Y881851D01*
G01X143500Y881500D02*
X143701Y881701D01*
G01X140500Y881500D02*
X140551Y881551D01*
G01X137500Y881500D02*
X137402Y881598D01*
G01X159449Y878276D02*
Y887970D01*
G01X135000Y882000D02*
X134252Y882748D01*
Y887970D01*
G01X149400Y880900D02*
G03X150000Y882349I-1449J1449D01*
G01Y887970D01*
G01X137402Y881598D02*
Y887970D01*
G01X140551Y881551D02*
Y887970D01*
G01X143701Y881701D02*
Y887970D01*
G01X146851Y881851D02*
Y887970D01*
G01X173897Y136122D02*
Y142874D01*
G01X181838Y126211D02*
Y122811D01*
X181738Y122711D01*
G01X173897Y142874D02*
Y149626D01*
G01X167145Y142874D02*
X173897D01*
G01D02*
X180649D01*
G01X191018Y196306D02*
Y195282D01*
X193400Y192900D01*
G01D02*
X196018Y195518D01*
Y196306D01*
G01X200300Y196350D02*
Y192000D01*
X197900Y189600D01*
X191800D01*
G01D02*
X188418D01*
X186418Y191600D01*
Y196306D01*
G01X191018Y241354D02*
Y246482D01*
X191000Y246500D01*
G01X202850Y251000D02*
X197550D01*
X197450Y251100D01*
G01X184350Y289472D02*
Y274822D01*
X183900Y274372D01*
G01X180850Y289472D02*
Y285650D01*
G01X179104Y446672D02*
X178415D01*
X176098Y444355D01*
G01X197841Y433892D02*
X197850Y433901D01*
Y437450D01*
G01X179089Y450747D02*
X175912D01*
G01X186675Y453505D02*
X188150Y454980D01*
Y458455D01*
G01X202064Y512946D02*
X187063D01*
X186808Y512691D01*
G01X198223Y509744D02*
X187256D01*
G01X209500Y510250D02*
X208994Y509744D01*
X198223D01*
G01X197500Y577300D02*
X199750Y579550D01*
Y580500D01*
G01X185500Y577300D02*
Y574250D01*
G01X191500Y583250D02*
Y582122D01*
X186698Y577320D01*
X185520D01*
X185500Y577300D01*
G01D02*
X184500Y578300D01*
Y594000D01*
G01X185500Y574250D02*
X189500D01*
G01X197500Y573782D02*
X201500D01*
G01X195500Y601750D02*
X196600D01*
X198600Y599750D01*
G01X195500Y590750D02*
X196600D01*
X198600Y588750D01*
G01X199750Y580500D02*
X197000Y583250D01*
X195500D01*
G01X181371Y598436D02*
Y601636D01*
G01X177871Y598436D02*
Y597029D01*
X179700Y595200D01*
X181000D01*
G01X184500Y594000D02*
Y598379D01*
X187871Y601750D01*
X191500D01*
G01Y590750D02*
X187750D01*
X184500Y594000D01*
G01X193500Y704000D02*
Y700000D01*
G01X182500Y708750D02*
Y705500D01*
G01X186000Y708750D02*
Y705500D01*
G01X182500Y712250D02*
X178750D01*
G01X193500Y725000D02*
X190000D01*
G01X177700Y727900D02*
Y723900D01*
G01Y748900D02*
X181200D01*
G01X184700Y732650D02*
Y729400D01*
G01X186000Y720250D02*
X182750D01*
G01X196250Y729500D02*
X193000D01*
G01X193500Y780500D02*
X190000D01*
G01X170500Y783000D02*
Y779000D01*
G01X193500Y759500D02*
Y755500D01*
G01X182500Y764250D02*
Y761000D01*
G01X186000Y764250D02*
Y761000D01*
G01Y775750D02*
X182750D01*
G01X174950Y753400D02*
X178000D01*
G01X182500Y767750D02*
X178750D01*
G01X170500Y804000D02*
X174000D01*
G01X177500Y787750D02*
Y784500D01*
G01X167750Y808500D02*
X170800D01*
G01X196250Y785000D02*
X193000D01*
G01X168898Y878200D02*
Y887970D01*
G01X197244D02*
Y879851D01*
X195669Y878276D01*
G01X187796Y887970D02*
Y880496D01*
X185500Y878200D01*
G01X178347Y887970D02*
Y879852D01*
X176771Y878276D01*
G01X235713Y63589D02*
X228121D01*
G01X235713Y73589D02*
X227531D01*
X226533Y72591D01*
G01X235713Y83589D02*
X227989D01*
G01X213607Y138175D02*
X218725D01*
G01X226729Y145011D02*
Y144349D01*
X223750Y141370D01*
G01X224600Y123550D02*
X223365D01*
X221574Y121759D01*
Y115015D01*
X223739Y112850D01*
X224900D01*
G01X224600Y123550D02*
X227770D01*
X228007Y123787D01*
G01X207369Y151234D02*
X210447D01*
X210478Y151203D01*
G01X228800Y160600D02*
X233507D01*
X233537Y160630D01*
G01X217800Y160600D02*
X214300D01*
X212000Y158300D01*
G01X216469Y168525D02*
X217800Y167194D01*
Y160600D01*
G01X222854Y152511D02*
X217789D01*
X212000Y158300D01*
G01X205200Y196350D02*
Y192783D01*
X205013Y192596D01*
G01X216469Y179525D02*
X210484D01*
G01X205200Y199850D02*
X209450D01*
X214794Y205194D01*
Y212100D01*
G01X205200Y199850D02*
X206018Y200668D01*
Y209858D01*
G01X200300Y196350D02*
X200950D01*
X204450Y199850D01*
X205200D01*
G01X202850Y251000D02*
Y253700D01*
X205250Y256100D01*
X212794D01*
X214794Y254100D01*
Y212100D01*
G01X205950Y446000D02*
Y443650D01*
X205200Y442900D01*
G01X216950Y446000D02*
X220800D01*
G01X220897Y441833D02*
X220969Y441761D01*
Y438422D01*
G01X213250Y478000D02*
Y476250D01*
X216000Y473500D01*
G01D02*
X218387D01*
X219700Y472187D01*
X219763D01*
G01X223250Y469000D02*
Y478842D01*
X218906Y483186D01*
G01X223250Y469000D02*
Y465000D01*
G01X231200Y509500D02*
X230450Y510250D01*
X226000D01*
G01X216873Y516458D02*
X214165Y513750D01*
X213500D01*
G01X226000Y510250D02*
X222500D01*
G01X219300Y508700D02*
X220850Y510250D01*
X222500D01*
G01X209500Y517250D02*
X206368D01*
X202064Y512946D01*
G01X213500Y510250D02*
X209500D01*
G01X222500Y513750D02*
X219050D01*
X217800Y512500D01*
G01X218906Y483186D02*
X218900D01*
X218514Y482800D01*
X217300D01*
X216100Y484000D01*
X213250D01*
G01Y490000D02*
Y486000D01*
G01D02*
Y484000D01*
G01D02*
Y482000D01*
G01X209750Y517500D02*
X209500Y517250D01*
G01D02*
Y513750D01*
G01X226000D02*
X222500D01*
G01X221000Y518250D02*
X219050D01*
X217500Y519800D01*
G01X225000Y518350D02*
X221100D01*
X221000Y518250D01*
G01Y529250D02*
X225000D01*
G01X214000Y530000D02*
X214750Y529250D01*
X217500D01*
G01D02*
X221000D01*
G01X213250Y517500D02*
X214650Y518900D01*
X214922D01*
X215822Y519800D01*
X217500D01*
G01X229000Y518350D02*
Y515000D01*
X229200Y514800D01*
G01X229000Y529250D02*
X236850Y537100D01*
X250100D01*
G01X213250Y534500D02*
Y538500D01*
G01D02*
Y542500D01*
G01X216300Y546350D02*
X216150Y546500D01*
X213250D01*
G01D02*
Y550500D01*
G01Y546500D02*
Y542500D01*
G01X222620Y568020D02*
X216957D01*
X216278Y567341D01*
G01X226200Y575912D02*
X223688D01*
X222300Y577300D01*
G01X201500Y573782D02*
Y574522D01*
X203250Y576272D01*
Y580500D01*
G01X213250Y554500D02*
X215155D01*
X216563Y555908D01*
G01X213250Y570500D02*
Y578250D01*
X211000Y580500D01*
X203250D01*
G01X213250Y570500D02*
Y554500D01*
G01D02*
Y550500D01*
G01X210000Y704000D02*
Y700000D01*
G01X217000Y708750D02*
Y705500D01*
G01X210000Y725000D02*
X213500D01*
G01X207250Y729500D02*
X210300D01*
G01X210000Y780500D02*
X213500D01*
G01X210000Y759500D02*
Y755500D01*
G01X217000Y764250D02*
Y761000D01*
G01X207250Y785000D02*
X210300D01*
G01X235040Y887970D02*
Y879852D01*
X233464Y878276D01*
G01X225591Y887970D02*
Y879851D01*
X227166Y878276D01*
G01X222441Y887970D02*
Y879851D01*
X220866Y878276D01*
G01X212992Y887970D02*
Y879851D01*
X214567Y878276D01*
G01X209843Y887970D02*
Y879852D01*
X208267Y878276D01*
G01X200394Y887970D02*
Y879851D01*
X201969Y878276D01*
G01X250181Y73589D02*
X258159D01*
G01X250181Y63589D02*
X257851D01*
G01X250181Y83589D02*
X257769D01*
G01X254000Y131500D02*
X254600Y130900D01*
X259500D01*
G01X269750Y126000D02*
X264400D01*
X259500Y130900D01*
G01X239600Y146150D02*
Y142900D01*
G01X241231Y245001D02*
Y238869D01*
G01X244300Y233750D02*
X247500D01*
G01X236331Y230330D02*
Y227631D01*
X236300Y227600D01*
Y227280D01*
G01X240400Y230350D02*
X244200D01*
X244300Y230250D01*
G01D02*
Y226700D01*
G01X270700Y304000D02*
X265000D01*
X263000Y302000D01*
Y296850D01*
G01X261479Y338640D02*
X257340D01*
G01X248160Y343140D02*
X248350Y342950D01*
Y339700D01*
G01X262900Y433850D02*
Y438700D01*
G01X249950Y443300D02*
X248950D01*
X246375Y440725D01*
G01D02*
X244900Y439250D01*
Y434350D01*
G01X260950Y443300D02*
X265100D01*
G01X255487Y512454D02*
Y512720D01*
X256465Y513698D01*
X259857D01*
G01X243200Y508000D02*
X241920Y509280D01*
X241339D01*
X241119Y509500D01*
X238800D01*
G01D02*
X236100Y512200D01*
Y517100D01*
G01X253500Y525750D02*
X249713D01*
X249700Y525737D01*
G01D02*
X249000D01*
X248987Y525750D01*
X246500D01*
G01Y521250D02*
X249700D01*
G01D02*
X253500D01*
G01X257500Y525750D02*
X260172D01*
X262222Y523700D01*
X262327D01*
X264500Y521527D01*
Y521309D01*
G01X258000Y521250D02*
X261100D01*
G01X252238Y577665D02*
Y574238D01*
G01X252270Y581381D02*
X250119D01*
X248500Y583000D01*
G01X263488Y578165D02*
X256238D01*
X255738Y577665D01*
G01Y574238D02*
Y577665D01*
G01X241550Y643400D02*
X238100D01*
G01X247717Y633233D02*
X245300Y635650D01*
G01X237300D02*
X241300D01*
G01X248000Y629400D02*
X242600D01*
X241300Y630700D01*
Y635650D01*
G01X236000Y656000D02*
X283500D01*
X285550Y653950D01*
Y643900D01*
G01X266906Y772148D02*
Y775531D01*
G01X263181Y772181D02*
X263500Y771862D01*
Y769500D01*
X264352Y768648D01*
X266906D01*
G01D02*
X267946Y767608D01*
Y755880D01*
X268193Y755633D01*
G01X260237Y887970D02*
Y879850D01*
X261811Y878276D01*
G01X257087Y887970D02*
Y879852D01*
X255511Y878276D01*
G01X247638Y887970D02*
Y879850D01*
X249212Y878276D01*
G01X290000Y141100D02*
Y148140D01*
X288790Y149350D01*
G01X277500Y133750D02*
X274250D01*
G01X798061Y-6439D02*
X795200Y-9300D01*
X753703D01*
X751165Y-11838D01*
X728538D01*
X725348Y-8648D01*
X497752D01*
X470279Y18825D01*
Y41071D01*
X449068Y62282D01*
Y62285D01*
X448910Y62443D01*
Y83720D01*
X417830Y114800D01*
X343022D01*
X324072Y133750D01*
X285250D01*
G01X281500D02*
X285250D01*
G01X281250Y145500D02*
X282960D01*
X284660Y143800D01*
X286000D01*
G01X281100Y208550D02*
X297850Y225300D01*
X331850D01*
X335150Y222000D01*
G01X277800Y208500D02*
X277850Y208550D01*
X281100D01*
G01X267300Y296750D02*
Y300600D01*
G01X272900Y296750D02*
Y301800D01*
X270700Y304000D01*
G01X267300Y293250D02*
X268250D01*
X271300Y296300D01*
X272450D01*
X272900Y296750D01*
G01X297090Y311350D02*
X293940Y308200D01*
X274900D01*
X270700Y304000D01*
G01X299639Y332651D02*
X302749D01*
G01X273229Y328640D02*
X267300D01*
G01X291479Y354640D02*
Y349806D01*
X293229Y348056D01*
Y343640D01*
G01X297729Y358390D02*
Y362571D01*
G01Y354890D02*
Y351029D01*
G01Y354890D02*
X291729D01*
X291479Y354640D01*
G01X287550Y465000D02*
X284200D01*
G01X272850Y467300D02*
X275900D01*
G01X284200Y471050D02*
X279650D01*
X275900Y467300D01*
G01X285800Y460810D02*
X288510D01*
X291050Y463350D01*
Y465000D01*
G01X282500Y491750D02*
X283326D01*
X285776Y489300D01*
G01X272860Y489147D02*
Y488643D01*
X272850Y488633D01*
Y485800D01*
G01X297738Y578165D02*
X300835D01*
G01X319150Y542500D02*
Y549580D01*
X307280Y561450D01*
X291000D01*
G01X297738Y583165D02*
X300835D01*
G01X297738Y588665D02*
X301000D01*
G01X283488Y593165D02*
X288835D01*
G01X278050Y634900D02*
X281700D01*
G01X278050Y638900D02*
X281800D01*
G01X276300Y651700D02*
X281100D01*
G01X290200Y706300D02*
X286900D01*
X285500Y704900D01*
G01X278406Y719648D02*
Y716531D01*
G01X274406Y719648D02*
Y716598D01*
G01X303300Y772050D02*
Y773000D01*
X300600Y775700D01*
X298400D01*
G01X282378Y775431D02*
X282478Y775331D01*
Y772181D01*
G01X286500Y772250D02*
X282547D01*
X282478Y772181D01*
G01X268900Y756340D02*
X268193Y755633D01*
G01X282284Y887970D02*
Y883084D01*
X281557Y882357D01*
Y879125D01*
X280708Y878276D01*
G01X272835Y887970D02*
Y879851D01*
X274410Y878276D01*
G01X269685Y887970D02*
Y879851D01*
X268110Y878276D01*
G01X307834Y244932D02*
Y237966D01*
G01X311250Y221900D02*
X311052Y221702D01*
X307300D01*
G01X328842Y295900D02*
X329708Y295034D01*
Y292248D01*
G01X328842Y300042D02*
Y295900D01*
G01X320662Y297040D02*
X321302Y296400D01*
X324842D01*
X325342Y295900D01*
G01X312900Y290450D02*
X312532Y290818D01*
Y293550D01*
G01X321300Y301500D02*
X320662Y300862D01*
Y297040D01*
G01X333208Y292248D02*
X332834Y291874D01*
Y283490D01*
G01X337410Y295910D02*
X336010D01*
X333208Y293108D01*
Y292248D01*
G01X334200Y299600D02*
X335720D01*
X337410Y297910D01*
Y295910D01*
G01X313200Y299900D02*
X322400Y309100D01*
X331800D01*
G01X326041Y329282D02*
X327314D01*
X327916Y328680D01*
X329241D01*
G01X312239Y326201D02*
X316420Y330382D01*
Y331830D01*
G01X329241Y325180D02*
X326380D01*
X326200Y325000D01*
X326041D01*
G01X310839Y340501D02*
Y344339D01*
G01X315300Y340750D02*
Y344500D01*
G01X301929Y354990D02*
Y351100D01*
G01X301500Y487050D02*
Y489000D01*
X303500Y491000D01*
G01X301500Y483550D02*
X305500D01*
G01X319150Y538300D02*
X320900D01*
X322700Y536500D01*
G01D02*
X320700Y534500D01*
X319250D01*
G01X312500Y716500D02*
Y712400D01*
G01X314500Y719750D02*
Y718500D01*
X312500Y716500D01*
G01X332677Y887970D02*
Y879851D01*
X331102Y878276D01*
G01X323229Y887970D02*
Y879850D01*
X324803Y878276D01*
G01X320079Y887970D02*
Y879852D01*
X318503Y878276D01*
G01X310630Y887970D02*
Y880070D01*
X312500Y878200D01*
G01X359132Y326647D02*
Y329706D01*
X356588Y332250D01*
X355200D01*
G01X342900Y730900D02*
Y727200D01*
G01X361024Y887970D02*
Y879851D01*
X362599Y878276D01*
G01X357874Y887970D02*
Y879851D01*
X356299Y878276D01*
G01X348426Y887970D02*
Y879850D01*
X350000Y878276D01*
G01X345276Y887970D02*
Y879852D01*
X343700Y878276D01*
G01X335827Y887970D02*
Y879851D01*
X337402Y878276D01*
G01X395670Y887970D02*
Y879850D01*
X397244Y878276D01*
G01X392520Y887970D02*
Y879852D01*
X390944Y878276D01*
G01X383071Y887970D02*
Y879851D01*
X384646Y878276D01*
G01X370473Y887970D02*
Y878227D01*
X370500Y878200D01*
G01X477466Y186270D02*
X472791D01*
X471902Y185381D01*
X441981D01*
X433400Y176800D01*
G01X430315Y887970D02*
Y879850D01*
X431889Y878276D01*
G01X420866Y887970D02*
Y879851D01*
X422441Y878276D01*
G01X417717Y887970D02*
Y879852D01*
X416141Y878276D01*
G01X408268Y887970D02*
Y879851D01*
X409843Y878276D01*
G01X405118Y887970D02*
Y879851D01*
X403543Y878276D01*
G01X461900Y65450D02*
Y62300D01*
G01X466000Y65450D02*
Y62300D01*
G01X457700Y65450D02*
Y62300D01*
G01X455800Y106450D02*
Y110200D01*
G01X459071Y122291D02*
X454871D01*
G01X455942Y114254D02*
X452600D01*
G01X461395Y137332D02*
X458968D01*
X457400Y138900D01*
G01X459071Y118791D02*
X454926D01*
G01X456910Y153259D02*
X452541D01*
X452500Y153300D01*
G01X460099Y210989D02*
X458489D01*
X455800Y208300D01*
G01X464389Y324210D02*
Y321510D01*
X461389Y318510D01*
G01X464086Y340500D02*
X471976Y348390D01*
X493640D01*
X529580Y384330D01*
X558531D01*
G01X459200Y372550D02*
Y369300D01*
G01X462700Y372550D02*
Y369300D01*
G01X459200Y376050D02*
X455450D01*
G01X470200Y388800D02*
X466700D01*
G01X462700Y384050D02*
X459450D01*
G01X439764Y887970D02*
Y879851D01*
X438189Y878276D01*
G01X483210Y13180D02*
X483220Y26720D01*
G01D02*
X483250Y26750D01*
Y49880D01*
G01X470200Y65450D02*
Y62300D01*
G01X478400Y65450D02*
Y62300D01*
G01X474400Y65450D02*
Y62300D01*
G01X483250Y59480D02*
Y73380D01*
G01Y49880D02*
Y59480D01*
G01X496782Y130548D02*
Y134315D01*
G01X478800Y122750D02*
X475080D01*
X474990Y122660D01*
G01X491528Y159142D02*
Y160128D01*
X494300Y162900D01*
X494800D01*
G01X494350Y166000D02*
Y163350D01*
X494800Y162900D01*
G01X498400Y198450D02*
Y194600D01*
X498000Y194200D01*
G01X471681Y306462D02*
Y285218D01*
X473231Y283668D01*
Y274930D01*
G01X505477Y295490D02*
X501867D01*
G01X478719Y308208D02*
X476965Y309962D01*
X471681D01*
G01X485389Y324210D02*
Y312913D01*
X486219Y312083D01*
G01X493909Y324041D02*
X493740Y324210D01*
X485389D01*
G01X493909Y324041D02*
X500198D01*
G01X485389Y324210D02*
X475389D01*
G01X478719Y315958D02*
Y319279D01*
X478728Y319288D01*
Y319528D01*
X480532Y321332D01*
G01X486700Y367800D02*
Y363800D01*
G01X470200Y367800D02*
Y363800D01*
G01X493700Y372550D02*
Y369300D01*
G01X486700Y388800D02*
X490200D01*
G01X472950Y393300D02*
X469700D01*
G01X483950D02*
X487000D01*
G01X487906Y771648D02*
Y768598D01*
G01X491906Y771648D02*
Y768531D01*
G01X480406Y820648D02*
Y816644D01*
X485300Y811750D01*
G01X480406Y824148D02*
Y827531D01*
G01X495878Y827431D02*
X495978Y827331D01*
Y824181D01*
G01X500100Y824150D02*
X496009D01*
X495978Y824181D01*
G01X480406Y820648D02*
X477206D01*
G01X522646Y-276199D02*
Y-356199D01*
G01X507861Y134154D02*
Y130716D01*
X507692Y130547D01*
G01X534875Y163463D02*
Y166525D01*
X534000Y167400D01*
G01X530050Y165815D02*
X531635Y167400D01*
X534000D01*
G01X505528Y159142D02*
Y164372D01*
X505100Y164800D01*
G01X508550Y186500D02*
X512600D01*
G01X517599Y233487D02*
Y229658D01*
G01X522899Y233487D02*
X517599D01*
G01X531232Y233474D02*
Y229927D01*
G01X534526Y248913D02*
Y243721D01*
X534481Y243676D01*
G01X542120Y215055D02*
X541759Y214694D01*
X532642D01*
X531742Y215594D01*
G01X524177Y291190D02*
Y289480D01*
X525881Y287776D01*
G01X518277Y293740D02*
Y288680D01*
G01X532921Y294567D02*
Y298436D01*
G01X513909Y339041D02*
X510509D01*
X507809Y336341D01*
G01X525409Y332291D02*
X523759D01*
X522209Y333841D01*
G01X525409Y320791D02*
X524759D01*
X522409Y318441D01*
G01X533779Y336979D02*
X537121D01*
X539507Y334593D01*
Y330787D01*
G01X539450Y322166D02*
Y319150D01*
X535891Y315591D01*
X532499D01*
G01X533779Y336979D02*
X525347D01*
G01X532499Y315591D02*
X516209D01*
X512100Y319700D01*
G01X527293Y345998D02*
X529126Y344165D01*
Y342336D01*
G01X525850Y340500D02*
Y344555D01*
X527293Y345998D01*
G01X528100Y771550D02*
Y767300D01*
G01X529700Y829700D02*
Y831400D01*
X533800Y835500D01*
G01X552800Y140800D02*
X552750D01*
X550750Y138800D01*
Y137597D01*
G01X562603Y140881D02*
X561720Y139998D01*
Y136909D01*
G01X565690Y133480D02*
X565149D01*
X561720Y136909D01*
G01X565690Y133480D02*
X569700D01*
G01X567200Y161250D02*
X571400D01*
G01X546800Y163450D02*
X548700Y161550D01*
X550400D01*
G01X570100Y205750D02*
X562850D01*
X562833Y205767D01*
X561567D01*
G01X541446Y222562D02*
X542120Y221888D01*
Y218555D01*
G01Y215055D02*
X545539D01*
X546494Y216010D01*
G01X541681Y294526D02*
Y297976D01*
G01X554400Y339350D02*
Y335900D01*
G01X561781Y342980D02*
Y346281D01*
G01X539507Y330787D02*
Y322223D01*
X539450Y322166D01*
G01X550731Y375080D02*
Y380269D01*
X550000Y381000D01*
G01X563531Y384080D02*
Y376830D01*
G01Y384080D02*
X559973Y387638D01*
G01D02*
X568368D01*
X580830Y400100D01*
X636150D01*
G01X567323Y887970D02*
Y879851D01*
X568898Y878276D01*
G01X564174Y887970D02*
Y879852D01*
X562598Y878276D01*
G01X554725Y887970D02*
Y879851D01*
X556300Y878276D01*
G01X551575Y887970D02*
Y879851D01*
X550000Y878276D01*
G01X542126Y887970D02*
Y880074D01*
X544000Y878200D01*
G01X579811Y179500D02*
Y171767D01*
X580865Y170713D01*
Y162565D01*
X579450Y161150D01*
X575600D01*
G01X571400Y161250D02*
X575500D01*
X575600Y161150D01*
G01X582400Y209500D02*
X590300Y201600D01*
Y167522D01*
X617711Y140111D01*
Y133331D01*
G01X603000Y190710D02*
Y207650D01*
X595342Y215308D01*
X593213D01*
G01X603363Y220508D02*
X598163D01*
X597813Y220858D01*
G01X587100Y234800D02*
X585364Y233064D01*
Y232969D01*
X580178D01*
G01X604170Y334090D02*
Y337900D01*
G01X576800Y375000D02*
Y369200D01*
G01X603478Y366212D02*
Y371178D01*
X603500Y371200D01*
G01X597522Y356988D02*
Y352222D01*
X597500Y352200D01*
Y352050D01*
G01X601969Y887970D02*
Y879852D01*
X600393Y878276D01*
G01X592520Y887970D02*
Y879851D01*
X594095Y878276D01*
G01X589371Y887970D02*
Y879852D01*
X587795Y878276D01*
G01X579922Y887970D02*
Y879851D01*
X581497Y878276D01*
G01X576772Y887970D02*
Y879851D01*
X575197Y878276D01*
G01X617711Y133331D02*
X613709D01*
G01D02*
X609901D01*
X608089Y131519D01*
G01X606808Y205137D02*
Y210908D01*
X607700Y211800D01*
G01X612113Y213608D02*
Y218087D01*
X608800Y221400D01*
G01X619363Y228358D02*
Y225108D01*
G01X623363Y228358D02*
Y225108D01*
G01X627363Y228358D02*
Y224358D01*
G01X625613Y238108D02*
X633692D01*
X637300Y234500D01*
G01X608450Y344200D02*
X609100D01*
X611000Y346100D01*
X618000D01*
X618680Y346780D01*
G01X632000Y320850D02*
X635350D01*
G01X609500Y364363D02*
Y360717D01*
G01X627500Y375850D02*
Y374000D01*
X626500Y373000D01*
Y372521D01*
X626458D01*
G01X609500Y357133D02*
Y360717D01*
G01X623000Y379350D02*
Y382500D01*
G01X617000Y379350D02*
Y382500D01*
G01X663250Y376600D02*
Y381750D01*
X655500Y389500D01*
X632000D01*
X629850Y387350D01*
X627500D01*
G01X623000Y390350D02*
X617000D01*
G01D02*
X609000D01*
G01X636150Y400100D02*
X700900D01*
X724500Y376500D01*
X909100D01*
X912800Y372800D01*
Y361300D01*
X910000Y358500D01*
G01X630315Y887970D02*
Y879851D01*
X631890Y878276D01*
G01X627166Y887970D02*
Y879852D01*
X625590Y878276D01*
G01X617717Y887970D02*
Y879851D01*
X619292Y878276D01*
G01X614567Y887970D02*
Y879851D01*
X612992Y878276D01*
G01X605119Y887970D02*
Y879850D01*
X606693Y878276D01*
G01X660146Y-276199D02*
Y-356199D01*
G01X670006Y204942D02*
Y209652D01*
X671124Y210770D01*
G01X656006Y204942D02*
Y212994D01*
X655500Y213500D01*
G01X652250Y340100D02*
X652254Y340096D01*
Y336353D01*
G01X663250Y340100D02*
Y333943D01*
X661240Y331933D01*
X646128D01*
X643000Y335061D01*
Y343000D01*
G01X665031Y358894D02*
X668379Y355546D01*
Y342379D01*
X666100Y340100D01*
X663250D01*
G01X652250Y376600D02*
Y379750D01*
X653000Y380500D01*
G01X663250Y376600D02*
X665031Y374819D01*
Y358894D01*
G01D02*
X663963D01*
X662600Y357531D01*
X658569D01*
X658500Y357600D01*
G01X651900Y814500D02*
Y817500D01*
X653500Y819100D01*
G01X664961Y887970D02*
Y879851D01*
X666536Y878276D01*
G01X661811Y887970D02*
Y879851D01*
X660236Y878276D01*
G01X652363Y887970D02*
Y879837D01*
X654000Y878200D01*
G01X639764Y887970D02*
Y880536D01*
X642200Y878100D01*
Y877900D01*
G01X684006Y204942D02*
Y209568D01*
X685115Y210677D01*
G01X699607Y887970D02*
Y882807D01*
X698031Y881231D01*
Y878276D01*
G01X690158Y887970D02*
Y879851D01*
X691733Y878276D01*
G01X687008Y887970D02*
Y879851D01*
X685433Y878276D01*
G01X677560Y887970D02*
Y879850D01*
X679134Y878276D01*
G01X674410Y887970D02*
Y879852D01*
X672834Y878276D01*
G01X736308Y-7483D02*
Y-7462D01*
X733382Y-4536D01*
Y-3869D01*
G01X724018Y5719D02*
X722463Y4164D01*
Y2380D01*
G01X718302Y3274D02*
X719196Y2380D01*
X722463D01*
G01X738850Y20300D02*
X735600D01*
X735186Y20714D01*
G01X736500Y24250D02*
X735186Y22936D01*
Y20714D01*
G01X707051Y12174D02*
X707815D01*
X710605Y14964D01*
X717255D01*
G01D02*
Y18354D01*
X713375Y22234D01*
Y24452D01*
G01X738384Y8232D02*
X739300Y9148D01*
Y12522D01*
X741828Y15050D01*
X742700D01*
G01X721690Y53340D02*
X720840Y54190D01*
Y56390D01*
G01X742290Y68550D02*
Y67820D01*
X738380Y63910D01*
G01X723200Y42300D02*
Y42400D01*
X723500Y42700D01*
Y51240D01*
X724570Y52310D01*
Y56060D01*
X724890Y56380D01*
G01X717750Y64000D02*
X725600D01*
X727490Y62110D01*
Y58342D01*
X725528Y56380D01*
X724890D01*
G01X738850Y114020D02*
X741410D01*
X743490Y111940D01*
G01X738830Y109410D02*
X740960D01*
X743490Y111940D01*
G01X734252Y887970D02*
Y879851D01*
X735827Y878276D01*
G01X731103Y887970D02*
Y879852D01*
X729527Y878276D01*
G01X721654Y887970D02*
Y879546D01*
X723000Y878200D01*
G01X767650Y26200D02*
X769600D01*
X771600Y24200D01*
G01X743250Y28640D02*
Y21200D01*
X742350Y20300D01*
G01X742700Y15050D02*
Y19950D01*
X742350Y20300D01*
G01X747250Y48375D02*
Y44550D01*
X747000Y44300D01*
G01X762250Y48375D02*
Y44650D01*
G01X753750Y64000D02*
X750790D01*
X750130Y63340D01*
G01X752550Y53800D02*
X748300D01*
G01X770950Y74000D02*
X774850D01*
G01X770950D02*
Y65250D01*
X772000Y64200D01*
G01X757850Y98800D02*
X755700D01*
X753500Y96600D01*
G01X757850Y94700D02*
X755400D01*
X753500Y96600D01*
G01X769400Y107650D02*
Y111900D01*
G01X757700Y75900D02*
X755700Y77900D01*
Y79100D01*
G01D02*
Y80150D01*
X757850Y82300D01*
G01Y90600D02*
Y86500D01*
G01Y102900D02*
X753700D01*
G01X765300Y107650D02*
X762600D01*
X760950Y109300D01*
G01X757850Y86500D02*
X754700D01*
X749800Y91400D01*
G01X765450Y125300D02*
X763900D01*
X762400Y126800D01*
Y127600D01*
G01D02*
Y128200D01*
X763600Y129400D01*
X765450D01*
G01X757450Y112800D02*
X755400D01*
X753500Y110900D01*
G01X757450Y109300D02*
X755100D01*
X753500Y110900D01*
G01X760950Y109300D02*
Y112800D01*
G01D02*
X765000D01*
G01X765450Y133500D02*
Y140750D01*
X767500Y142800D01*
X776950D01*
X781100Y138650D01*
G01X765450Y133500D02*
X763160D01*
X758600Y128940D01*
Y123550D01*
X760950Y121200D01*
X765450D01*
G01X772048Y887970D02*
Y879851D01*
X773623Y878276D01*
G01X768898Y887970D02*
Y879851D01*
X767323Y878276D01*
G01X759449Y887970D02*
Y879851D01*
X761024Y878276D01*
G01X756300Y887970D02*
Y879852D01*
X754724Y878276D01*
G01X746851Y887970D02*
Y879851D01*
X748426Y878276D01*
G01X743701Y887970D02*
Y879851D01*
X742126Y878276D01*
G01X775146Y-276199D02*
Y-356199D01*
G01X838300Y2000D02*
X829800Y-6500D01*
X798122D01*
X798061Y-6439D01*
G01X794900Y1100D02*
Y-3278D01*
X798061Y-6439D01*
G01X791800Y29350D02*
X788550D01*
G01X806152Y51692D02*
X811774Y57314D01*
Y66612D01*
X812424Y67618D01*
X820465Y75659D01*
Y83760D01*
X827810Y91105D01*
Y102980D01*
X827860Y103030D01*
Y105580D01*
X827810Y105630D01*
G01X794850Y74200D02*
X791300D01*
G01D02*
X787750D01*
X787650Y74100D01*
G01X802850Y106300D02*
X799600D01*
X797800Y104500D01*
G01X802850Y102800D02*
X799500D01*
X797800Y104500D01*
G01X806350Y102800D02*
Y106300D01*
G01X810000Y109400D02*
X806900Y106300D01*
X806350D01*
G01X773550Y135200D02*
Y137950D01*
X773900Y138300D01*
G01X791200Y125300D02*
X790800Y125700D01*
Y138500D01*
X789300Y140000D01*
X782450D01*
X781100Y138650D01*
G01X806693Y887970D02*
Y879851D01*
X805118Y878276D01*
G01X797245Y887970D02*
Y879850D01*
X798819Y878276D01*
G01X794095Y887970D02*
Y879852D01*
X792519Y878276D01*
G01X784646Y887970D02*
Y879851D01*
X786221Y878276D01*
G01X781497Y887970D02*
Y879852D01*
X779921Y878276D01*
G01X815500Y17050D02*
Y14500D01*
X813900Y12900D01*
G01X824450Y67775D02*
X831125D01*
G01X810250Y82400D02*
Y77250D01*
X809000Y76000D01*
G01X810250Y90600D02*
X817000D01*
X819000Y92600D01*
Y97100D01*
G01X812163Y118898D02*
Y111563D01*
X810000Y109400D01*
G01X835040Y887970D02*
Y879851D01*
X836615Y878276D01*
G01X819292Y887970D02*
Y878908D01*
X820000Y878200D01*
G01X809843Y887970D02*
Y879851D01*
X811418Y878276D01*
G01X846131Y5499D02*
Y8231D01*
X847000Y9100D01*
G01X851100D02*
X854400Y12400D01*
Y14250D01*
G01X855489Y9811D02*
X855578Y9900D01*
X855622D01*
X857800Y12078D01*
Y13798D01*
X858252Y14250D01*
G01X859300Y9900D02*
X860800Y11400D01*
Y12048D01*
X861752Y13000D01*
Y14250D01*
G01X874300Y18875D02*
Y15675D01*
X873250Y14625D01*
G01X861750Y32000D02*
X858500D01*
G01X861750Y40000D02*
X858500D01*
G01X875000Y31000D02*
X871500D01*
X871497Y31003D01*
X869468D01*
X869447Y31024D01*
G01X861750Y28000D02*
X858500D01*
G01X858252Y17750D02*
X861752D01*
G01X853700Y25500D02*
X854700Y24500D01*
G01X858100Y21400D02*
X857800D01*
X854700Y24500D01*
G01X858100Y21400D02*
X858252Y21248D01*
Y17750D01*
G01X861750Y36000D02*
X858500D01*
G01X851870Y52160D02*
X853430D01*
X854500Y51090D01*
Y49250D01*
G01X862250Y48500D02*
X860600D01*
X859200Y47100D01*
G01X854500Y45750D02*
X851302D01*
X851300Y45748D01*
G01X862083Y44034D02*
X859534D01*
X859000Y43500D01*
G01X862250Y52800D02*
X859400D01*
X858800Y52200D01*
G01X857406Y748648D02*
Y745598D01*
G01X861406Y748648D02*
Y745531D01*
G01X867352Y741450D02*
X865487D01*
X861406Y745531D01*
G01X849906Y801148D02*
Y804531D01*
G01X865478Y801181D02*
Y804331D01*
X865378Y804431D01*
G01X870900Y808850D02*
Y812104D01*
G01X849906Y797648D02*
X856554Y791000D01*
X859000D01*
G01X846706Y797648D02*
X849906D01*
G01X857087Y887970D02*
Y879287D01*
X856000Y878200D01*
G01X847638Y887970D02*
Y879851D01*
X849213Y878276D01*
G01X844489Y887970D02*
Y879852D01*
X842913Y878276D01*
G01X896000Y6250D02*
X895850D01*
X892745Y9355D01*
Y9681D01*
G01X896000Y2750D02*
X898164D01*
X899769Y4355D01*
G01X891301Y13127D02*
Y11125D01*
X892745Y9681D01*
G01X900522Y16716D02*
X902440D01*
X904262Y14894D01*
G01X896500Y9500D02*
Y13250D01*
G01X886520Y13252D02*
Y11127D01*
X888474Y9173D01*
G01X900522Y13216D02*
X902262D01*
X903184Y12294D01*
X905230D01*
X911616Y5908D01*
G01X900522Y13216D02*
X900200Y12894D01*
Y9600D01*
G01X878800Y52850D02*
Y49600D01*
G01X908250Y48500D02*
X907750Y49000D01*
Y51750D01*
G01X894110Y49250D02*
X891860Y51500D01*
X891150D01*
G01X892900Y57935D02*
Y55008D01*
X895080Y52828D01*
G01X895000Y46000D02*
X901000D01*
X902000Y45000D01*
X904750D01*
G01Y48500D02*
Y45000D01*
G01X900501Y48705D02*
X904179D01*
X904384Y48500D01*
X904750D01*
G01X887650Y51500D02*
X884500D01*
X883700Y50700D01*
G01X885300Y57150D02*
X887650Y54800D01*
Y51500D01*
G01X903750Y341600D02*
X906100D01*
X908900Y344400D01*
Y347100D01*
X908700Y347300D01*
G01X905500Y334750D02*
X906250D01*
X909500Y338000D01*
G01X905500Y331250D02*
X911750D01*
X913500Y333000D01*
Y349000D01*
X912000Y350500D01*
G01X903750Y363000D02*
X904300D01*
X907500Y366200D01*
Y368000D01*
G01X903750Y354000D02*
X909000D01*
Y353600D01*
G01X912000Y350500D02*
X911500Y350000D01*
X903750D01*
G01X910000Y358500D02*
X903750D01*
G01Y350000D02*
Y345600D01*
G01X897600Y748550D02*
X900999D01*
G01X883600Y739800D02*
Y741800D01*
X885400Y743600D01*
G01X886420Y808230D02*
Y811256D01*
X885137Y812539D01*
G01D02*
Y816563D01*
X885167Y816593D01*
G01X908250Y41000D02*
X912000D01*
G01X927250Y31450D02*
Y27270D01*
G01X908250Y37000D02*
X911800D01*
G01X938000Y26750D02*
Y30300D01*
G01X927220Y23540D02*
X926702Y24058D01*
X923242D01*
X919400Y27900D01*
Y33300D01*
G01X908250Y45000D02*
X912000D01*
G01X947900Y67900D02*
X947500Y67500D01*
X941000D01*
X939100Y69400D01*
Y75000D01*
X937400Y76700D01*
G01X932350Y78600D02*
X935500D01*
X937400Y76700D01*
G01X912000Y350500D02*
Y356500D01*
X910000Y358500D01*
G01X942646Y-276199D02*
Y-356199D01*
G01X942500Y30100D02*
X943734D01*
X945531Y28303D01*
Y25374D01*
G01X974100Y19600D02*
X976700D01*
X977713Y18587D01*
X984667D01*
G01X985880Y50586D02*
Y62449D01*
X981514Y66815D01*
X967290D01*
X967180Y66705D01*
G01X942850Y71275D02*
X949198D01*
X952500Y74577D01*
Y75100D01*
G01X956000Y93250D02*
Y97000D01*
X956500Y97500D01*
Y108000D01*
G01X988961Y14160D02*
X985315D01*
Y14425D01*
G01X1007921Y39585D02*
X1005994Y41512D01*
X1005176D01*
G01X992396Y45073D02*
Y45056D01*
X993834Y46494D01*
X996230D01*
G01X994597Y52869D02*
X993526Y51798D01*
Y46203D01*
X992396Y45073D01*
G01X1022300Y13900D02*
Y14400D01*
X1022613Y14713D01*
Y17398D01*
G01X1020330Y35032D02*
X1023677D01*
X1024330Y34379D01*
G01X1040218Y32140D02*
X1040294Y32216D01*
X1043418D01*
G01X1039675Y18837D02*
X1045005D01*
X1047429Y16413D01*
Y15229D01*
G01X1037071Y26921D02*
X1040070D01*
X1040121Y26870D01*
G01X1039822Y35743D02*
X1039849Y35716D01*
X1043418D01*
G01X1014451Y39889D02*
Y41556D01*
G01X1018900Y14198D02*
Y14937D01*
X1019113Y15150D01*
Y17398D01*
G01D02*
X1018144Y18367D01*
X1013132D01*
G01X1032142Y11076D02*
X1031553D01*
X1029553Y13076D01*
Y13981D01*
G01X1014451Y45056D02*
X1017863D01*
G01X1015228Y49109D02*
Y45833D01*
X1014451Y45056D01*
G01Y41556D02*
X1017908D01*
G01X1038189Y887970D02*
Y879851D01*
X1039764Y878276D01*
G01X1075089Y14070D02*
X1074140D01*
X1072140Y16070D01*
Y16447D01*
G01X1054835Y40386D02*
X1054650Y40571D01*
Y44400D01*
G01X1046200Y24500D02*
X1046448Y24748D01*
X1048952D01*
X1049935Y25731D01*
Y28600D01*
G01X1072140Y16447D02*
X1072093Y16400D01*
Y15576D01*
X1069809Y13292D01*
X1068809D01*
G01X1062433Y48832D02*
Y40942D01*
X1062088Y40597D01*
G01X1043418Y35716D02*
X1043902Y36200D01*
X1049150D01*
G01X1075726Y18266D02*
X1074610Y19382D01*
X1073316D01*
X1072804Y19894D01*
G01X1068673Y20895D02*
X1071803D01*
X1072804Y19894D01*
G01X1064900Y10400D02*
X1062600Y12700D01*
X1055122D01*
X1053630Y11208D01*
X1052236D01*
G01X1074103Y44988D02*
X1073788Y44673D01*
X1070733D01*
G01X1077432Y64225D02*
X1074250Y67407D01*
Y68500D01*
G01X1052850Y64100D02*
Y67595D01*
X1054610Y69355D01*
G01X1052850Y64100D02*
Y62994D01*
X1050946Y61090D01*
X1050875D01*
G01X1050500Y101750D02*
X1052250D01*
X1053665Y103165D01*
Y108835D01*
X1053000Y109500D01*
G01X1061000Y111000D02*
X1054500D01*
X1053000Y109500D01*
G01X1075985Y887970D02*
Y879851D01*
X1077560Y878276D01*
G01X1072835Y887970D02*
Y879851D01*
X1071260Y878276D01*
G01X1063386Y887970D02*
Y879851D01*
X1064961Y878276D01*
G01X1060237Y887970D02*
Y879852D01*
X1058661Y878276D01*
G01X1050788Y887970D02*
Y879851D01*
X1052363Y878276D01*
G01X1047638Y887970D02*
Y879851D01*
X1046063Y878276D01*
G01X1110630Y887970D02*
Y879851D01*
X1109055Y878276D01*
G01X1101182Y887970D02*
Y879850D01*
X1102756Y878276D01*
G01X1098032Y887970D02*
Y879852D01*
X1096456Y878276D01*
G01X1088583Y887970D02*
Y879851D01*
X1090158Y878276D01*
G01X1085434Y887970D02*
Y879852D01*
X1083858Y878276D01*
G01X1112646Y-276199D02*
Y-356199D01*
G01X1117625Y228750D02*
Y228000D01*
X1120625Y225000D01*
X1124000D01*
X1126500Y222500D01*
G01X1132125Y228750D02*
X1135750D01*
G01X1138977Y887970D02*
Y879851D01*
X1140552Y878276D01*
G01X1135827Y887970D02*
Y879851D01*
X1134252Y878276D01*
G01X1126378Y887970D02*
Y879851D01*
X1127953Y878276D01*
G01X1123229Y887970D02*
Y879852D01*
X1121653Y878276D01*
G01X1113780Y887970D02*
Y879851D01*
X1115355Y878276D01*
G01X1146625Y228750D02*
X1150250D01*
G01X1175700Y814200D02*
Y817500D01*
X1174900Y818300D01*
G01X1173623Y887970D02*
Y878200D01*
G01X1161024Y887970D02*
Y879852D01*
X1159448Y878276D01*
G01X1151575Y887970D02*
Y879851D01*
X1153150Y878276D01*
G01X1148426Y887970D02*
Y879852D01*
X1146850Y878276D01*
G01X1195670Y887970D02*
Y882770D01*
X1194943Y882043D01*
Y879125D01*
X1194094Y878276D01*
G01X1186221Y887970D02*
Y879851D01*
X1187796Y878276D01*
G01X1183071Y887970D02*
Y879851D01*
X1181496Y878276D01*
G01X1217717Y887970D02*
Y878076D01*
G01X1242914Y887970D02*
Y879851D01*
X1244489Y878276D01*
G01X1239764Y887970D02*
Y879851D01*
X1238189Y878276D01*
G01X1230315Y887970D02*
Y879851D01*
X1231890Y878276D01*
G01X1227166Y887970D02*
Y879852D01*
X1225590Y878276D01*
G01X1249718Y141179D02*
X1249720Y141181D01*
X1252768D01*
G01X1258500Y338750D02*
Y335500D01*
G01X1266500Y338750D02*
Y335500D01*
G01X1278500Y338750D02*
X1282500D01*
G01X1274500D02*
X1270500D01*
G01D02*
Y335500D01*
G01X1262500Y338750D02*
Y334500D01*
X1264100Y332900D01*
X1268400D01*
X1270500Y335000D01*
Y335500D01*
G01X1274500Y338750D02*
X1278500D01*
G01X1273500Y393750D02*
Y397000D01*
G01X1257500Y393750D02*
Y397000D01*
G01X1254000Y393750D02*
Y397000D01*
G01Y390250D02*
X1257500D01*
G01X1249250D02*
X1254000D01*
G01X1269500Y393750D02*
Y397000D01*
G01X1277500Y401250D02*
X1282250D01*
X1285000Y398500D01*
Y394250D01*
X1285500Y393750D01*
G01X1277560Y887970D02*
Y879852D01*
X1275984Y878276D01*
G01X1268111Y887970D02*
Y879851D01*
X1269686Y878276D01*
G01X1264961Y887970D02*
Y879851D01*
X1263386Y878276D01*
G01X1255512Y887970D02*
Y879851D01*
X1257087Y878276D01*
G01X1252363Y887970D02*
Y879852D01*
X1250787Y878276D01*
G01X1310146Y-276199D02*
Y-356199D01*
G01X1342146Y-260199D02*
X1310146D01*
G01X1304000Y39750D02*
Y44000D01*
G01Y16250D02*
Y19466D01*
X1303983Y19483D01*
Y22083D01*
G01X1304000Y63250D02*
Y67500D01*
G01Y86750D02*
Y90500D01*
G01X1306970Y131435D02*
Y130700D01*
X1301749Y125479D01*
G01X1297668Y159835D02*
Y155524D01*
G01X1311262Y181958D02*
X1311181Y182039D01*
Y186548D01*
G01X1290978Y181958D02*
Y186177D01*
X1290870Y186285D01*
G01X1298300Y292700D02*
X1299300D01*
X1302500Y289500D01*
X1303700D01*
G01X1289250Y295000D02*
X1286700D01*
X1283300Y298400D01*
Y302900D01*
G01X1311000Y282250D02*
Y285000D01*
X1310500Y285500D01*
G01X1298500Y338750D02*
X1294500D01*
G01D02*
X1290500D01*
G01D02*
X1286500D01*
G01D02*
X1282500D01*
G01X1302500D02*
X1298500D01*
G01X1289500Y393750D02*
X1285500D01*
G01X1305500D02*
X1309250D01*
X1309584Y394084D01*
X1310068D01*
G01X1301500Y393750D02*
X1305500D01*
G01X1297500D02*
X1293500D01*
G01X1301500D02*
X1297500D01*
G01X1293500D02*
X1289500D01*
G01X1302128Y677117D02*
Y674067D01*
G01X1306128Y677117D02*
Y674000D01*
G01X1294628Y726117D02*
Y721700D01*
X1301728Y714600D01*
G01X1294628Y729617D02*
Y733000D01*
G01X1310200Y729650D02*
Y732800D01*
X1310100Y732900D01*
G01X1294628Y726117D02*
X1291428D01*
G01X1304800Y818400D02*
Y811900D01*
G01X1305906Y887970D02*
Y879851D01*
X1307481Y878276D01*
G01X1290158Y887970D02*
Y879852D01*
X1288582Y878276D01*
G01X1280709Y887970D02*
Y879851D01*
X1282284Y878276D01*
G01X1338146Y-260199D02*
G02I-12000J0D01*
G01X1332996D02*
G02I-6850J0D01*
G01X1326146Y-276199D02*
Y-244199D01*
G01X1324845Y130527D02*
X1322502D01*
X1321345Y129370D01*
G01X1321655Y148259D02*
X1325398D01*
X1325409Y148270D01*
X1325429D01*
G01X1328750Y290500D02*
X1333500D01*
G01X1355000Y286300D02*
X1349100D01*
X1346400Y283600D01*
X1337000D01*
G01D02*
Y287000D01*
X1333500Y290500D01*
G01X1315000Y282250D02*
X1319000D01*
G01D02*
X1322250D01*
G01X1342300Y676750D02*
X1345850D01*
G01X1322400Y669550D02*
X1326250D01*
G01X1326100Y737650D02*
Y740139D01*
X1326661Y740700D01*
G01X1343701Y887970D02*
Y879851D01*
X1345276Y878276D01*
G01X1340552Y887970D02*
Y879852D01*
X1338976Y878276D01*
G01X1331103Y887970D02*
Y879851D01*
X1332678Y878276D01*
G01X1327953Y887970D02*
Y879851D01*
X1326378Y878276D01*
G01X1318504Y887970D02*
Y879851D01*
X1320079Y878276D01*
G01X1315355Y887970D02*
Y879852D01*
X1313779Y878276D01*
G01X1378134Y173459D02*
X1381696D01*
G01X1359124Y171370D02*
X1356070D01*
X1355321Y172119D01*
G01X1381568Y180579D02*
X1381096Y181051D01*
X1378160D01*
G01X1382138Y184129D02*
Y183927D01*
X1381514Y184551D01*
X1378160D01*
G01X1357000Y271500D02*
X1357666Y272166D01*
Y274496D01*
X1358655Y275485D01*
X1358662D01*
G01X1353150Y887970D02*
Y879350D01*
X1352200Y878400D01*
X18577Y107902D03*
X5500Y119571D03*
Y139571D03*
Y159571D03*
X22000Y167200D03*
X5500Y179571D03*
Y199571D03*
X26500Y199500D03*
X21900Y199700D03*
X21800Y188100D03*
X5500Y219571D03*
Y239571D03*
X23100Y224500D03*
X27300Y229000D03*
X28400Y262800D03*
X18000Y271600D03*
X5500Y259571D03*
X26600Y249217D03*
Y253582D03*
X18000Y289400D03*
X28200Y296100D03*
X5500Y279571D03*
Y299571D03*
X24000Y308700D03*
X26300Y317600D03*
X21400Y327900D03*
Y341000D03*
X5500Y339571D03*
Y319571D03*
X24639Y321239D03*
X21400Y354000D03*
X22900Y365300D03*
X5500Y359571D03*
Y399571D03*
Y379571D03*
X31324Y410800D03*
X25350Y389000D03*
X17500Y412374D03*
X20713Y410087D03*
X5500Y419571D03*
Y439571D03*
X21300Y429500D03*
X20713Y418326D03*
X5500Y479571D03*
Y459571D03*
X23720Y472640D03*
X5500Y499571D03*
Y519571D03*
Y539571D03*
X29300Y539850D03*
X24800Y540900D03*
X5500Y579571D03*
Y559571D03*
Y599571D03*
Y639571D03*
Y619571D03*
Y679571D03*
Y659571D03*
X26100Y671200D03*
X24000Y659000D03*
X29500Y676500D03*
X5500Y699571D03*
X27125Y695275D03*
X25200Y712650D03*
X17500Y706300D03*
X21300Y728400D03*
X21108Y732713D03*
X18250Y749250D03*
X5500Y719571D03*
Y739571D03*
X25050Y716900D03*
X21250Y742650D03*
X27000Y754400D03*
X5500Y779571D03*
Y759571D03*
Y799571D03*
X10020Y835051D03*
X30020D03*
X5500Y819571D03*
X31400Y209190D03*
X46760Y209157D03*
X63250Y205050D03*
X42800Y200100D03*
X44400Y216600D03*
X34900Y216800D03*
X59800Y211800D03*
X50200Y212000D03*
X31500Y224400D03*
X41250Y216728D03*
X53400Y211928D03*
X38050Y216728D03*
X56600Y211928D03*
X58400Y271800D03*
X57500Y263300D03*
X63700Y257300D03*
X63800Y267100D03*
X44029Y272572D03*
X44426Y267408D03*
X35150Y273250D03*
X60872Y274328D03*
X63700Y260725D03*
X55800Y266293D03*
X63700Y263925D03*
X55800Y269493D03*
X44900Y261750D03*
X35300Y303100D03*
X59173Y288186D03*
X42900Y284500D03*
X58730Y299508D03*
X35150Y284350D03*
X47912Y294940D03*
X39000Y299500D03*
X53100Y279500D03*
X47800Y309400D03*
X31662Y303262D03*
X58700Y308600D03*
X61800Y306900D03*
X38800Y302900D03*
X62200Y288256D03*
X58383Y294947D03*
X47355Y303376D03*
X47991Y299958D03*
X49934Y280811D03*
X49100Y328300D03*
X39600Y317600D03*
X58990Y342700D03*
X34800Y321200D03*
X54600Y328600D03*
X38500Y321400D03*
X58100Y334600D03*
X62400Y334500D03*
X31700Y314700D03*
X52050Y316100D03*
X51050Y321650D03*
X62400Y342700D03*
X38518Y376916D03*
X34153D03*
X39866Y371366D03*
X52521Y350357D03*
X31500Y366900D03*
X48512Y356488D03*
X49300Y346700D03*
X43262Y357062D03*
X44866Y378634D03*
X55907Y350673D03*
X54200Y347400D03*
X62838Y392392D03*
X60610Y381665D03*
X39300Y389557D03*
X47132Y444399D03*
X48000Y426000D03*
Y422500D03*
Y429500D03*
X57800Y420700D03*
X35709Y426942D03*
X43500Y418802D03*
X47734Y465792D03*
X45531Y474400D03*
X31500Y447000D03*
X64820Y455887D03*
X64680Y452389D03*
X64500Y459400D03*
X36750Y462900D03*
X53200Y462500D03*
X49812Y479921D03*
X33900Y469300D03*
X46500Y460300D03*
X46087Y455819D03*
X50140Y494559D03*
X60987Y489223D03*
X63519Y505320D03*
X62298Y484200D03*
X35700Y488500D03*
X60150Y506450D03*
X50140Y490750D03*
X60900Y495122D03*
X61870Y515670D03*
X60300Y533900D03*
X61128Y519646D03*
X64200Y534500D03*
X61800Y537000D03*
X55950Y564500D03*
Y572500D03*
X63000Y558930D03*
X62611Y608289D03*
X62400Y624500D03*
X53000Y645000D03*
X63300Y634800D03*
X43600Y665700D03*
X54200Y666800D03*
X60700Y682100D03*
X47800Y666400D03*
X35766Y673178D03*
X34500Y666500D03*
X39900Y678100D03*
X33600Y675800D03*
X43100Y670900D03*
X36624Y669155D03*
X47300Y704400D03*
X42300Y704900D03*
X62000Y713000D03*
X45800Y685100D03*
X42100Y684000D03*
X53500Y690200D03*
X60650Y694050D03*
X63300Y697200D03*
X59100Y705600D03*
X42130Y694440D03*
X38000Y684000D03*
X59300Y734900D03*
X54300Y729900D03*
X49300Y734900D03*
X54300Y739900D03*
Y734900D03*
X56590Y720410D03*
X47800Y772900D03*
X35000Y769900D03*
X39000D03*
X42800Y770000D03*
X52500Y779600D03*
X64900Y780500D03*
X50020Y835051D03*
X96584Y195100D03*
X78050Y196300D03*
X82676Y208785D03*
X67600Y209500D03*
X92859Y226659D03*
X87978Y226596D03*
X78508Y232693D03*
X72934Y232675D03*
X95200Y210800D03*
X85600D03*
X80600Y216700D03*
X71000Y216600D03*
X88276Y232700D03*
X88259Y223184D03*
X92659D03*
X78000Y229289D03*
X73600D03*
X77400Y216528D03*
X88800Y210851D03*
X74200Y216528D03*
X92000Y210851D03*
X97480Y266420D03*
X94600Y277100D03*
X93672Y270153D03*
X71870Y257120D03*
X77527Y255800D03*
X94530Y264671D03*
X75800Y274100D03*
X68100Y255000D03*
X71094Y285981D03*
X77964Y285670D03*
X68429Y288212D03*
X75400Y309700D03*
X71500Y297900D03*
X77100Y303800D03*
X65400D03*
X65500Y291900D03*
X77500D03*
X89400Y279300D03*
X96798Y301484D03*
Y297915D03*
X95700Y293900D03*
X73125Y288231D03*
X76325D03*
X65400Y288256D03*
X84600Y303000D03*
X78121Y325870D03*
X73721D03*
X70210Y342700D03*
X77290Y344212D03*
X86511Y344200D03*
X66400Y334500D03*
X66800Y342700D03*
X83500Y344200D03*
X80300D03*
X77421Y322470D03*
X74221D03*
X79455Y357174D03*
X75256Y370303D03*
X70591Y359309D03*
X71794Y377639D03*
X76055Y357145D03*
X82500Y362890D03*
X92580Y410761D03*
X79600Y399200D03*
X95223Y385704D03*
X79267Y410185D03*
X80940Y395989D03*
X86904Y385798D03*
X72708Y382055D03*
X68365Y381464D03*
X84700Y396000D03*
X92752Y434193D03*
X91370Y445394D03*
X70700Y443244D03*
X77859Y429879D03*
X72533Y416996D03*
X79164Y426221D03*
X96351Y443000D03*
Y438600D03*
X85042Y439144D03*
X91200Y448800D03*
Y453200D03*
X91311Y456609D03*
X89400Y470400D03*
X89500Y466600D03*
X85748Y475813D03*
X73232Y476912D03*
X97100Y466500D03*
X98400Y454400D03*
X77681Y499033D03*
X77413Y506468D03*
X76100Y483400D03*
X77700Y502500D03*
X88573Y503935D03*
X70910Y502219D03*
X67700Y499120D03*
X77700Y522500D03*
X88204Y543283D03*
X89200Y518700D03*
Y528500D03*
X65600Y543200D03*
X75600Y518600D03*
X67700Y518500D03*
X67162Y515142D03*
X77300Y531238D03*
X77700Y538500D03*
X74301Y538390D03*
X65800Y538900D03*
X74300Y533600D03*
X73900Y527050D03*
X77372Y526885D03*
X73700Y542600D03*
X70000Y542500D03*
X74000Y557000D03*
X77500Y554500D03*
X90500Y580100D03*
X81000Y579000D03*
X95252Y571638D03*
X70800Y559895D03*
X77400Y559000D03*
X77250Y562750D03*
X77400Y577000D03*
X71400Y578300D03*
X87555Y561085D03*
X87200Y574250D03*
X87337Y569268D03*
X84226Y577924D03*
X87200Y565785D03*
X77400Y550400D03*
X65381Y548719D03*
X87608Y557685D03*
X69100Y549200D03*
X73700Y549300D03*
X92000Y591200D03*
X69500Y586000D03*
X90500Y587000D03*
X80300Y596100D03*
X69258Y603000D03*
X82000Y592500D03*
X66000Y604800D03*
X88000Y613600D03*
X81000Y589000D03*
X78300Y634250D03*
X94860Y628750D03*
X78300Y637750D03*
X75800Y681900D03*
X94950Y677850D03*
X75450Y694150D03*
X69700Y690300D03*
X89825Y692875D03*
X79250Y716050D03*
X91800Y716100D03*
X66700Y713500D03*
X74500Y713400D03*
X91450Y707650D03*
X65350Y690356D03*
X89400Y749200D03*
X89300Y736300D03*
X95400Y731600D03*
Y728200D03*
X68900Y730000D03*
X68465Y736229D03*
X85800Y727500D03*
Y731000D03*
X74300Y769950D03*
X89800Y753400D03*
X69800Y772700D03*
X86900Y757900D03*
X89400Y762400D03*
X93100Y813200D03*
X70020Y835051D03*
X90020D03*
X93300Y818900D03*
X118577Y107902D03*
X104000Y128330D03*
X114364Y122054D03*
X118500Y176500D03*
Y173000D03*
X100900Y173800D03*
X108631Y168836D03*
X116000Y207000D03*
Y202000D03*
X118500Y188500D03*
X116000Y192000D03*
Y196500D03*
X118500Y185000D03*
Y181000D03*
X104100Y194600D03*
X103700Y200800D03*
X111967Y199632D03*
X119800Y234531D03*
X116000Y211500D03*
X103100Y211600D03*
X127330Y248029D03*
X112764Y264218D03*
X109600Y276850D03*
X112732Y272786D03*
X107340Y266140D03*
X101463Y268811D03*
X102499Y281183D03*
X109810Y310358D03*
X109972Y305968D03*
X112217Y296435D03*
X108500Y284000D03*
X107213Y301192D03*
X120700Y282400D03*
X100500Y285300D03*
X113915Y307600D03*
X117484D03*
X106400Y312200D03*
X101630Y312236D03*
X106717Y335600D03*
X117700Y323400D03*
X111900Y344200D03*
X113000Y336000D03*
X107558Y321012D03*
X122000Y343300D03*
X100277Y336077D03*
X102000Y364700D03*
X99128Y366961D03*
X108200Y378656D03*
X126800Y362500D03*
X108484Y348377D03*
X122645Y367966D03*
X117300Y361700D03*
X108453Y385164D03*
X100924Y409968D03*
X115951Y384138D03*
X111950Y392050D03*
X104204Y383661D03*
X129500Y412400D03*
X124290Y401910D03*
X125718Y383302D03*
X125600Y386700D03*
X107358Y409942D03*
X126122Y432323D03*
X105303Y419497D03*
X116173Y422379D03*
X107844Y414785D03*
X99749Y443671D03*
X99818Y437908D03*
X127925Y428093D03*
X116235Y444665D03*
X103179Y423267D03*
X103176Y434180D03*
X110406Y417067D03*
X113518Y420179D03*
X131304Y418855D03*
X131004Y422710D03*
X130633Y444763D03*
X120200Y436400D03*
X115500Y454700D03*
X111500D03*
X103500D03*
X120000Y451285D03*
X107900Y448900D03*
X101200Y470400D03*
X129520Y448660D03*
X127820Y452280D03*
X123696Y454452D03*
X114400Y550000D03*
X104461Y571715D03*
X100140Y559260D03*
X99460Y566200D03*
X102870Y565740D03*
Y561340D03*
X105851Y611436D03*
X104400Y590300D03*
X102000Y599000D03*
Y602500D03*
X101750Y595600D03*
X120351Y633500D03*
X126851Y633449D03*
X116551Y644936D03*
X128220Y620392D03*
X125581Y641436D03*
X109051Y645936D03*
X131051Y656436D03*
X119051Y653906D03*
X109800Y681900D03*
X130900Y714300D03*
Y710800D03*
X107950Y687650D03*
X124150Y707050D03*
X111400Y741800D03*
Y718300D03*
X118060Y743460D03*
X106900Y738600D03*
Y721300D03*
X115000Y717600D03*
X107000Y717800D03*
X132200Y761300D03*
Y756300D03*
X111300Y756000D03*
X109900Y828800D03*
X105400Y828700D03*
X103200Y825400D03*
X115500Y825500D03*
X107600D03*
X120000Y843500D03*
X126500Y878200D03*
Y871000D03*
X129000Y875000D03*
X117500Y878200D03*
X122000D03*
X124500Y875000D03*
X120000Y865000D03*
Y875000D03*
Y853500D03*
X138577Y107902D03*
X158577D03*
X149380Y176010D03*
X162500Y173500D03*
X163000Y211500D03*
X157200Y241400D03*
X153000Y225000D03*
X155026Y212580D03*
X134120Y267630D03*
X157300Y259900D03*
X157400Y254000D03*
X157300Y246500D03*
X155662Y266438D03*
X159662Y266600D03*
X162910Y244290D03*
X139286Y311214D03*
X166087Y304350D03*
X143000Y342900D03*
X155891Y339730D03*
X134800Y329600D03*
X144595Y312861D03*
X137862Y361723D03*
X161311Y371428D03*
X141216Y361163D03*
X145027D03*
X156573Y371799D03*
X140500Y390500D03*
X145500Y385500D03*
X158800Y406255D03*
X143000Y388000D03*
X142608Y403594D03*
X157550Y399100D03*
X146105Y403610D03*
X155657Y384291D03*
X137000Y436700D03*
X145901Y441262D03*
X139019Y443177D03*
X159540Y445692D03*
X146165Y444876D03*
X149838Y446190D03*
X150431Y420306D03*
X153100Y439000D03*
X136500Y417400D03*
X152978Y435602D03*
X137344Y446737D03*
X137000Y451300D03*
X163440Y453020D03*
X133000Y454700D03*
X143547Y477976D03*
X137000Y454700D03*
X159239Y449079D03*
X159082Y452509D03*
X165851Y630651D03*
X137551Y629849D03*
X149851Y631251D03*
X155851Y631051D03*
X160851Y630651D03*
X150069Y640500D03*
X150280Y636620D03*
X150600Y648300D03*
X150409Y643884D03*
X153019Y622720D03*
X159716Y620392D03*
X166015D03*
X136651Y653036D03*
X162100Y677800D03*
X164400Y668300D03*
X160500Y689500D03*
X150000Y701500D03*
X142500Y709000D03*
X137000Y715500D03*
X164500Y693500D03*
X144400Y731600D03*
Y728200D03*
X136400Y738300D03*
Y721800D03*
X161200Y723900D03*
X150200Y729400D03*
X153700D03*
X157700Y748900D03*
X150450Y744150D03*
X146450Y736150D03*
X135700Y745200D03*
X163800Y771000D03*
X160400D03*
X154000Y779000D03*
X160700Y753400D03*
X143000Y784500D03*
X146500D03*
X150500Y804000D03*
X139250Y791250D03*
X143250Y799250D03*
X153500Y808500D03*
X163800Y820000D03*
X160400D03*
X138500Y835000D03*
X137600Y839500D03*
X141100Y824500D03*
X141000Y830700D03*
X145900Y824400D03*
X142500Y862500D03*
Y867500D03*
Y872500D03*
X138500Y869500D03*
Y875200D03*
X141000Y877700D03*
X145500D03*
X149700D03*
X142500Y856500D03*
X159449Y878276D03*
X178577Y107902D03*
X181738Y122711D03*
X171500Y207500D03*
Y202500D03*
X193400Y192900D03*
X191800Y189600D03*
X196018Y204200D03*
X167000Y211500D03*
X172450Y211050D03*
X183400Y221600D03*
X171100Y247500D03*
X191000Y246500D03*
X167600Y247600D03*
X193303Y264310D03*
X167700Y296882D03*
Y292517D03*
X180850Y285650D03*
X170062Y304556D03*
X174943Y321015D03*
X167687Y329434D03*
X192407Y320262D03*
X180571Y327023D03*
X176674Y344934D03*
X189365Y329905D03*
X179381Y369903D03*
X196529Y352284D03*
X185970Y358962D03*
X195940Y348814D03*
X182969Y352641D03*
X192150Y406429D03*
X197000Y404000D03*
X171434Y398093D03*
X177550Y407850D03*
X166321Y388316D03*
X176098Y444355D03*
X197850Y437450D03*
X185000Y419900D03*
X197531Y451187D03*
X189381Y451394D03*
X193718D03*
X196239Y462262D03*
X173471Y454700D03*
X175912Y450747D03*
X166534Y450821D03*
X186675Y453505D03*
X177500Y454300D03*
X199900Y544500D03*
X196782Y563564D03*
X197334Y567232D03*
X197500Y577300D03*
X189500Y567700D03*
X185500Y577300D03*
X184189Y564504D03*
X185500Y567700D03*
X193001Y574708D03*
X181000Y585000D03*
Y581500D03*
X198600Y599750D03*
Y588750D03*
X181371Y601636D03*
X181000Y595200D03*
X168769Y622720D03*
X171300Y678300D03*
X175200Y678500D03*
X199900Y692000D03*
X171000Y715900D03*
X167600D03*
X193500Y700000D03*
X182500Y705500D03*
X186000D03*
X178750Y712250D03*
X189000Y684500D03*
X185000D03*
X167000Y686500D03*
X199900Y747500D03*
Y741000D03*
X190000Y725000D03*
X177700Y723900D03*
X182860Y742240D03*
X181200Y748900D03*
X184700Y729400D03*
X182750Y720250D03*
X193000Y729500D03*
X171000Y764900D03*
X167600D03*
X190000Y780500D03*
X170500Y779000D03*
X193500Y755500D03*
X182500Y761000D03*
X186000D03*
X182750Y775750D03*
X178000Y753400D03*
X178750Y767750D03*
X199900Y796500D03*
X175660Y797340D03*
X174000Y804000D03*
X177500Y784500D03*
X170800Y808500D03*
X193000Y785000D03*
X195000Y824090D03*
X188572Y832186D03*
X196474Y832178D03*
X197420Y821701D03*
X194120Y830301D03*
X190920D03*
X176900Y867600D03*
X173500D03*
X196000Y868700D03*
X176771Y878276D03*
X195669D03*
X168898Y878200D03*
X185500D03*
X197218Y871676D03*
X227669Y5500D03*
X210028Y12605D03*
Y32605D03*
Y52605D03*
Y72605D03*
X226533Y72591D03*
X228121Y63589D03*
X228163Y68589D03*
X210028Y92605D03*
X227989Y83589D03*
X222354Y103006D03*
X228163Y78589D03*
X227606Y98642D03*
X223641Y99302D03*
X228163Y93589D03*
Y88589D03*
X228500Y138100D03*
X223750Y141370D03*
X218725Y138175D03*
X228007Y123787D03*
X233500Y137000D03*
X220300Y129300D03*
X222356Y133438D03*
X228708Y127115D03*
X215136Y142786D03*
X218299Y123319D03*
X224576Y116678D03*
X221418Y109634D03*
X210478Y151203D03*
X233537Y160630D03*
X213282Y188452D03*
X202892Y188441D03*
X205013Y192596D03*
X210484Y179525D03*
X206297Y188492D03*
X209866D03*
X214794Y212100D03*
X206200Y247500D03*
X209200Y252800D03*
X230400Y283400D03*
X222200Y300500D03*
X205840Y325381D03*
X210177D03*
X218102Y334880D03*
X218070Y340244D03*
X221460Y335475D03*
Y339875D03*
X228100Y364600D03*
X219018Y378000D03*
X223383D03*
X217000Y360000D03*
X219580Y356970D03*
X214776Y352807D03*
X212536Y349805D03*
X205750Y408250D03*
X205915Y422424D03*
X217190Y428485D03*
X212200Y428800D03*
X212000Y438713D03*
X217500Y441992D03*
X205200Y442900D03*
X220897Y441833D03*
X220800Y446000D03*
X200100Y415100D03*
X201868Y451187D03*
X227700Y476537D03*
Y472200D03*
X216404Y469751D03*
X216282Y463288D03*
X219763Y472187D03*
X230572Y455128D03*
X228900Y446800D03*
X219300Y508700D03*
X228298Y488100D03*
X228347Y484700D03*
X219700Y489800D03*
X202700Y495400D03*
X206700Y498000D03*
X216600Y496550D03*
X217800Y512500D03*
X200917Y490578D03*
X203550Y484522D03*
X233290Y493277D03*
X206700Y494000D03*
X203500Y499200D03*
X207026Y483956D03*
X219800Y493700D03*
X218906Y483186D03*
X226300Y505700D03*
X226530Y502307D03*
X216873Y516458D03*
X203300Y538500D03*
X206700Y544500D03*
Y538500D03*
X221000Y541300D03*
X217500Y519800D03*
Y529250D03*
X225000Y541300D03*
X229200Y514800D03*
X216300Y546350D03*
X203300Y544500D03*
Y548500D03*
X219700Y550500D03*
X218780Y560082D03*
X206700Y548500D03*
X216300Y550500D03*
X216278Y567341D03*
X202300Y559763D03*
X222300Y577300D03*
X216563Y555908D03*
X229800Y558500D03*
X206700Y554500D03*
X203304Y554684D03*
X205700Y559763D03*
X222500Y573220D03*
X216241Y563095D03*
X216090Y593937D03*
X227500Y603500D03*
X201000Y674000D03*
X206952Y655370D03*
X203300Y692000D03*
X219000Y694000D03*
X210000Y700000D03*
X231500Y699000D03*
X217000Y705500D03*
X203300Y747500D03*
Y741000D03*
X213500Y725000D03*
X215160Y718340D03*
X210300Y729500D03*
X227409Y775903D03*
X233000D03*
X213500Y780500D03*
X210000Y755500D03*
X215160Y773840D03*
X217000Y761000D03*
X228550Y772700D03*
X231750D03*
X203300Y796500D03*
X210300Y785000D03*
X203124Y824090D03*
X233650Y827374D03*
X208700Y828000D03*
X201641Y827947D03*
X214380Y827374D03*
X221052D03*
X226978D03*
X200620Y821701D03*
X231915Y830301D03*
X219317D03*
X206718D03*
X228715D03*
X216117D03*
X203518D03*
X201500Y868700D03*
X233464Y878276D03*
X208267D03*
X201969D03*
X220866D03*
X214567D03*
X227166D03*
X225615Y875176D03*
X213017D03*
X200418Y871676D03*
X222415Y875176D03*
X209817D03*
X247669Y5500D03*
X258159Y73589D03*
X257851Y63589D03*
X257759Y68589D03*
X257769Y83589D03*
X264817Y105350D03*
X257731Y78589D03*
X258100Y93589D03*
X257912Y101408D03*
X258029Y97353D03*
X260562Y85988D03*
X254000Y131500D03*
X264500Y142750D03*
X254500D03*
X246500Y139000D03*
X243000D03*
X258068Y110180D03*
X259331Y118580D03*
X264443Y109587D03*
X257422Y121792D03*
X259500Y143250D03*
Y147750D03*
Y160750D03*
Y156250D03*
X264397Y160977D03*
X264500Y157250D03*
Y153750D03*
Y150250D03*
Y146250D03*
X259500Y152000D03*
X254500Y161250D03*
Y157250D03*
Y153750D03*
Y150250D03*
Y146250D03*
X239600Y142900D03*
X243618Y143381D03*
X243500Y147500D03*
X241231Y238869D03*
X236300Y227280D03*
X247500Y233750D03*
X244300Y226700D03*
X266500Y239400D03*
X245400Y296500D03*
X267300Y300600D03*
Y328640D03*
X257340Y338640D03*
X248160Y343140D03*
X267300Y362200D03*
X244000Y377617D03*
X260929Y345571D03*
X248930Y358000D03*
X244000Y381982D03*
X258500Y391200D03*
X239100Y399200D03*
X251700Y421600D03*
Y425200D03*
X238400Y416200D03*
X235750Y419500D03*
X262900Y438700D03*
X246375Y440725D03*
X265100Y443300D03*
X264100Y425400D03*
X249342Y439064D03*
X251800Y470100D03*
X248500Y465000D03*
X263700Y474600D03*
X257493Y456679D03*
X253302D03*
X257400Y477300D03*
X235850Y455050D03*
X246300Y478600D03*
Y485400D03*
X246407Y488799D03*
X256300Y494500D03*
X244100Y499900D03*
X246800Y496800D03*
X257400Y481637D03*
X256300Y486000D03*
Y490000D03*
X260646Y499181D03*
X256855Y499154D03*
X265019Y497483D03*
X255487Y512454D03*
X242800Y495486D03*
X246500Y493400D03*
X240450Y499400D03*
X236737Y493170D03*
X243200Y508000D03*
X250200Y506600D03*
X264522Y511690D03*
X260407Y502674D03*
X257207D03*
X246300Y482000D03*
X239139Y525077D03*
X239321Y521081D03*
X249700Y525737D03*
Y521250D03*
X264500Y521309D03*
X261100Y521250D03*
X250100Y537100D03*
X236100Y517100D03*
X263300Y526300D03*
X234777Y550569D03*
X252238Y574238D03*
X255738D03*
X253500Y590500D03*
X257413D03*
X266100Y614400D03*
X265850Y606400D03*
X248500Y583000D03*
X260100Y647400D03*
X259300Y632400D03*
Y639300D03*
X250500Y642500D03*
X265900Y622400D03*
X238100Y643400D03*
X247717Y633233D03*
X259300Y635900D03*
X236000Y656000D03*
X256600Y652200D03*
X241000Y712500D03*
X262628Y744470D03*
X266980Y723854D03*
X241000Y721500D03*
X258100Y726100D03*
X241000Y725500D03*
Y718000D03*
X266906Y775531D03*
X263181Y772181D03*
X249025Y827374D03*
X255697D03*
X261624D03*
X266561Y830301D03*
X253962D03*
X263361D03*
X250762D03*
X261811Y878276D03*
X249212D03*
X239764D03*
X255511D03*
X260261Y875176D03*
X238213D03*
X257061D03*
X235013D03*
X267669Y5500D03*
X290000Y141100D03*
X274250Y133750D03*
X292000Y130000D03*
X285500D03*
X284440Y139580D03*
X285250Y133750D03*
X294500Y152500D03*
X286000Y143800D03*
X286100Y153900D03*
X280000D03*
X290500Y152500D03*
X275000Y147500D03*
X277800Y208500D03*
X271231Y237031D03*
X283622Y226340D03*
X279257D03*
X269849Y308414D03*
X277300Y304800D03*
X297090Y311350D03*
X282700Y300100D03*
X299600Y297662D03*
X269270Y315759D03*
X287200Y326802D03*
X287800Y311600D03*
X267979Y342500D03*
X295400Y325390D03*
X283700Y322100D03*
X297729Y362571D03*
X288270Y365240D03*
X297729Y351029D03*
X294009Y363063D03*
X293800Y436100D03*
X301170Y462780D03*
X301162Y459290D03*
X273783Y476100D03*
X283400Y477900D03*
X284200Y465000D03*
X275900Y467300D03*
X285800Y460810D03*
X290838Y501600D03*
X286181Y498546D03*
X291500Y497700D03*
X269000Y504962D03*
X275286Y504392D03*
X280749Y512744D03*
X286169Y502000D03*
X285776Y489300D03*
X272860Y489147D03*
X282400Y487300D03*
X295876Y520800D03*
X296200Y566900D03*
X290000Y578165D03*
X300835D03*
X279994Y554794D03*
X283600Y551400D03*
X291000Y561450D03*
X280200Y551400D03*
X289835Y583165D03*
Y588165D03*
X269000Y589000D03*
X269335Y593165D03*
X300835Y583165D03*
X301000Y588665D03*
X288835Y593165D03*
X297750Y592750D03*
X276300Y617350D03*
X281700Y634900D03*
X281800Y638900D03*
X288400Y626100D03*
Y634200D03*
X292500Y630200D03*
X271500Y639500D03*
X281100Y651700D03*
X285500Y704900D03*
X298406Y706000D03*
X290338Y715800D03*
X278406Y716531D03*
X274406Y716598D03*
X270000Y732650D03*
X283161Y730092D03*
X281500Y748500D03*
X275609Y726886D03*
X270556Y716702D03*
X269500Y736150D03*
X286500Y740500D03*
X287278Y729031D03*
X286406Y716531D03*
X296132Y726171D03*
X290720Y726333D03*
X285333Y726241D03*
X282406Y716598D03*
X298620Y728596D03*
X282378Y775431D03*
X298500Y752000D03*
X272116Y755592D03*
X298400Y775700D03*
X283500Y765631D03*
X268193Y755633D03*
X293692Y765571D03*
X287115Y765584D03*
X281500Y752000D03*
X299184Y765691D03*
X268296Y827374D03*
X280894D03*
X274222D03*
X279159Y830301D03*
X275959D03*
X286800Y863300D03*
X280800Y863500D03*
X268110Y878276D03*
X280708D03*
X287008D03*
X274410D03*
X285500Y866200D03*
X272859Y875176D03*
X282300Y866200D03*
X269659Y875176D03*
X307300Y221702D03*
X307834Y237966D03*
X306900Y251000D03*
X302500Y251600D03*
X311882Y310550D03*
X306800Y290500D03*
X328842Y300042D03*
X307425Y309838D03*
X303517Y309777D03*
X312900Y290450D03*
X321300Y301500D03*
X334200Y299600D03*
X313200Y299900D03*
X331800Y309100D03*
X310485Y314670D03*
X328800Y315900D03*
X316420Y331830D03*
X302749Y332651D03*
X326041Y329282D03*
Y325000D03*
X310839Y344339D03*
X315300Y344500D03*
X315900Y320900D03*
X313100Y371038D03*
Y374438D03*
X301320Y362500D03*
X313875Y364201D03*
X310475Y364193D03*
X316315Y369889D03*
X316205Y376006D03*
X301929Y351100D03*
X313500Y437400D03*
Y441000D03*
X313300Y429603D03*
X313294Y434006D03*
X302140Y444160D03*
X306521Y463576D03*
X304293Y466146D03*
X329014Y472022D03*
X306612Y460177D03*
X307400Y467600D03*
X303440Y475360D03*
X322268Y466591D03*
X322305Y469991D03*
X321900Y459800D03*
X322036Y463198D03*
X327512Y509612D03*
X303800Y505100D03*
X304400Y511400D03*
X327589Y504300D03*
X333102Y485902D03*
X330000Y501900D03*
X303500Y491000D03*
X305500Y483550D03*
X320500Y531000D03*
X321000Y527000D03*
X322700Y536500D03*
X311406Y535944D03*
X306900Y529100D03*
X311500Y548000D03*
X314900D03*
X322100Y638500D03*
X309000Y679000D03*
X305500Y676400D03*
X334800Y712000D03*
X302406Y706031D03*
X306406D03*
X322178Y729178D03*
X310016Y729793D03*
X312500Y716500D03*
X317300Y739300D03*
X302000Y740800D03*
X320000Y718200D03*
X323600Y717800D03*
X301310Y726403D03*
X326000Y729000D03*
X315132Y727197D03*
X307278Y726198D03*
X313452Y753856D03*
X330000Y754000D03*
X311200Y765500D03*
X311406Y775198D03*
X302700Y765400D03*
X315406Y765598D03*
Y775200D03*
X307406Y775198D03*
X312017Y827374D03*
X318689D03*
X324616D03*
X331288D03*
X329553Y830301D03*
X316954D03*
X326353D03*
X313754D03*
X306500Y868700D03*
X312000Y868600D03*
X324803Y878276D03*
X331102D03*
X318503D03*
X312500Y878200D03*
X323253Y875176D03*
X310955Y865676D03*
X332651Y875176D03*
X320053D03*
X307755Y865676D03*
X362528Y123931D03*
X358917Y124122D03*
X355069D03*
X352600Y128200D03*
Y132537D03*
X337000Y162000D03*
X354800Y171400D03*
X358300D03*
X354800Y166900D03*
X358300D03*
X354800Y162400D03*
X358300D03*
X362300D03*
Y166900D03*
Y171400D03*
X354800Y181900D03*
X358300D03*
X354800Y176900D03*
X358300D03*
X362300D03*
Y181900D03*
X345820Y256570D03*
X349970Y256720D03*
X344958Y300740D03*
X344955Y305843D03*
X341652Y305034D03*
Y301534D03*
X362500Y341700D03*
X362825Y336000D03*
X359132Y326647D03*
X351515Y327915D03*
X356953Y353653D03*
X359403Y351203D03*
X352003Y358603D03*
X354505Y356102D03*
X360820Y359299D03*
X363270Y356940D03*
X355872Y363965D03*
X358362Y361649D03*
X359500Y448800D03*
X335570Y491460D03*
X342300Y511600D03*
X350000Y537600D03*
X347100Y605300D03*
X357600Y638300D03*
X367000Y704000D03*
X360000D03*
X344200Y696300D03*
X354300Y696000D03*
Y704500D03*
X363500Y704000D03*
X366792Y734171D03*
X364275Y723033D03*
X359500Y727335D03*
X342900Y727200D03*
X364354Y731801D03*
X362091Y729538D03*
X367675Y723000D03*
X349813Y827374D03*
X356485D03*
X362411D03*
X343886D03*
X337214D03*
X367348Y830301D03*
X354750D03*
X342151D03*
X364148D03*
X351550D03*
X338951D03*
X362599Y878276D03*
X356299D03*
X350000D03*
X343700D03*
X337402D03*
X361048Y875176D03*
X348450D03*
X335851D03*
X357848D03*
X345250D03*
X387669Y5500D03*
X401300Y159800D03*
X401200Y150200D03*
X401300Y156715D03*
Y153215D03*
X400400Y189100D03*
X383600Y203200D03*
X376600Y261350D03*
X381700Y265800D03*
X368900Y315700D03*
X370700Y353900D03*
X395100Y449100D03*
X380300Y508700D03*
X401000Y575500D03*
X372000Y579300D03*
X388900Y550400D03*
X386500Y607900D03*
X370500Y705500D03*
X374275Y722919D03*
X370875Y723000D03*
X369083Y827374D03*
X384459D03*
X391131D03*
X397057D03*
X401994Y830301D03*
X389396D03*
X398794D03*
X386196D03*
X378346Y878276D03*
X390944D03*
X397244D03*
X384646D03*
X370500Y878200D03*
X395694Y875176D03*
X383096D03*
X392494D03*
X379896D03*
X407669Y5500D03*
X427669D03*
X406500Y141700D03*
X403600Y142542D03*
X433000Y169700D03*
X406500Y146900D03*
X435161Y166892D03*
X403600Y146042D03*
X422876Y199830D03*
Y204195D03*
X421757Y177999D03*
X411400Y183900D03*
X433400Y176800D03*
X410900Y217100D03*
X404170Y326708D03*
X403900Y315492D03*
X404040Y318900D03*
Y323300D03*
X416100Y470800D03*
X418900Y529300D03*
X410300Y637500D03*
X416328Y827374D03*
X428926D03*
X422254D03*
X403729D03*
X409656D03*
X427191Y830301D03*
X414593D03*
X423991D03*
X411393D03*
X416141Y878276D03*
X431889D03*
X422441D03*
X403543D03*
X409843D03*
X420891Y875176D03*
X408292D03*
X417691D03*
X405092D03*
X447669Y5500D03*
X467669D03*
X461900Y62300D03*
X466000D03*
X457700D03*
X465127Y57727D03*
X452600Y114254D03*
X454871Y122291D03*
X457400Y138900D03*
X454926Y118791D03*
X455800Y110200D03*
X452500Y153300D03*
X438561Y166892D03*
X456500Y169783D03*
Y165418D03*
X455800Y208300D03*
X464086Y287614D03*
X461389Y318510D03*
X464086Y340500D03*
X459200Y369300D03*
X462700D03*
X455450Y376050D03*
X466700Y388800D03*
X469700Y393300D03*
X459450Y384050D03*
X448200Y531400D03*
X443000Y596500D03*
X469000Y784000D03*
X461300Y813100D03*
X457900D03*
X456335Y835051D03*
X444500Y864450D03*
X438189Y878276D03*
X489261Y-14185D03*
X470200Y62300D03*
X478400D03*
X474400D03*
X483250Y59480D03*
X479700Y90100D03*
X491466Y126683D03*
X496782Y134315D03*
X474990Y122660D03*
X494800Y162900D03*
X480910Y164099D03*
X480800Y160700D03*
X498900Y171800D03*
X498000Y194200D03*
X493186Y272414D03*
X501867Y295490D03*
X477037Y333841D03*
X473637Y333876D03*
X500198Y324041D03*
X480532Y321332D03*
X480000Y355800D03*
X476600D03*
X486700Y363800D03*
X470200D03*
X493700Y369300D03*
X490200Y388800D03*
X491860Y382140D03*
X487000Y393300D03*
X480368Y405606D03*
X476531D03*
X472600Y477700D03*
X487400Y492100D03*
X500800Y567200D03*
X487906Y768598D03*
X491906Y768531D03*
X496061Y781678D03*
X482925Y777422D03*
X489522Y780127D03*
X478000Y777500D03*
X483850Y773800D03*
X500778Y781031D03*
X499906Y768531D03*
X497910Y778824D03*
X495906Y768598D03*
X494582Y800500D03*
X483500Y784650D03*
X485300Y808250D03*
X480100Y784575D03*
X497000Y817500D03*
X483000Y788150D03*
X499000Y793000D03*
X485300Y811750D03*
X500415Y817532D03*
X494582Y804000D03*
X496335Y835051D03*
X480406Y827531D03*
X495878Y827431D03*
X477206Y820648D03*
X500700Y828100D03*
X500807Y831499D03*
X491906Y827403D03*
X487906D03*
X530400Y72400D03*
X524000Y43500D03*
X532500Y62900D03*
X536100Y56700D03*
X531400Y102900D03*
X522700D03*
X528700Y91100D03*
X531200Y87900D03*
X535400Y87400D03*
X532900Y92400D03*
X532400Y78200D03*
X509369Y141559D03*
X530800Y123900D03*
X521465Y140964D03*
X513876D03*
X532110Y138400D03*
X525000D03*
X506006Y126183D03*
X507861Y134154D03*
X519300Y138871D03*
X530177Y140708D03*
X516100Y138871D03*
X526977Y140708D03*
X529176Y151713D03*
X532560Y152046D03*
X534000Y167400D03*
X535960Y151999D03*
X507300Y175500D03*
X515348Y163101D03*
X515354Y168998D03*
X505100Y164800D03*
X503975Y172372D03*
X518686Y163800D03*
Y168200D03*
X512600Y186500D03*
X517599Y229658D03*
X531232Y229927D03*
X534481Y243676D03*
X510462Y261315D03*
X525881Y287776D03*
X534481Y286876D03*
X518277Y288680D03*
X532921Y298436D03*
X509143Y284391D03*
X529881Y287376D03*
X525347Y336979D03*
X512100Y319700D03*
X532499Y315591D03*
X533779Y336979D03*
X507809Y336341D03*
X522209Y333841D03*
X522409Y318441D03*
X529126Y342336D03*
X532978Y371023D03*
X534500Y395100D03*
X528850Y394750D03*
X518100Y453200D03*
X520500Y519400D03*
X527700Y587500D03*
X522500Y782031D03*
X535178Y781000D03*
X511800Y768300D03*
X515900D03*
X531500Y774500D03*
X531600Y770200D03*
X515278Y779198D03*
X519748Y768297D03*
X507729Y778198D03*
X504278Y779198D03*
X507906Y768531D03*
X528179Y782555D03*
X524795Y778529D03*
X511484Y778515D03*
X515650Y764500D03*
X503906Y768598D03*
X519906Y764900D03*
X526274Y806000D03*
X511500Y803000D03*
X532000Y792500D03*
X515000D03*
X524700Y817500D03*
X507044Y817569D03*
X516943Y817401D03*
X528906Y817598D03*
X512716Y817550D03*
X533800Y835500D03*
X508579Y827421D03*
X527500Y836200D03*
X512679Y827500D03*
X527941Y864680D03*
X541200Y73400D03*
X541600Y62600D03*
X544500Y57400D03*
X546800Y46300D03*
X566700Y48700D03*
X570900Y56200D03*
X537400Y91000D03*
X540100Y102900D03*
X541700Y92300D03*
X544600Y87300D03*
X538800Y76900D03*
X546800Y76200D03*
X566100Y103100D03*
X543000Y76300D03*
X539031Y136200D03*
X547400Y136170D03*
X560633Y127988D03*
X552800Y140800D03*
X562603Y140881D03*
X544800Y137769D03*
X541600D03*
X549100Y126900D03*
X566531Y143123D03*
X570754Y147365D03*
X546800Y163450D03*
X564483Y167935D03*
X558121Y167249D03*
X543900Y154800D03*
X550300D03*
X548700Y152200D03*
X545500D03*
X547173Y167987D03*
X561567Y205767D03*
X554149Y200229D03*
X541446Y222562D03*
X569500Y240225D03*
X546494Y216010D03*
X539798Y228856D03*
X539934Y232660D03*
X540035Y236294D03*
X541637Y263240D03*
X545974D03*
X541681Y297976D03*
X539481Y286676D03*
X544993Y281352D03*
X539450Y322166D03*
X539507Y330787D03*
X554400Y335900D03*
X539400Y376444D03*
X560531Y358080D03*
X564100Y358100D03*
X556500Y358000D03*
X561781Y346281D03*
X561300Y369500D03*
X552720Y364180D03*
X539400Y380781D03*
X550000Y381000D03*
X559973Y387638D03*
X561912Y390762D03*
X567150Y415750D03*
X560900Y413700D03*
X544000Y761000D03*
X540500Y781000D03*
X547395Y761198D03*
X540500Y761000D03*
X542500Y806000D03*
X550186Y827374D03*
X543514D03*
X568711D03*
X556113D03*
X562785D03*
X561050Y830301D03*
X548451D03*
X570448D03*
X557850D03*
X545251D03*
X538000Y878200D03*
X550000Y878276D03*
X562598D03*
X568898D03*
X556300D03*
X544000Y878200D03*
X567348Y875176D03*
X554750D03*
X542151D03*
X564148D03*
X551550D03*
X538951D03*
X590000Y46200D03*
X579900Y55800D03*
X588000Y57200D03*
X584600Y63200D03*
X575800Y63100D03*
X588000Y72200D03*
X579000Y72300D03*
X573800Y72400D03*
X576800Y91600D03*
X584600Y78200D03*
X575500Y78500D03*
X588000Y87100D03*
X579000Y87200D03*
X584500Y93200D03*
X580700Y90900D03*
X572500Y91200D03*
X576300Y103300D03*
X585100D03*
X580800Y76000D03*
X574100Y87800D03*
X579200Y140400D03*
X583640Y140636D03*
X598240Y137800D03*
X572990Y140501D03*
X588955Y140600D03*
X591377Y125797D03*
X597846Y125623D03*
X577650Y137780D03*
X587850Y137800D03*
X604450Y137780D03*
X574450D03*
X584650Y137800D03*
X601250Y137780D03*
X593000Y152800D03*
X598300Y152850D03*
X597350Y149950D03*
X594150D03*
X596253Y210000D03*
X603000Y190710D03*
X579811Y179500D03*
X582400Y209500D03*
X597813Y220858D03*
X597763Y242608D03*
X602763Y240858D03*
X597763Y231608D03*
Y235108D03*
Y239108D03*
X602763Y236608D03*
Y232108D03*
X587100Y234800D03*
X587438Y230850D03*
X576100Y234500D03*
X592563Y228308D03*
X588963Y227408D03*
X587400Y238200D03*
X597763Y246108D03*
Y250108D03*
X602763Y245108D03*
Y249608D03*
X604170Y337900D03*
X600800Y337400D03*
X597600Y339100D03*
X599100Y348700D03*
X597500Y352050D03*
X589500Y361000D03*
X581700Y360700D03*
X573900Y360600D03*
X603500Y371200D03*
X576800Y369200D03*
X604400Y421200D03*
X579900Y427400D03*
X584500Y462500D03*
X600400Y538000D03*
X586900Y713200D03*
X593908Y827374D03*
X600580D03*
X587981D03*
X581309D03*
X575383D03*
X598845Y830301D03*
X586246D03*
X573648D03*
X595645D03*
X583046D03*
X594095Y878276D03*
X600393D03*
X587795D03*
X575197D03*
X581497D03*
X592545Y875176D03*
X579947D03*
X601944D03*
X589345D03*
X576747D03*
X631100Y72300D03*
X622100Y72400D03*
X628200Y62600D03*
X619200Y62800D03*
X614300Y55800D03*
X620838Y58628D03*
X634100Y46800D03*
X631300Y57100D03*
X616800Y72200D03*
X624700Y61400D03*
X611100Y103300D03*
X619600D03*
X628300D03*
X615800Y91200D03*
X624400Y91100D03*
X628000Y93000D03*
X618300Y88000D03*
X628100Y77700D03*
X619400Y77500D03*
X631200Y87200D03*
X624000Y76000D03*
X621900Y87600D03*
X619700Y92100D03*
X614721Y138287D03*
X623498Y140671D03*
X629393Y140451D03*
X631940Y137800D03*
X607520Y137780D03*
X605924Y126398D03*
X608089Y131519D03*
X627826Y137880D03*
X638150D03*
X624626D03*
X634950D03*
X617000Y144500D03*
X633900Y149600D03*
X636950Y149650D03*
X635482Y207733D03*
X607700Y211800D03*
X608800Y221400D03*
X635863Y216308D03*
X607763Y242608D03*
Y231608D03*
Y235108D03*
Y239108D03*
X619363Y225108D03*
X623363D03*
X635190Y219641D03*
X631063Y242108D03*
X616970Y235017D03*
X629663Y221708D03*
X616718Y238408D03*
X627363Y224358D03*
X637300Y234500D03*
X607763Y246108D03*
Y250108D03*
X628563Y249108D03*
X624101Y330010D03*
X627500Y329900D03*
X635350Y320850D03*
X622629Y344635D03*
X616640Y342230D03*
X620000Y341500D03*
X606322Y351522D03*
X633000Y356600D03*
Y360500D03*
Y353000D03*
X636500Y356500D03*
X629500D03*
Y371000D03*
X626458Y372521D03*
X616706Y349718D03*
X618680Y346780D03*
X621300Y366900D03*
X609500Y360717D03*
X618600Y357100D03*
X623000Y382500D03*
X617000D03*
X609000Y390350D03*
X615500Y420100D03*
X619100Y418000D03*
X627600Y685000D03*
X608000Y700800D03*
X613178Y827374D03*
X606506D03*
X638375D03*
X631703D03*
X619105D03*
X625777D03*
X636640Y830301D03*
X624042D03*
X611443D03*
X633440D03*
X620842D03*
X608243D03*
X606693Y878276D03*
X619292D03*
X612992D03*
X625590D03*
X631890D03*
X630340Y875176D03*
X617742D03*
X605144D03*
X627140D03*
X614542D03*
X653300Y48600D03*
X665400Y72500D03*
X661100Y73000D03*
X662300Y63300D03*
X656700Y57400D03*
X665696Y57027D03*
X671100Y63400D03*
X656400Y102600D03*
X665100Y102700D03*
X660600Y93300D03*
X669400Y93200D03*
X659700Y86400D03*
X662400Y78100D03*
X667500Y76000D03*
X664000Y91100D03*
X671300Y78100D03*
X641159Y137800D03*
X654500Y143000D03*
X647000D03*
X643160Y149600D03*
X640150Y149650D03*
X640400Y218200D03*
X649400Y234500D03*
X671124Y210770D03*
X655500Y213500D03*
X642463Y241608D03*
X638963D03*
X660700Y212000D03*
X640532Y318099D03*
X643932Y318104D03*
X639500Y342500D03*
X652254Y336353D03*
X643000Y343000D03*
X643750Y321500D03*
X640550D03*
X662897Y346873D03*
X663140Y353982D03*
X646884Y355616D03*
X639500Y371000D03*
X643000Y369500D03*
X648792Y358431D03*
X660244Y352200D03*
Y349000D03*
X653000Y380500D03*
X644100Y488700D03*
X639500Y678500D03*
X657000Y714500D03*
X668500Y700000D03*
X648900Y782500D03*
X645800Y780500D03*
Y776900D03*
Y783900D03*
X666348Y827374D03*
X653750D03*
X660422D03*
X653500Y819100D03*
X671285Y830301D03*
X658687D03*
X668085D03*
X655487D03*
X647838Y872000D03*
X660236Y878276D03*
X666536D03*
X654000Y878200D03*
X642200Y877900D03*
X664986Y875176D03*
X652388D03*
X661786D03*
X649188D03*
X674600Y72200D03*
X676800Y46300D03*
X674300Y102400D03*
X678300Y93100D03*
X674800Y86800D03*
X687900Y208100D03*
X697494Y186256D03*
Y181919D03*
X693300Y181200D03*
X685115Y210677D03*
X674500Y212000D03*
X689500Y344000D03*
X704500Y343000D03*
X676700Y378800D03*
X687000Y378700D03*
X680100Y378718D03*
X683600D03*
X678500Y684000D03*
X673020Y827374D03*
X698217D03*
X691545D03*
X678947D03*
X685619D03*
X698100Y821600D03*
X696482Y830301D03*
X683884D03*
X693282D03*
X680684D03*
X703900Y866100D03*
X697700D03*
X704331Y878276D03*
X698031D03*
X691733D03*
X685433D03*
X679134D03*
X672834D03*
X702400Y868800D03*
X690183Y875176D03*
X677585D03*
X699200Y868800D03*
X686983Y875176D03*
X674385D03*
X728395Y-7315D03*
X713461Y-3006D03*
X736308Y-7483D03*
X711919Y6754D03*
X729132Y3575D03*
X724018Y5719D03*
X729555Y33100D03*
X709120Y35980D03*
X719555Y33100D03*
X735186Y20714D03*
X729000Y24800D03*
X725314Y24751D03*
X721890Y24887D03*
X719008Y21999D03*
X707051Y12174D03*
X738384Y8232D03*
X722955Y33095D03*
X726155D03*
X727265Y52588D03*
X726646Y42651D03*
X721690Y53340D03*
X723200Y42300D03*
X726609Y49251D03*
Y46051D03*
X732900Y44900D03*
X730021Y42235D03*
X723501Y82680D03*
X723481Y76780D03*
X723610Y106430D03*
X723569Y100969D03*
X723659Y97292D03*
X723429Y91683D03*
X735157Y97005D03*
X735326Y102660D03*
X732500Y98421D03*
X720800Y102150D03*
Y93150D03*
Y78150D03*
X732500Y101621D03*
X720800Y105350D03*
Y96350D03*
Y81350D03*
X723438Y112700D03*
X723638Y118353D03*
X720800Y114150D03*
Y117350D03*
X713000Y310000D03*
X724400Y626500D03*
X712495Y816195D03*
X735640Y827374D03*
X723041D03*
X729713D03*
X727978Y830301D03*
X737377D03*
X724778D03*
X714900Y818600D03*
X729527Y878276D03*
X735827D03*
X723000Y878200D03*
X734277Y875176D03*
X731077D03*
X746329Y-7789D03*
X771715Y6840D03*
X752763Y38638D03*
X771600Y24200D03*
X741600Y41000D03*
X747000Y44300D03*
X762250Y44650D03*
X742290Y68550D03*
X750130Y63340D03*
X748300Y53800D03*
X772000Y64200D03*
X753500Y96600D03*
X755700Y79100D03*
X749800Y91400D03*
X753700Y102900D03*
X759600Y79200D03*
X762400Y127600D03*
X753500Y110900D03*
X769400Y111900D03*
X743490Y111940D03*
X765000Y112800D03*
X768777Y171450D03*
X761242Y169242D03*
X765579D03*
X771400Y185919D03*
X766244Y185897D03*
X748237Y194042D03*
X751737D03*
X766950Y189252D03*
X763562Y189539D03*
X770385Y189165D03*
X749337Y212192D03*
X746037Y213992D03*
X746237Y210392D03*
X743500Y362000D03*
X753000Y359000D03*
X743000Y598000D03*
X773435Y827374D03*
X754910D03*
X748238D03*
X742312D03*
X760837D03*
X767509D03*
X765774Y830301D03*
X753175D03*
X740577D03*
X762574D03*
X749975D03*
X754724Y878276D03*
X761024D03*
X767323D03*
X742126D03*
X748426D03*
X772073Y875176D03*
X759474D03*
X746876D03*
X768873D03*
X756274D03*
X743676D03*
X790150Y-1400D03*
X788408Y-4321D03*
X798061Y-6439D03*
X788550Y29350D03*
X806152Y51692D03*
X791300Y74200D03*
X775381Y66115D03*
X778800Y66388D03*
X782551Y67144D03*
X786333Y66963D03*
X781500Y85100D03*
X797800Y104500D03*
X776538Y107162D03*
X773900Y138300D03*
X791200Y125300D03*
X796051Y175147D03*
X806665Y174050D03*
X803265D03*
X792760Y176043D03*
X799000Y196000D03*
X802200D03*
X796089Y181182D03*
X775397Y179165D03*
Y184215D03*
X792390Y199166D03*
X786463Y199019D03*
X803169Y198850D03*
X797890Y198918D03*
X792000Y195778D03*
X787600Y195804D03*
X773984Y189118D03*
X792760Y180443D03*
X778807Y183890D03*
Y179490D03*
X780800Y545900D03*
X786033Y827374D03*
X780107D03*
X792705D03*
X798632D03*
X805304D03*
X803569Y830301D03*
X790970D03*
X778372D03*
X800369D03*
X787770D03*
X775172D03*
X779921Y878276D03*
X786221D03*
X792519D03*
X798819D03*
X805118D03*
X773623D03*
X797270Y875176D03*
X784671D03*
X806668D03*
X794070D03*
X781471D03*
X807514Y2199D03*
X813900Y12900D03*
X830773Y9000D03*
X834227D03*
X831592Y34411D03*
X838252Y20800D03*
X834500D03*
X830500D03*
X828283Y24734D03*
X824462Y25770D03*
X821877Y21090D03*
X823996Y44276D03*
X832401Y46472D03*
X831125Y67775D03*
X820004Y44234D03*
X828700Y48800D03*
X808114Y67634D03*
X816043Y94981D03*
Y99318D03*
X823551Y80551D03*
X819000Y97100D03*
X809000Y76000D03*
X810000Y109400D03*
X833900Y467000D03*
X812500Y499400D03*
X840500Y735500D03*
X837000D03*
X839990Y789230D03*
X836427Y827374D03*
X817902D03*
X811230D03*
X816167Y830301D03*
X838164D03*
X812967D03*
X836615Y878276D03*
X830315D03*
X811418D03*
X820000Y878200D03*
X835065Y875176D03*
X809868D03*
X831865D03*
X861000Y350D03*
X857453Y303D03*
X867600Y2500D03*
X863300Y23575D03*
X851100Y9100D03*
X855489Y9811D03*
X859300Y9900D03*
X874300Y18875D03*
X858500Y40000D03*
Y32000D03*
X869447Y31024D03*
X843500Y9150D03*
X849051Y20908D03*
X845052Y20800D03*
X841652D03*
X858500Y28000D03*
X858100Y21400D03*
X858500Y36000D03*
X847000Y9100D03*
X870600Y18915D03*
X854252Y20800D03*
X851870Y52160D03*
X859200Y47100D03*
X847337Y46563D03*
X851300Y45748D03*
X848623Y70757D03*
X852019Y70589D03*
X855421Y70551D03*
X858821Y70614D03*
X859000Y43500D03*
X871550Y56450D03*
X858800Y52200D03*
X868800Y49200D03*
X844900Y85100D03*
X868800Y85300D03*
X871696Y87082D03*
X868200Y116000D03*
X846702Y117371D03*
X854400Y117500D03*
X861300Y117800D03*
X851500Y705500D03*
X864800Y707700D03*
X868200D03*
X852500Y718000D03*
X847500Y717500D03*
X857406Y745598D03*
X861406Y745531D03*
X852895Y748648D03*
X869406Y745531D03*
X848000Y735500D03*
X865406Y745598D03*
X873367Y745335D03*
X844000Y735500D03*
X855500Y775500D03*
X844150Y762150D03*
X858695Y759900D03*
X871000Y776500D03*
X854049Y757573D03*
X857406Y755198D03*
X861406D03*
X858126Y763600D03*
X841500Y771000D03*
X874000Y772000D03*
X869562Y758457D03*
X844500Y758000D03*
X867410Y755824D03*
X849906Y804531D03*
X865378Y804431D03*
X851890Y789270D03*
X870900Y812104D03*
X866878Y794531D03*
X853500Y798000D03*
X846706Y797648D03*
X870278Y794531D03*
X874570Y811820D03*
X861406Y804403D03*
X857406D03*
X855697Y827374D03*
X849025D03*
X843099D03*
X853962Y830301D03*
X841364D03*
X850762D03*
X861823Y853696D03*
X849213Y878276D03*
X842913D03*
X856000Y878200D03*
X847663Y875176D03*
X844463D03*
X883800Y-500D03*
X881700Y2300D03*
X899769Y4355D03*
X904262Y14894D03*
X887800Y40100D03*
X880883Y30583D03*
X892745Y9681D03*
X896500Y9500D03*
X877500Y23600D03*
X900250Y38150D03*
X888474Y9173D03*
X900200Y9600D03*
X883800Y41400D03*
X907750Y51750D03*
X894110Y49250D03*
X878800Y49600D03*
X875050Y56250D03*
X895080Y52828D03*
X900501Y48705D03*
X883700Y50700D03*
X905488Y54479D03*
X890000Y97800D03*
X897000Y96700D03*
X878394Y85780D03*
X875001Y86003D03*
X901899Y85942D03*
X892900Y85300D03*
X885042Y85292D03*
X888600Y85700D03*
X897600Y85500D03*
X876378Y122047D03*
Y125984D03*
X880315Y118110D03*
Y122047D03*
Y125984D03*
X884252Y122047D03*
Y125984D03*
X876378Y251968D03*
Y255905D03*
X880315Y251968D03*
Y255905D03*
Y259842D03*
X884252Y251968D03*
Y255905D03*
X908500Y270500D03*
Y275000D03*
Y267000D03*
X907500Y325000D03*
X902500Y370000D03*
X897000Y370500D03*
X907500Y368000D03*
X900999Y748550D03*
X885400Y743600D03*
X895800Y738400D03*
X893400Y745100D03*
X884700Y721100D03*
X896500Y734000D03*
X877000Y745000D03*
X892100Y721100D03*
X881200Y721300D03*
X888400Y721400D03*
X900824Y781531D03*
X895278Y758885D03*
X874887Y759253D03*
X884671Y775500D03*
X889900Y769600D03*
X884778Y756198D03*
X876036Y755481D03*
X894465Y755501D03*
X891056Y755641D03*
X882227Y758835D03*
X885167Y816593D03*
X894200Y794500D03*
X877930Y796880D03*
X876470Y808710D03*
X906396Y810300D03*
X886288Y794372D03*
X898700Y794200D03*
Y816000D03*
X882290Y796770D03*
X881720Y807390D03*
X906450Y806900D03*
X906092Y813687D03*
X884412Y835051D03*
X894406Y818000D03*
X888100Y823338D03*
X890200Y819200D03*
X912000Y41000D03*
X927250Y31450D03*
X911800Y37000D03*
X938000Y30300D03*
X919400Y33300D03*
X915486Y41030D03*
X918952Y40680D03*
X912000Y45000D03*
X939064Y58104D03*
X934881Y57322D03*
X909797Y55037D03*
X910000Y85300D03*
X937642Y85562D03*
X926093Y85239D03*
X929213Y86593D03*
X934438Y86700D03*
X919050Y85500D03*
X913979Y86580D03*
X935000Y97400D03*
X927100Y96900D03*
X929800Y105900D03*
X909000Y279000D03*
X909500Y283000D03*
Y338000D03*
X909000Y353600D03*
X908700Y347300D03*
X938898Y640169D03*
X916319Y678588D03*
Y658588D03*
Y698588D03*
Y738588D03*
Y718588D03*
Y778588D03*
Y758588D03*
Y798588D03*
Y818588D03*
X969100Y14600D03*
X942500Y30100D03*
X974100Y19600D03*
X970064Y18764D03*
X963700Y21700D03*
X959877Y26978D03*
X967180Y66705D03*
X952500Y75100D03*
X949102Y74964D03*
X947900Y67900D03*
X959300Y68600D03*
Y72000D03*
X964105Y62308D03*
X959855Y61107D03*
X956687Y85482D03*
X942800Y85700D03*
X948200Y85900D03*
X953301Y85793D03*
X956500Y108000D03*
X949500Y103000D03*
Y97500D03*
X949893Y106378D03*
X949828Y109778D03*
X957800Y570300D03*
X960500Y607000D03*
X953500D03*
X956900D03*
X958898Y640169D03*
X976500Y4500D03*
X1008353Y-1940D03*
X985579Y26494D03*
X985403Y22993D03*
X980100Y14500D03*
X1000985Y29307D03*
X1007921Y39585D03*
X985315Y14425D03*
X997385Y29307D03*
X994650Y39880D03*
X992396Y45073D03*
X990628Y49698D03*
X997007Y49560D03*
X1008508Y47704D03*
X982500Y271500D03*
Y275500D03*
X982000Y267500D03*
X983500Y279500D03*
Y283500D03*
X1006100Y528700D03*
X977500Y550000D03*
X978898Y640169D03*
X994248Y665818D03*
Y685818D03*
Y705818D03*
Y745818D03*
Y725818D03*
Y765818D03*
Y805818D03*
Y785818D03*
X1025700Y7600D03*
X1022711Y-4975D03*
X1012177Y-2940D03*
X1019859Y-7642D03*
X1033017Y14743D03*
X1024330Y34379D03*
X1040218Y32140D03*
X1010229Y19022D03*
X1022300Y13900D03*
X1033554Y30216D03*
X1040121Y26870D03*
X1039822Y35743D03*
X1017908Y41556D03*
X1018900Y14198D03*
X1010975Y29017D03*
X1029553Y13981D03*
X1030139Y30209D03*
X1024432Y43718D03*
X1035783Y51473D03*
X1017863Y45056D03*
X1011300Y53000D03*
X1024318Y51554D03*
X1014700Y53700D03*
X1040241Y61043D03*
X1033517Y48934D03*
X1036854Y47110D03*
X1019900Y108500D03*
X1015948D03*
X1034500D03*
X1027483Y108431D03*
X1024000Y108500D03*
X1037900D03*
X1041300D03*
X1030883Y108438D03*
X1010236Y122047D03*
Y125984D03*
X1014173Y118110D03*
Y122047D03*
Y125984D03*
X1018110Y122047D03*
Y125984D03*
X1010236Y251968D03*
Y255905D03*
X1014173Y251968D03*
Y255905D03*
Y259842D03*
X1018110Y251968D03*
Y255905D03*
X1028500Y257500D03*
X1012600Y476700D03*
X1022600Y542100D03*
X1017800Y572700D03*
X1043300Y631300D03*
X1041500Y682000D03*
X1041900Y658100D03*
X1039577Y827374D03*
X1041314Y830301D03*
X1024004Y855893D03*
X1033464Y878276D03*
X1039764D03*
X1038214Y875176D03*
X1035014D03*
X1062044Y-4173D03*
X1065620Y-4335D03*
X1072800Y-800D03*
X1069261Y-14185D03*
X1049261D03*
X1045850Y6228D03*
X1069200Y-4200D03*
X1060800Y10100D03*
X1061253Y17487D03*
X1062470Y31823D03*
X1062433Y37099D03*
X1056049Y18396D03*
X1061153Y27488D03*
X1046200Y24500D03*
X1054835Y40386D03*
X1072140Y16447D03*
X1047429Y15229D03*
X1044050Y28815D03*
X1062088Y40597D03*
X1072804Y19894D03*
X1064900Y10400D03*
X1065700Y32888D03*
Y36088D03*
X1061200Y20888D03*
Y24088D03*
X1056200Y10100D03*
X1065657Y28946D03*
X1047500Y41500D03*
X1051000D03*
X1076970Y30411D03*
X1052600Y14400D03*
X1054210Y53370D03*
X1054090Y58470D03*
X1068315Y56120D03*
X1068390Y61611D03*
X1074103Y44988D03*
X1049772Y57259D03*
X1049470Y53749D03*
X1050875Y61090D03*
X1057000Y54500D03*
X1071135Y60375D03*
X1057000Y57700D03*
X1071135Y57175D03*
X1057000Y107700D03*
X1057259Y77276D03*
X1048100Y108500D03*
X1044700D03*
X1061000Y111000D03*
X1053000Y109500D03*
X1047000Y644000D03*
X1045000Y617500D03*
X1067000Y711000D03*
X1062500Y738000D03*
X1058500Y758000D03*
X1058847Y827374D03*
X1052175D03*
X1046249D03*
X1064774D03*
X1071446D03*
X1069711Y830301D03*
X1057112D03*
X1044514D03*
X1066511D03*
X1053912D03*
X1046063Y878276D03*
X1071260D03*
X1064961D03*
X1058661D03*
X1052363D03*
X1076010Y875176D03*
X1050813D03*
X1072810D03*
X1047613D03*
X1084000Y500D03*
X1089261Y-14185D03*
X1083315Y36654D03*
X1082808Y30601D03*
X1092094Y30362D03*
X1080672Y9500D03*
X1084800Y9400D03*
X1083379Y40889D03*
X1083500Y25500D03*
X1082974Y14467D03*
X1105441Y54768D03*
X1100992Y52374D03*
X1078694Y43478D03*
X1103424Y67690D03*
X1077432Y64225D03*
X1103300Y73900D03*
X1103349Y70700D03*
X1088005Y46541D03*
X1088287Y55917D03*
X1096496Y51226D03*
X1110664Y78483D03*
X1103253Y76910D03*
X1079500Y631000D03*
X1080000Y650500D03*
X1081000Y670000D03*
X1084044Y827374D03*
X1077372D03*
X1102569D03*
X1109241D03*
X1089970D03*
X1096642D03*
X1107506Y830301D03*
X1094907D03*
X1082309D03*
X1104306D03*
X1091707D03*
X1079109D03*
X1090158Y878276D03*
X1083858D03*
X1077560D03*
X1096456D03*
X1102756D03*
X1109055D03*
X1101207Y875176D03*
X1088608D03*
X1110605D03*
X1098007D03*
X1085408D03*
X1127300Y46300D03*
X1122800Y55100D03*
X1132100Y56300D03*
X1131900Y70700D03*
X1140900Y71100D03*
X1141900Y63300D03*
X1142418Y78638D03*
X1131800Y85600D03*
X1141200Y86800D03*
X1126400Y92200D03*
X1143500Y93300D03*
X1123000Y99200D03*
X1131880Y100377D03*
X1134800Y93300D03*
X1116933Y85243D03*
X1112700Y80700D03*
X1114842Y83078D03*
X1122001Y126574D03*
Y136874D03*
X1135150Y137851D03*
X1122001Y133324D03*
X1141900Y137851D03*
X1122001Y130124D03*
X1138700Y137851D03*
X1126500Y222500D03*
X1135750Y228750D03*
X1143000Y242000D03*
X1140364Y827374D03*
X1121839D03*
X1115167D03*
X1127766D03*
X1134438D03*
X1132703Y830301D03*
X1120104D03*
X1142101D03*
X1129503D03*
X1116904D03*
X1140552Y878276D03*
X1115355D03*
X1127953D03*
X1134252D03*
X1121653D03*
X1139002Y875176D03*
X1126403D03*
X1113805D03*
X1135802D03*
X1123203D03*
X1175300Y71100D03*
X1175100Y55700D03*
X1166500Y56200D03*
X1171700Y45900D03*
X1149100Y46300D03*
X1150700Y63300D03*
X1148900Y75900D03*
X1168400Y103000D03*
X1177000Y102800D03*
X1176200Y92900D03*
X1178100Y78000D03*
X1175200Y85900D03*
X1151492Y78668D03*
X1164857Y138505D03*
X1154557D03*
X1145450Y137851D03*
X1175851Y142410D03*
X1161307Y138505D03*
X1158107D03*
X1170400Y144100D03*
X1150250Y228750D03*
X1147000Y242000D03*
X1151000D03*
X1161700Y818500D03*
X1159634Y827374D03*
X1152962D03*
X1147036D03*
X1175010D03*
X1174900Y818300D03*
X1157899Y830301D03*
X1145301D03*
X1176747D03*
X1154699D03*
X1159448Y878276D03*
X1153150D03*
X1173623Y878200D03*
X1146850Y878276D03*
X1165748D03*
X1164199Y875176D03*
X1151600D03*
X1160999D03*
X1148400D03*
X1185200Y72600D03*
X1210511Y52300D03*
X1193555Y61875D03*
X1183884Y61598D03*
X1188200Y61600D03*
X1192300Y46100D03*
X1184100Y56100D03*
X1193900Y78000D03*
X1211500Y102900D03*
X1194000Y93200D03*
X1185800Y102900D03*
X1185100Y93000D03*
X1187100Y77900D03*
X1184800Y87200D03*
X1202410Y142850D03*
X1193845Y137855D03*
X1184629Y137740D03*
X1185070Y142384D03*
X1182061Y142478D03*
X1190835Y137899D03*
X1199400Y142851D03*
X1178861Y142478D03*
X1187635Y137899D03*
X1196200Y142851D03*
X1210391Y156730D03*
X1200391Y156779D03*
X1193192Y142970D03*
X1206991Y156730D03*
X1203791D03*
X1205500Y334400D03*
X1201000Y417900D03*
X1196600Y416200D03*
X1194280Y827374D03*
X1187608D03*
X1181682D03*
X1192545Y830301D03*
X1179947D03*
X1189345D03*
X1200735Y864273D03*
X1194063D03*
X1200394Y878276D03*
X1194094D03*
X1187796D03*
X1181496D03*
X1199000Y867200D03*
X1186246Y875176D03*
X1195800Y867300D03*
X1183046Y875176D03*
X1231400Y58300D03*
X1215400Y57600D03*
X1216300Y72900D03*
X1235800Y46400D03*
X1228000Y57000D03*
X1218600Y56000D03*
X1214700Y46000D03*
X1221200Y63400D03*
X1230300Y63200D03*
X1228900Y72900D03*
X1230000Y78800D03*
X1221300Y78400D03*
X1219200Y87000D03*
X1229100Y87900D03*
X1232500Y90900D03*
X1229900Y103100D03*
X1228300Y93100D03*
X1219500Y93300D03*
X1220100Y102700D03*
X1219138Y137928D03*
X1227999Y142465D03*
X1236692Y137720D03*
X1237219Y142420D03*
X1228359Y137960D03*
X1214795Y142443D03*
X1234209Y142463D03*
X1242900Y137851D03*
X1225348Y137960D03*
X1231009Y142463D03*
X1239700Y137851D03*
X1222148Y137960D03*
X1242621Y153690D03*
X1226000Y261300D03*
X1242000Y343000D03*
X1235400Y364400D03*
X1213400Y355400D03*
X1214100Y469800D03*
X1237800Y524500D03*
X1232300Y568900D03*
X1238375Y827374D03*
X1231703D03*
X1219105D03*
X1225777D03*
X1244302D03*
X1236640Y830301D03*
X1224042D03*
X1233440D03*
X1220842D03*
X1217717Y878076D03*
X1225590Y878276D03*
X1231890D03*
X1244489D03*
X1238189D03*
X1242939Y875176D03*
X1230340D03*
X1239739D03*
X1227140D03*
X1261900Y71039D03*
X1265500Y61900D03*
X1272200Y72900D03*
X1275200Y61200D03*
X1269900Y61100D03*
X1279100Y46300D03*
X1272200Y57900D03*
X1258400Y45900D03*
X1254500Y51100D03*
X1271300Y77100D03*
X1273200Y103200D03*
X1256000Y103300D03*
X1263200Y102700D03*
X1270300Y91100D03*
X1262800Y93100D03*
X1254200Y96300D03*
X1275500Y91000D03*
X1272700Y88000D03*
X1265200Y77400D03*
X1261900Y86000D03*
X1275800Y75900D03*
X1252768Y141181D03*
X1278160Y140547D03*
X1257899Y142881D03*
X1245910Y137810D03*
X1273068Y140514D03*
X1277265Y137673D03*
X1274065D03*
X1262880Y142909D03*
X1273499Y151498D03*
X1273520Y148070D03*
X1261944Y145770D03*
X1258744D03*
X1251801Y144871D03*
X1275500Y264500D03*
X1258500Y335500D03*
X1266500D03*
X1255000Y317300D03*
X1270500Y335500D03*
X1272500Y350000D03*
X1275060Y345690D03*
X1277620Y349500D03*
X1264820Y349320D03*
X1273500Y397000D03*
X1257500D03*
X1254000D03*
X1249250Y390250D03*
X1269500Y397000D03*
X1273500Y400500D03*
X1258000Y421500D03*
X1259200Y471800D03*
X1259000Y680000D03*
X1265000Y672000D03*
X1253500D03*
X1278000Y689000D03*
X1263572Y827374D03*
X1269498D03*
X1276170D03*
X1256900D03*
X1250974D03*
X1274435Y830301D03*
X1261837D03*
X1249239D03*
X1271235D03*
X1258637D03*
X1246039D03*
X1263386Y878276D03*
X1275984D03*
X1257087D03*
X1269686D03*
X1250787D03*
X1268136Y875176D03*
X1255537D03*
X1277534D03*
X1264936D03*
X1252337D03*
X1303983Y22083D03*
X1304000Y44000D03*
Y67500D03*
Y90500D03*
X1291660Y140257D03*
X1297360Y140172D03*
X1301749Y125479D03*
X1286543Y141581D03*
X1296017Y137478D03*
X1283343Y141581D03*
X1292817Y137478D03*
X1282189Y144361D03*
X1287637Y144386D03*
X1297668Y155524D03*
X1290870Y186285D03*
X1311181Y186548D03*
X1290000Y271000D03*
X1308500Y262500D03*
X1311200Y256500D03*
X1293500Y271000D03*
X1312200Y275200D03*
X1303700Y289500D03*
X1288900Y304000D03*
X1283300Y302900D03*
X1309900Y292400D03*
X1310500Y285500D03*
X1297500Y351800D03*
X1281900Y346580D03*
X1282740Y350010D03*
X1311500Y391000D03*
X1310068Y394084D03*
X1297625Y382375D03*
X1296500Y386500D03*
X1290125Y382875D03*
X1289500Y386500D03*
X1282740Y383000D03*
X1282000Y386500D03*
X1291600Y495200D03*
X1296400Y542400D03*
X1294700Y593400D03*
X1301000Y618500D03*
X1300000Y637000D03*
X1302128Y674067D03*
X1306128Y674000D03*
X1297617Y677117D03*
X1286800Y671100D03*
X1297500Y664000D03*
X1310207D03*
X1297400Y651300D03*
X1290550D03*
X1285000Y694000D03*
X1280500Y706000D03*
X1310376Y687205D03*
X1301728Y711200D03*
X1302000Y695500D03*
X1302128Y685500D03*
X1307000Y686500D03*
X1304500Y698000D03*
X1301728Y714600D03*
X1312132Y684293D03*
X1310100Y732900D03*
X1294628Y733000D03*
X1310500Y723000D03*
X1291428Y726117D03*
X1306128Y732872D03*
X1302128D03*
X1304800Y811900D03*
X1288768Y827374D03*
X1282096D03*
X1307294D03*
X1312231Y830301D03*
X1287033D03*
X1309031D03*
X1283833D03*
X1301800Y878100D03*
X1294268Y872169D03*
X1288582Y878276D03*
X1282284D03*
X1307481D03*
X1305931Y875176D03*
X1293333D03*
X1280734D03*
X1302731D03*
X1290133D03*
X1324845Y130527D03*
X1339471Y139268D03*
X1325429Y148270D03*
X1316590Y147210D03*
X1317400Y143620D03*
X1340130Y145980D03*
X1331243Y182198D03*
X1337000Y263250D03*
X1332000Y261500D03*
Y265000D03*
Y268500D03*
Y272500D03*
Y257500D03*
Y254000D03*
X1342000D03*
Y257500D03*
Y261500D03*
Y265000D03*
Y268500D03*
Y272500D03*
X1337000Y267500D03*
Y272000D03*
Y259000D03*
Y254500D03*
X1322000Y276500D03*
X1322500Y266800D03*
X1333500Y290500D03*
X1317026Y304858D03*
X1322250Y282250D03*
X1314000Y286500D03*
X1345850Y676750D03*
X1313607Y664000D03*
X1327200Y661800D03*
X1331000Y662000D03*
X1326128Y674000D03*
X1340000D03*
X1317007Y664000D03*
X1334128Y674000D03*
X1333500Y709500D03*
X1323076Y686999D03*
X1338200Y689800D03*
X1315546Y709500D03*
X1341400Y686900D03*
X1337500Y698000D03*
X1322439Y697767D03*
X1315000Y686500D03*
X1329500Y684667D03*
X1321928Y683798D03*
X1318500Y684667D03*
X1339934Y683832D03*
X1336795Y685141D03*
X1326758Y686678D03*
X1314628Y733000D03*
X1315000Y723000D03*
X1326661Y740700D03*
X1333500Y723000D03*
X1334128Y732667D03*
X1325600Y722987D03*
X1342000Y732500D03*
X1337500Y723000D03*
X1340500Y742500D03*
X1338128Y732872D03*
X1330128Y732667D03*
X1345088Y827374D03*
X1332490D03*
X1339162D03*
X1326564D03*
X1319892D03*
X1313966D03*
X1337427Y830301D03*
X1324829D03*
X1346825D03*
X1334227D03*
X1321629D03*
X1320079Y878276D03*
X1345276D03*
X1332678D03*
X1338976D03*
X1326378D03*
X1313779D03*
X1343726Y875176D03*
X1331128D03*
X1318529D03*
X1340526D03*
X1327928D03*
X1315329D03*
X1368028Y175745D03*
X1359128Y167226D03*
X1355321Y172119D03*
X1354971Y167446D03*
X1365804Y185197D03*
X1368300Y267800D03*
X1358662Y275485D03*
X1355066Y275228D03*
X1348500Y276500D03*
X1361500Y273500D03*
X1352000Y276700D03*
X1352500Y267000D03*
X1369300Y259300D03*
X1355000Y286300D03*
X1364000Y280500D03*
X1369700Y424600D03*
X1366000Y472900D03*
X1363900Y537600D03*
X1361800Y596800D03*
X1358700Y655700D03*
X1351500Y675000D03*
X1348500Y713000D03*
X1377000Y725000D03*
X1378000Y806900D03*
X1369925Y835051D03*
X1351760Y827374D03*
X1350025Y830301D03*
X1357886Y864246D03*
X1352200Y878400D03*
X1394500Y139626D03*
Y119626D03*
Y159626D03*
X1381696Y173459D03*
X1387196Y174160D03*
X1394500Y199626D03*
Y179626D03*
X1381568Y180579D03*
X1382138Y184129D03*
X1385467Y180543D03*
X1394500Y239626D03*
Y219626D03*
Y259626D03*
Y299626D03*
Y279626D03*
Y339626D03*
Y319626D03*
Y359626D03*
Y399626D03*
Y379626D03*
Y439626D03*
Y419626D03*
Y479626D03*
Y459626D03*
Y499626D03*
Y539626D03*
Y519626D03*
Y579626D03*
Y559626D03*
Y599626D03*
Y639626D03*
Y619626D03*
Y679626D03*
Y659626D03*
Y699626D03*
Y739626D03*
Y719626D03*
Y759626D03*
Y779626D03*
Y799626D03*
Y819626D03*
X1389925Y835051D03*
G54D122*
X272979Y354640D03*
X291479D03*
G54D21*
X28148Y310872D03*
X28212Y306674D03*
X21800Y424000D03*
X29300Y429000D03*
X30600Y533500D03*
X25100Y720400D03*
X41600Y321400D03*
X36800Y466000D03*
X57400Y470100D03*
Y474200D03*
X63569Y502220D03*
X37300Y484500D03*
X55400Y713000D03*
X97900Y272000D03*
X95607Y281582D03*
X76291Y365075D03*
X76105Y360727D03*
X85700Y360000D03*
X80990Y392665D03*
X93649Y477241D03*
X79569Y513090D03*
X80444Y508831D03*
X92300Y506000D03*
X80444Y504831D03*
X92300Y526500D03*
Y522500D03*
Y530500D03*
X79569Y517090D03*
X92300Y534500D03*
Y518500D03*
Y538500D03*
X80800Y534300D03*
Y538300D03*
X67720Y535931D03*
Y531831D03*
X80300Y606500D03*
X73800Y582000D03*
X79900Y681900D03*
X87500D03*
X75800Y723200D03*
X79600Y753700D03*
Y757900D03*
X107100Y212200D03*
X106100Y230100D03*
X100800Y294900D03*
Y290900D03*
X100490Y319780D03*
X100540Y315650D03*
X100700Y324100D03*
X100600Y328600D03*
X123000Y392300D03*
X99200Y732300D03*
X114800Y756000D03*
X132480Y311214D03*
X154100Y402200D03*
X162627Y447721D03*
X143369Y636620D03*
X133851Y648436D03*
X137200Y727800D03*
X164000Y753400D03*
X156800Y808500D03*
X179139Y450747D03*
X196300Y729500D03*
Y785000D03*
X207749Y143587D03*
X202900Y251000D03*
X213500Y446000D03*
X219800Y469000D03*
Y465000D03*
X209800Y478000D03*
X218300Y486600D03*
X209800Y502000D03*
Y506000D03*
X223950Y491200D03*
X223962Y495300D03*
X209800Y534500D03*
Y542500D03*
Y538500D03*
Y550500D03*
Y570500D03*
X222672Y563994D03*
X248400Y339700D03*
X261529Y334140D03*
X257500Y443300D03*
X277800Y126000D03*
X285340Y149350D03*
X277800Y145500D03*
X294288Y578165D03*
Y583165D03*
Y588665D03*
X309082Y293550D03*
X333100Y318900D03*
X315700Y538300D03*
X344000Y335600D03*
X483260Y13180D03*
X483270Y26720D03*
X483300Y49880D03*
Y73380D03*
X469960Y143008D03*
X490900Y166000D03*
X473000Y393300D03*
X504242Y130547D03*
X535012Y159035D03*
X534925Y163463D03*
X505100Y186500D03*
X550780Y133550D03*
X545999Y291069D03*
X558331Y342980D03*
X581363Y228608D03*
X589763Y211308D03*
X619863Y209608D03*
X627463Y209408D03*
Y217608D03*
X622163Y238108D03*
X627463Y213508D03*
X605000Y348200D03*
X652300Y340100D03*
X659800D03*
X652300Y344600D03*
Y372100D03*
Y376600D03*
X659800D03*
X652300Y367100D03*
Y362100D03*
Y352600D03*
Y348600D03*
X733100Y14000D03*
X735400Y114020D03*
X735380Y109410D03*
X756400Y35100D03*
Y26200D03*
X764200D03*
X753800Y64000D03*
X767500Y74000D03*
X757900Y98800D03*
Y94700D03*
X765500Y129400D03*
Y125300D03*
X797610Y26343D03*
X784200Y74100D03*
X806800Y82400D03*
X806900Y94600D03*
Y98700D03*
X773600Y135200D03*
X827860Y105630D03*
X811725Y123631D03*
Y127631D03*
X860500Y3900D03*
X861800Y28000D03*
Y36000D03*
X862300Y8000D03*
X871300Y52800D03*
X862133Y44034D03*
X904800Y33000D03*
Y29000D03*
Y41000D03*
X900300Y341600D03*
Y363000D03*
Y354000D03*
X927270Y23540D03*
X984717Y18587D03*
X1033621Y26921D03*
X1011778Y49109D03*
X1048786Y11208D03*
X1075776Y18266D03*
X1074300Y68500D03*
X1054660Y69355D03*
X1062483Y48832D03*
X1087300Y500D03*
Y5000D03*
X1086920Y27440D03*
X1087304Y36383D03*
X1086920Y22940D03*
X1087304Y40883D03*
X1086525Y14177D03*
X1086727Y18525D03*
X1244784Y145217D03*
X1246268Y141179D03*
X1310110Y145310D03*
X1310826Y151199D03*
X1289300Y295000D03*
X1325300Y290500D03*
X1317300Y294000D03*
X1363218Y168102D03*
G54D105*
X242129Y41754D03*
G54D141*
X626110Y366593D03*
Y346607D03*
X639890D03*
Y366593D03*
G54D123*
X298306Y735298D03*
X295746D03*
X293186D03*
X290626D03*
X288066D03*
X285506D03*
X282946D03*
X280386D03*
X277826D03*
Y757498D03*
X280386D03*
X282946D03*
X285506D03*
X288066D03*
X290626D03*
X293186D03*
X295746D03*
X298306D03*
X305986Y735298D03*
X303426D03*
X300866D03*
Y757498D03*
X303426D03*
X305986D03*
X461440Y84600D03*
X464000D03*
X466560D03*
X469120D03*
Y106800D03*
X466560D03*
X464000D03*
X461440D03*
X471680Y84600D03*
X474240D03*
X476800D03*
X479360D03*
Y106800D03*
X476800D03*
X474240D03*
X471680D03*
X491326Y809498D03*
X493886D03*
X496446D03*
X499006D03*
X501566D03*
Y787298D03*
X499006D03*
X496446D03*
X493886D03*
X491326D03*
X504126Y809498D03*
X506686D03*
X509246D03*
X511806D03*
X514366D03*
X516926D03*
X519486D03*
Y787298D03*
X516926D03*
X514366D03*
X511806D03*
X509246D03*
X506686D03*
X504126D03*
X873626Y764298D03*
X871066D03*
X868506D03*
X865946D03*
X863386D03*
X860826D03*
Y786498D03*
X863386D03*
X865946D03*
X868506D03*
X871066D03*
X873626D03*
X891660Y334690D03*
X894220D03*
X896780D03*
X899340D03*
Y318510D03*
X896780D03*
X894220D03*
X891660D03*
X888986Y764298D03*
X886426D03*
X883866D03*
X881306D03*
X878746D03*
X876186D03*
Y786498D03*
X878746D03*
X881306D03*
X883866D03*
X886426D03*
X888986D03*
X1007253Y13707D03*
X1004753D03*
X1002253D03*
X999753D03*
X997253D03*
Y34307D03*
X999753D03*
X1002253D03*
X1004753D03*
X1007253D03*
X1014753Y13707D03*
X1012253D03*
X1009753D03*
Y34307D03*
X1012253D03*
X1014753D03*
X1264820Y377500D03*
X1267380D03*
X1269940D03*
X1272500D03*
X1275060D03*
X1277620D03*
Y355300D03*
X1275060D03*
X1272500D03*
X1269940D03*
X1267380D03*
X1264820D03*
X1280180Y377500D03*
X1282740D03*
X1285300D03*
X1287860D03*
X1290420D03*
X1292980D03*
Y355300D03*
X1290420D03*
X1287860D03*
X1285300D03*
X1282740D03*
X1280180D03*
X1305548Y714967D03*
X1308108D03*
X1310668D03*
Y692767D03*
X1308108D03*
X1305548D03*
X1313228Y714967D03*
X1315788D03*
X1318348D03*
X1320908D03*
X1323468D03*
X1326028D03*
X1328588D03*
X1331148D03*
X1333708D03*
Y692767D03*
X1331148D03*
X1328588D03*
X1326028D03*
X1323468D03*
X1320908D03*
X1318348D03*
X1315788D03*
X1313228D03*
G54D114*
X249857Y142157D03*
Y144126D03*
Y146094D03*
Y148063D03*
Y150031D03*
Y152000D03*
Y153969D03*
Y155937D03*
Y157906D03*
Y159874D03*
Y161843D03*
X269143D03*
Y159874D03*
Y157906D03*
Y155937D03*
Y153969D03*
Y152000D03*
Y150031D03*
Y148063D03*
Y146094D03*
Y144126D03*
Y142157D03*
X593120Y231015D03*
Y232984D03*
Y234952D03*
Y236921D03*
Y238889D03*
Y240858D03*
Y242827D03*
Y244795D03*
Y246764D03*
Y248732D03*
Y250701D03*
X612406Y242827D03*
Y240858D03*
Y238889D03*
Y236921D03*
Y234952D03*
Y232984D03*
Y231015D03*
Y250701D03*
Y248732D03*
Y246764D03*
Y244795D03*
X1346643Y273093D03*
Y271124D03*
Y269156D03*
Y267187D03*
Y265219D03*
Y263250D03*
Y261281D03*
Y259313D03*
Y257344D03*
Y255376D03*
Y253407D03*
X1327357D03*
Y255376D03*
Y257344D03*
Y259313D03*
Y261281D03*
Y263250D03*
Y265219D03*
Y267187D03*
Y269156D03*
Y271124D03*
Y273093D03*
G54D150*
X803264Y0D03*
X815634D03*
G54D12*
X31977Y126614D03*
Y116614D03*
X91189Y126614D03*
Y116614D03*
Y136614D03*
G54D30*
X25500Y420000D03*
X20025Y435203D03*
X29400Y738500D03*
X24000Y751200D03*
X46000Y292100D03*
X45882Y287141D03*
X41300Y307200D03*
X62900Y322300D03*
X56500Y372900D03*
X63500Y353960D03*
X34866Y390400D03*
X64800Y383400D03*
X60500Y439500D03*
X47500Y414000D03*
X60500Y417500D03*
X49000Y469400D03*
X59000Y454500D03*
X60810Y478441D03*
X31562Y465195D03*
X44000Y466500D03*
X31700Y481100D03*
X43046Y497465D03*
X59587Y511198D03*
X42534Y490525D03*
X63370Y498214D03*
X44500Y484000D03*
X52000Y501500D03*
Y484000D03*
X39616Y532255D03*
X64500Y615500D03*
X32498Y682487D03*
X61505Y689980D03*
X34831Y727839D03*
X34300Y732900D03*
X48700Y718195D03*
X35300Y738400D03*
X53700Y717250D03*
X42600Y718000D03*
X34800Y721900D03*
X37800Y745400D03*
X40200Y756200D03*
X35000Y756400D03*
X56100Y755900D03*
X50900Y756000D03*
X64400Y751800D03*
X45400Y756200D03*
X61300D03*
X90100Y266400D03*
X83300Y266800D03*
X75800Y269600D03*
X70000Y273000D03*
X80358Y274360D03*
X96677Y285294D03*
X94700Y335600D03*
X91300Y331600D03*
X96107Y324781D03*
X97838Y311989D03*
X96500Y316900D03*
X98400Y332400D03*
X85800Y355000D03*
X90093Y365200D03*
X67000Y377500D03*
X65965Y362838D03*
X84400Y406500D03*
X93314Y466166D03*
X88500Y509613D03*
X66473Y511404D03*
X73787Y522705D03*
X88727Y547047D03*
X88000Y538500D03*
X93100Y543638D03*
X71540Y518238D03*
X83600Y525700D03*
X81523Y521151D03*
X66494Y556916D03*
X88271Y552998D03*
X98008Y548438D03*
X96537Y555253D03*
X93400Y551200D03*
X65780Y586777D03*
X67508Y608289D03*
X83562Y610519D03*
X92000Y605500D03*
X78200Y646000D03*
X89600Y622600D03*
X73717Y632517D03*
X84000Y615500D03*
X85500Y706800D03*
X70700Y714000D03*
X85000Y714900D03*
X73800Y749600D03*
X71000Y719200D03*
X89600Y727900D03*
X73400Y741700D03*
X73900Y755200D03*
X111319Y195688D03*
X105300Y207900D03*
X111050Y207700D03*
X116300Y218100D03*
X128015Y219803D03*
X100688Y224517D03*
X107300Y272700D03*
X104000Y286200D03*
X124300Y305300D03*
X108385Y327857D03*
X131500Y340800D03*
X122963Y377696D03*
X119830Y348670D03*
X109285Y352411D03*
X130280Y389720D03*
X129694Y379247D03*
X112250Y385000D03*
X100400Y392184D03*
X130000Y397000D03*
X127633Y441705D03*
X131355Y437004D03*
X116300Y436400D03*
X120500Y461000D03*
X125500Y466000D03*
X128500Y456000D03*
X120680Y466020D03*
X102032Y475274D03*
X100000Y462700D03*
X115673Y464911D03*
X106983Y465035D03*
X111421Y467542D03*
X129076Y462500D03*
X107000Y472700D03*
X122406Y447830D03*
X102000Y497700D03*
X105045Y505292D03*
X107423Y500672D03*
X106258Y480600D03*
X99800Y511851D03*
X106000Y511600D03*
X99820Y505670D03*
X103313Y531239D03*
X99829Y527520D03*
X103100Y517400D03*
X103289Y523893D03*
X99476Y534446D03*
X103300Y537800D03*
X99164Y540611D03*
X103000Y555500D03*
X131500Y584000D03*
X104000Y627000D03*
X102020Y633720D03*
X119650Y707800D03*
X101800Y737200D03*
X102100Y723300D03*
X124800Y745300D03*
X120500Y752100D03*
X118600Y762500D03*
X98800Y764900D03*
X108200Y775800D03*
X112700Y775300D03*
Y770800D03*
X108200D03*
X103700D03*
Y775800D03*
Y766300D03*
X108200D03*
X112700D03*
X125900Y785000D03*
X119800Y813700D03*
X109500Y836500D03*
X162500Y222000D03*
X144300Y235400D03*
X137200Y302300D03*
X145300Y302200D03*
X158170Y314302D03*
X162670D03*
X153670D03*
X156170Y318302D03*
X160670D03*
X136257Y316125D03*
X145168Y317749D03*
X137768Y322641D03*
X145965Y374500D03*
X160850Y375200D03*
X138905Y368565D03*
X148900Y363200D03*
X160303Y365303D03*
X151760Y372214D03*
X157065Y395331D03*
X160204Y384199D03*
X137778Y401708D03*
X161800Y389700D03*
X132778Y401706D03*
X134768Y429438D03*
X133812Y414712D03*
X143073Y424833D03*
X164222Y457919D03*
X134090Y465780D03*
X138930Y465660D03*
X141500Y461400D03*
X158790Y458450D03*
X160300Y465900D03*
X164268Y462983D03*
X154700Y461100D03*
X154500Y466000D03*
X150174Y458541D03*
X149461Y466837D03*
X144520Y466070D03*
X163225Y720683D03*
X139642Y736317D03*
X139480Y724027D03*
X149241Y740242D03*
X156126Y775783D03*
X163600Y757500D03*
X156400Y812800D03*
X142492Y795526D03*
X166890Y237540D03*
X182604Y442854D03*
X192173Y466075D03*
X179599Y457479D03*
X170192Y465776D03*
X175000Y466000D03*
X177377Y461749D03*
X180000Y466000D03*
X168320Y455278D03*
X185200Y466000D03*
X198274Y473078D03*
X199510Y465568D03*
X197228Y478071D03*
X189275Y470882D03*
X169399Y470740D03*
X199829Y485947D03*
X198279Y496230D03*
X198223Y509744D03*
X197126Y490845D03*
X198803Y501591D03*
X198000Y529500D03*
Y534500D03*
Y523000D03*
X196882Y542190D03*
X176500Y571500D03*
X174500Y561500D03*
X178500Y576376D03*
X174500Y566500D03*
X193610Y578880D03*
X175360Y580890D03*
X177187Y586239D03*
X187750Y584750D03*
X187500Y596000D03*
X195788Y696965D03*
X175505Y720797D03*
X195900Y733400D03*
X181873Y716530D03*
X189913Y736842D03*
X169029Y775496D03*
X195489Y752261D03*
X175300Y757500D03*
X182092Y771758D03*
X168100Y812800D03*
X195900Y789200D03*
X177092Y800861D03*
X231270Y140880D03*
X224500Y170500D03*
Y174700D03*
Y166300D03*
X203740Y144334D03*
X214145Y147841D03*
X212000Y158300D03*
X224500Y178900D03*
X223000Y184000D03*
Y188500D03*
X225000Y192500D03*
X229200D03*
X205601Y426212D03*
X217998Y424771D03*
X202270Y438448D03*
X202652Y432259D03*
X220969Y431372D03*
X204700Y479804D03*
X204198Y474804D03*
X204500Y490000D03*
X202064Y512946D03*
X221152Y499246D03*
X203000Y534500D03*
X200217Y517593D03*
X217163Y523586D03*
X233101Y526064D03*
X204200Y522600D03*
X203314Y527894D03*
X208500Y563500D03*
X200000Y550424D03*
X202610Y563580D03*
X230856Y566468D03*
X204100Y600100D03*
X230250Y593750D03*
Y582400D03*
X207977Y696708D03*
X221200Y712250D03*
X207600Y733500D03*
X207931Y752312D03*
X218080Y771407D03*
X207600Y789200D03*
X259500Y138500D03*
X242634Y134760D03*
X248992Y130867D03*
X261500Y173500D03*
X253000Y166500D03*
X258700D03*
X262900D03*
X243000Y176500D03*
X243500Y166500D03*
Y162000D03*
Y157000D03*
X233770Y152909D03*
X261500Y179000D03*
Y184500D03*
X261000Y190500D03*
X258225Y193963D03*
X266500Y184500D03*
Y190500D03*
X243000Y181000D03*
Y186000D03*
X263068Y328619D03*
X252250Y343500D03*
X262604Y350015D03*
X247901Y422389D03*
X241800Y426300D03*
X266756Y431549D03*
X261349Y450988D03*
X249311Y450950D03*
X257000Y473400D03*
X265800Y467660D03*
Y485000D03*
X249601Y514174D03*
X249674Y532413D03*
X237779Y528680D03*
X235291Y521326D03*
X257000Y585500D03*
X239900Y600100D03*
X240000Y608600D03*
Y604400D03*
X248100Y622000D03*
X245050Y647100D03*
X243000Y737500D03*
X240275Y731000D03*
X246000Y745500D03*
X278909Y141324D03*
X280050Y149350D03*
X288000Y193000D03*
X271000Y184500D03*
X299296Y327204D03*
X300300Y340501D03*
X274702Y365240D03*
X296940Y458370D03*
X296000Y497500D03*
X278100Y482000D03*
X293000Y625700D03*
X282500Y647700D03*
X270700Y627300D03*
X270800Y652900D03*
X280498Y726806D03*
X292831Y729494D03*
X279500Y764500D03*
X274406Y763500D03*
X273700Y752000D03*
X296500Y763000D03*
X290400Y763672D03*
X296872Y821628D03*
X295592Y828408D03*
X329500Y192500D03*
X328000Y197400D03*
X334500Y197500D03*
Y192500D03*
X329894Y334794D03*
X329000Y320600D03*
X312430Y333540D03*
X304100Y336301D03*
X314485Y352315D03*
X328000Y663000D03*
X304416Y728698D03*
X310622Y760126D03*
X307000Y764000D03*
X303266Y825234D03*
X356361Y158609D03*
X344000Y197500D03*
X339500D03*
X344000Y192500D03*
X339500D03*
X351605Y334920D03*
X353000Y320300D03*
X354500Y325200D03*
X339149Y315170D03*
X344836Y314844D03*
X461900Y73800D03*
X455300Y90600D03*
X464692Y114063D03*
X455328Y159738D03*
X458029Y380305D03*
X465600Y428000D03*
X456100Y727000D03*
X486750Y31020D03*
X486979Y8837D03*
X486760Y54580D03*
X470200Y73800D03*
X478400D03*
X486764Y78077D03*
X474362Y130750D03*
X481800Y131719D03*
X488838Y140700D03*
X475567Y136564D03*
X475089Y114652D03*
X470047Y113969D03*
X497530Y144850D03*
X481801Y329085D03*
X488109Y332641D03*
X488009Y340441D03*
X484695Y360571D03*
X471852Y360377D03*
X484300Y397550D03*
X472600D03*
X494908Y379870D03*
X484830Y780711D03*
X493408Y778813D03*
X502044Y765135D03*
X493255Y816854D03*
X488255Y816894D03*
X487000Y801500D03*
X536081Y304376D03*
X536809Y298789D03*
X527293Y345998D03*
X520672Y345868D03*
X509246Y781700D03*
X519458Y779247D03*
X509855Y814998D03*
X520781Y816463D03*
X503745Y815682D03*
X534543Y829543D03*
X532217Y839013D03*
X561600Y154800D03*
X558100Y158600D03*
X538500Y154900D03*
X565063Y256608D03*
Y247608D03*
Y252108D03*
X560318Y267199D03*
Y272199D03*
X560418Y278299D03*
Y283799D03*
Y289299D03*
X560318Y295699D03*
X553563Y306108D03*
Y310608D03*
X554074Y291069D03*
X551926Y295585D03*
X557904Y327115D03*
X562123Y319158D03*
X553455Y314807D03*
X553463Y319108D03*
X557863D03*
X549000Y318500D03*
X565900Y339000D03*
X541400Y368580D03*
X548928Y347157D03*
X554500Y380500D03*
X540200Y837200D03*
X591571Y206500D03*
X573151Y211067D03*
X584522Y240830D03*
X605063Y257608D03*
X585515Y276459D03*
X583009Y264117D03*
X585351Y269292D03*
X587984Y246148D03*
X587980Y251975D03*
X589164Y264150D03*
X582738Y273300D03*
X587063Y257608D03*
X582976Y246148D03*
X583286Y251974D03*
X582682Y257614D03*
X589400Y308626D03*
X585737Y289608D03*
Y283108D03*
X582683Y279618D03*
X582411Y286589D03*
X582363Y293408D03*
X580563Y308608D03*
X583391Y298870D03*
X583282Y303091D03*
X571600Y324400D03*
X573500Y381000D03*
X637063Y229408D03*
X632449Y224622D03*
X611563Y278108D03*
X607563Y265608D03*
X607463Y270608D03*
X607563Y261108D03*
X609063Y255608D03*
X607563Y276108D03*
X638063Y290608D03*
X607563Y282108D03*
Y287608D03*
Y293608D03*
X607519Y299497D03*
X611563Y290108D03*
Y284608D03*
X632000Y329100D03*
X620200Y335900D03*
X626260Y341091D03*
X608090Y338070D03*
X632750Y341033D03*
X632600Y372042D03*
X632000Y384100D03*
X637000D03*
X626900Y390900D03*
X613400Y387000D03*
X636150Y400100D03*
X628148Y805648D03*
X614444Y800544D03*
X638470Y807070D03*
X666593Y226677D03*
X662593Y223677D03*
X658093D03*
X671000Y215000D03*
X670063Y274708D03*
X669633Y259148D03*
X672100Y299800D03*
X660100Y344600D03*
X647621Y340950D03*
X660500Y367100D03*
Y362300D03*
Y372100D03*
X648500Y372000D03*
X642000Y384100D03*
X682000Y174300D03*
X674100Y191500D03*
X688200Y191200D03*
X704537Y221492D03*
X678063Y238108D03*
X673063D03*
X672927Y219677D03*
X677927D03*
X686063Y230108D03*
X696800Y237900D03*
X682763Y238008D03*
X686063Y224608D03*
X703600Y233700D03*
X687253Y237878D03*
X691753D03*
X698300Y226500D03*
X693800D03*
X685000Y215000D03*
X689623Y269648D03*
X694963Y269608D03*
X689723Y274748D03*
X694223D03*
X679723D03*
X684223D03*
X690233Y255748D03*
X695000Y255800D03*
X690133Y260348D03*
X694633D03*
X680133Y259148D03*
X684633D03*
X674563Y274708D03*
X674133Y259148D03*
X695963Y302308D03*
Y297808D03*
Y293308D03*
X690663Y287608D03*
Y292108D03*
X677000Y299900D03*
X682063Y299108D03*
X683800Y295000D03*
X684063Y285908D03*
Y290408D03*
X694500Y366000D03*
X713332Y1831D03*
X736317Y35906D03*
X732837Y9562D03*
X723740Y9594D03*
X718343Y10856D03*
X717325Y28240D03*
X738220Y68350D03*
X718500Y68500D03*
X712337Y207792D03*
X712137Y213292D03*
Y219392D03*
X725300Y228700D03*
X730300D03*
X711300D03*
X716300D03*
X716900Y233800D03*
X721400D03*
X730400D03*
X725900D03*
X735400D03*
X707900D03*
X712400D03*
X738800Y272000D03*
Y265500D03*
Y258000D03*
Y251500D03*
X706800Y272500D03*
Y265500D03*
Y258000D03*
Y252000D03*
X715300Y272000D03*
Y265500D03*
Y258000D03*
Y251500D03*
X724300Y272000D03*
Y265500D03*
Y258000D03*
Y251500D03*
X732300Y272000D03*
Y265500D03*
Y258000D03*
Y251500D03*
X706800Y290700D03*
X718800Y291000D03*
X714300D03*
X707363Y298108D03*
X718863Y295908D03*
X714363D03*
X723300Y291000D03*
X732300D03*
X727800D03*
X723363Y295908D03*
X732363D03*
X727863D03*
X737300Y291000D03*
X756565Y30918D03*
X763400Y35200D03*
X760084Y53800D03*
X758000Y68500D03*
X742367Y57852D03*
X763147Y65169D03*
X767450Y68465D03*
X766000Y85700D03*
X766683Y99583D03*
X766000Y94400D03*
X768700Y139100D03*
X767600Y117400D03*
X751300Y115000D03*
X745000Y733500D03*
X774392Y69785D03*
X779752Y70067D03*
X773617Y104731D03*
X802600Y89500D03*
X786200Y136200D03*
X805247Y123218D03*
X815200Y7500D03*
X813214Y38497D03*
X824118Y55116D03*
X839289Y68301D03*
X835492Y72992D03*
X835500Y100500D03*
X816600Y83025D03*
X822035Y130312D03*
X811202Y139324D03*
X807900Y114800D03*
X807801Y127889D03*
X833086Y743052D03*
X830569Y751931D03*
X828394Y760106D03*
X865500Y-824D03*
X854453Y3932D03*
X868819Y27276D03*
X869250Y39909D03*
X869195Y34816D03*
X869250Y45400D03*
X863500Y59400D03*
X848781Y64281D03*
X844212Y69179D03*
X842300Y63300D03*
X856000Y62500D03*
X842707Y75879D03*
X861310Y122608D03*
X846730Y123128D03*
X854510Y122640D03*
X847710Y110570D03*
X867000Y357000D03*
X854749Y692148D03*
X864000Y758000D03*
X855292Y782500D03*
X872244Y755738D03*
X863374Y792846D03*
X858000Y794000D03*
X873700Y792100D03*
X901000Y34000D03*
Y29000D03*
Y42000D03*
X878992Y61508D03*
X903000Y61500D03*
X906200Y85270D03*
X896500Y342500D03*
X898817Y311761D03*
X887500Y312000D03*
X896200Y358300D03*
X896500Y350200D03*
X879816Y755877D03*
X888087Y758068D03*
X894108Y790279D03*
X898700Y788300D03*
X879696Y792164D03*
X890049Y793216D03*
X921300Y74700D03*
X918100Y71900D03*
X929464Y49420D03*
X925022Y42909D03*
X929713Y44849D03*
X926500Y60050D03*
X930500Y57500D03*
X928398Y70962D03*
X940377Y81913D03*
X922015Y83123D03*
X929060Y82741D03*
X934779Y82801D03*
X915908Y83067D03*
X910754Y81409D03*
X937400Y76700D03*
X925300Y78500D03*
X976066Y26581D03*
X971466Y26681D03*
X975086Y61900D03*
X970000Y61050D03*
X950120Y63525D03*
X942500Y102500D03*
X947000Y106000D03*
X953000Y108000D03*
X960522Y89645D03*
X945590Y82830D03*
X950970Y82791D03*
X956313Y81319D03*
X992540Y18675D03*
X985880Y41686D03*
X980566Y26581D03*
X992002Y37056D03*
X985880Y46086D03*
Y50586D03*
X1000480Y41812D03*
X1004765Y49647D03*
X1033747Y20176D03*
X1036692Y38477D03*
X1028900Y56100D03*
X1028815Y41714D03*
X1042600Y46100D03*
X1026500Y75500D03*
X1031400Y112500D03*
X1069131Y7363D03*
X1071559Y35329D03*
X1043650Y15633D03*
X1045000Y64500D03*
X1060000Y74000D03*
X1049500Y45000D03*
X1050216Y50022D03*
X1051850Y75550D03*
X1057431Y89182D03*
X1071330Y132580D03*
X1097000Y1500D03*
X1083235Y5000D03*
X1086613Y31774D03*
X1090929Y9074D03*
X1078000Y72500D03*
X1120205Y239021D03*
X1127500Y234500D03*
X1134187Y238517D03*
X1141500Y234000D03*
X1177600Y241200D03*
X1173400D03*
X1166400Y234300D03*
X1170600D03*
X1175700D03*
X1171300Y215700D03*
X1166300D03*
X1175999D03*
X1155000Y242000D03*
X1156000Y234500D03*
X1177200Y248200D03*
X1173000D03*
X1177300Y254400D03*
X1173100D03*
X1176300Y261500D03*
X1171200D03*
X1167000D03*
X1167500Y294500D03*
X1168000Y280000D03*
X1173000D03*
X1177500D03*
X1172500Y742500D03*
X1169000Y750500D03*
X1165375Y757000D03*
X1203100Y241100D03*
X1198900D03*
X1207900D03*
X1182400Y241200D03*
X1197900Y234300D03*
X1207400D03*
X1203200D03*
X1179900D03*
X1188900D03*
X1184700D03*
X1193700D03*
X1190300Y215700D03*
X1185300D03*
X1208800D03*
X1203800D03*
X1180601D03*
X1199300D03*
X1194500D03*
X1182000Y248200D03*
X1202600Y254100D03*
X1198400D03*
X1207400D03*
X1202500Y247500D03*
X1198300D03*
X1207300D03*
X1182100Y254400D03*
X1203800Y261500D03*
X1208000D03*
X1194300D03*
X1198500D03*
X1185300D03*
X1189500D03*
X1180500D03*
X1189600Y244600D03*
X1187000Y280000D03*
X1192000D03*
X1205500D03*
X1210500D03*
X1182500D03*
X1201000D03*
X1196200D03*
X1220164Y204033D03*
X1229000Y210500D03*
X1242500Y209000D03*
X1232000Y194500D03*
X1237000D03*
X1226500Y201500D03*
Y194500D03*
X1244500D03*
X1212900Y234300D03*
X1214800Y215700D03*
X1233900Y240700D03*
X1239900D03*
X1244900D03*
X1228900D03*
X1228500Y235000D03*
X1234000D03*
X1240000D03*
X1245000D03*
X1214000Y261500D03*
X1233800Y246600D03*
X1239800D03*
X1244800D03*
X1228800D03*
X1229000Y252000D03*
X1245000D03*
X1240000D03*
X1234000D03*
X1227000Y279000D03*
X1242000D03*
X1232000Y292000D03*
X1237000D03*
X1227000Y285500D03*
X1244500Y292000D03*
X1247500Y209000D03*
X1252500Y194500D03*
X1263000Y210307D03*
X1257500Y194500D03*
X1263000Y202000D03*
X1262500Y194500D03*
X1255900Y240700D03*
X1249900D03*
X1262500Y235000D03*
X1250000D03*
X1256000D03*
X1255800Y246600D03*
X1249800D03*
X1262000Y252000D03*
X1256000D03*
X1250000D03*
X1247000Y279000D03*
X1262500Y279500D03*
X1252000Y292000D03*
X1257000D03*
X1262500Y286000D03*
X1257500Y378500D03*
X1262600Y346000D03*
X1269940D03*
X1278000Y385500D03*
X1273400Y383500D03*
X1268400Y386100D03*
X1266513Y397500D03*
X1261600Y386500D03*
X1273500Y448500D03*
X1299933Y129548D03*
X1305710Y144320D03*
X1295600Y305182D03*
X1285760Y347120D03*
X1293280Y345770D03*
X1289960Y349900D03*
X1299000Y347500D03*
X1284000Y604000D03*
X1311017Y673086D03*
X1306623Y722399D03*
X1301625Y722567D03*
X1314930Y126650D03*
X1319875Y135104D03*
X1316049Y120821D03*
X1329618Y135248D03*
X1327782Y192579D03*
Y200579D03*
Y207579D03*
X1328411Y237679D03*
X1327782Y215579D03*
Y221579D03*
X1327841Y228639D03*
X1332683Y240409D03*
X1328356Y242091D03*
X1328317Y246291D03*
X1332683Y244609D03*
Y248809D03*
X1325161Y279162D03*
X1326250Y669550D03*
X1329579Y672408D03*
X1316216Y673308D03*
X1333052Y686020D03*
X1319500Y726000D03*
Y737000D03*
Y731500D03*
X1329500Y721500D03*
X1378998Y168228D03*
X1371541Y166287D03*
X1366672Y210312D03*
X1360844Y210366D03*
X1355944Y210313D03*
X1351525Y207104D03*
X1351545Y202879D03*
Y198575D03*
X1378115Y189144D03*
X1374000Y192500D03*
Y188300D03*
Y196700D03*
X1378500Y198000D03*
X1378115Y193344D03*
X1375196Y217203D03*
X1367042Y223895D03*
X1375359Y230110D03*
X1372000Y240500D03*
X1351777Y227823D03*
X1360644Y223881D03*
X1350987Y236754D03*
X1351668Y232125D03*
X1355644Y223881D03*
X1351899Y219598D03*
X1351954Y215268D03*
X1354989Y239016D03*
X1350950Y241000D03*
X1349639Y211374D03*
X1349298Y223737D03*
X1372000Y245300D03*
Y249500D03*
X1355050Y247300D03*
X1350950Y246100D03*
X1362239Y262939D03*
X1356400Y282400D03*
X1350186Y280040D03*
X1348669Y704831D03*
X1383108Y198473D03*
X1382500Y193500D03*
Y188000D03*
X1383340Y177216D03*
G54D132*
X530152Y175634D03*
X522278D03*
X530152Y192366D03*
X522278D03*
X569522Y175634D03*
X561648D03*
X553774D03*
X545900D03*
X538026D03*
X569522Y192366D03*
X561648D03*
X553774D03*
X545900D03*
X538026D03*
G54D40*
X31600Y204900D03*
X46950Y200100D03*
X52700Y775300D03*
X82350Y199400D03*
X67800Y204800D03*
X85650Y702150D03*
X161400Y727900D03*
Y748900D03*
X154200Y783000D03*
Y804000D03*
X193700Y704000D03*
Y725000D03*
Y759500D03*
Y780500D03*
X208200Y530000D03*
X286200Y126000D03*
X282900Y630200D03*
X305039Y340501D03*
X306700Y712400D03*
X470400Y367800D03*
Y388800D03*
X523900Y829700D03*
X646100Y814500D03*
X727909Y68898D03*
X708224D03*
X747594D03*
X846134Y-1815D03*
X1169900Y814200D03*
X1296806Y7874D03*
Y31496D03*
Y55118D03*
Y78740D03*
X1299000Y818400D03*
X1341200Y246500D03*
G54D133*
X532909Y331641D03*
Y321441D03*
G54D124*
X320500Y165100D03*
Y189900D03*
X674763Y227208D03*
Y252008D03*
X674837Y266292D03*
Y291092D03*
X1234500Y202100D03*
Y226900D03*
Y260100D03*
Y284900D03*
X1255000Y202100D03*
Y226900D03*
Y260100D03*
Y284900D03*
G54D22*
X27470Y330307D03*
Y350307D03*
X43262Y330307D03*
Y350307D03*
G54D142*
X633000Y356600D03*
G54D115*
X266231Y245001D03*
X261231D03*
X256231D03*
X251231D03*
X246231D03*
X241231D03*
X236231D03*
Y283559D03*
X241231D03*
X246231D03*
X251231D03*
X256231D03*
X261231D03*
X266231D03*
X271231Y245001D03*
Y283559D03*
X332834Y244932D03*
X327834D03*
X322834D03*
X317834D03*
X312834D03*
X307834D03*
X302834D03*
Y283490D03*
X307834D03*
X312834D03*
X317834D03*
X322834D03*
X327834D03*
X332834D03*
X337834Y244932D03*
Y283490D03*
G54D160*
X1309410Y170203D03*
G54D31*
X25000Y527062D03*
X34000D03*
X119500Y768500D03*
X128500D03*
G54D13*
X22000Y171200D03*
X48400Y269200D03*
X38500Y280800D03*
X47300Y709600D03*
X72300Y261900D03*
X95223Y388904D03*
X68500Y420700D03*
X74000Y561200D03*
X80500Y562700D03*
X84000D03*
X98500Y598200D03*
X81000Y582200D03*
X81500Y634200D03*
X74600Y727500D03*
X104050Y131660D03*
X100900Y177800D03*
X121799Y359964D03*
X108400Y388400D03*
X118351Y574636D03*
X113851D03*
X145809Y574830D03*
X152319Y574920D03*
X159751Y574836D03*
X153700Y732600D03*
X150200D03*
X146500Y787700D03*
X143000D03*
X186000Y708700D03*
X182500D03*
X186000Y764200D03*
X182500D03*
X205200Y196300D03*
X213500Y510200D03*
X209500D03*
X221000Y518200D03*
X246500Y525700D03*
X282300Y499400D03*
X459200Y372500D03*
X462700D03*
X515950Y130260D03*
X519450D03*
X524450D03*
X527950D03*
X532950D03*
X536450D03*
X525409Y320741D03*
X541450Y130260D03*
X544950D03*
X554400Y339300D03*
X600800Y130100D03*
X588000Y130200D03*
X584500D03*
X577730Y130180D03*
X574300D03*
X593000Y130200D03*
X596500D03*
X604300Y130100D03*
X638000Y130200D03*
X634500D03*
X627676D03*
X624176D03*
X609500Y364313D03*
X646000Y130200D03*
X642500D03*
X861752Y14200D03*
X858252D03*
X854500Y45700D03*
X878800Y52800D03*
X1043418Y32166D03*
X1142000Y130200D03*
X1138500D03*
X1161407Y130854D03*
X1157907D03*
X1199500Y130200D03*
X1196000D03*
X1190935Y130248D03*
X1207949Y130130D03*
X1204449D03*
X1187435Y130248D03*
X1178661Y130327D03*
X1182161D03*
X1243000Y130200D03*
X1239500D03*
X1234309Y130312D03*
X1230809D03*
X1225448Y130309D03*
X1221948D03*
X1277365Y130022D03*
X1273865D03*
X1258544Y130119D03*
X1262044D03*
X1296117Y129827D03*
X1292617D03*
X1286643Y129930D03*
X1283143D03*
X1319000Y278700D03*
X1378160Y181001D03*
G54D151*
X831592Y29400D03*
X833167D03*
X834742D03*
X836317D03*
X837892D03*
X839467D03*
Y51600D03*
X837892D03*
X836317D03*
X834742D03*
X833167D03*
X831592D03*
X841037Y29400D03*
X842612D03*
X844187D03*
X845762D03*
X847337D03*
X848912D03*
Y51600D03*
X847337D03*
X845762D03*
X844187D03*
X842612D03*
X841037D03*
G54D106*
X235713Y73589D03*
Y68589D03*
Y63589D03*
Y103589D03*
Y98589D03*
Y93589D03*
Y88589D03*
Y83589D03*
Y78589D03*
Y108589D03*
Y118589D03*
Y113589D03*
X250181Y73589D03*
Y68589D03*
Y63589D03*
Y103589D03*
Y98589D03*
Y93589D03*
Y88589D03*
Y83589D03*
Y78589D03*
Y108589D03*
Y118589D03*
Y113589D03*
G54D170*
G01X187256Y509744D02*
X186508Y508996D01*
X183090D01*
G01X831592Y29400D02*
Y34411D01*
G01Y51600D02*
Y47281D01*
X832401Y46472D01*
G01D02*
Y46587D01*
X833167Y47353D01*
Y51600D01*
G01X847337Y29400D02*
Y26263D01*
X849500Y24100D01*
X854300D01*
X854700Y24500D01*
G01X848912Y29400D02*
Y26988D01*
X850400Y25500D01*
X853700D01*
G01X854500Y49250D02*
X849750D01*
X848912Y50088D01*
Y51600D01*
G01X847337D02*
Y46563D01*
G54D116*
X235500Y439000D03*
Y449000D03*
Y469000D03*
Y459000D03*
Y479000D03*
Y499000D03*
Y489000D03*
G54D161*
X1311262Y175228D03*
X1290978D03*
X1311262Y181958D03*
X1290978D03*
G54D134*
X559109Y312241D03*
X574609D03*
X1353250Y192000D03*
X1368750D03*
G54D50*
X49866Y364307D03*
X44866D03*
X39866D03*
X34866D03*
Y384307D03*
X39866D03*
X44866D03*
X49866D03*
X191018Y211856D03*
X196018D03*
Y239356D03*
X191018D03*
X201018Y211856D03*
X206018D03*
Y239356D03*
X201018D03*
X236231Y245705D03*
X241231D03*
X246231D03*
X251231D03*
X256231D03*
X261231D03*
X266231D03*
Y282855D03*
X261231D03*
X256231D03*
X251231D03*
X246231D03*
X241231D03*
X236231D03*
X271231Y245705D03*
Y282855D03*
X302834Y245636D03*
X307834D03*
X312834D03*
X317834D03*
X322834D03*
X327834D03*
X332834D03*
Y282786D03*
X327834D03*
X322834D03*
X317834D03*
X312834D03*
X307834D03*
X302834D03*
X337834Y245636D03*
Y282786D03*
X519526Y251011D03*
X524526D03*
X529526D03*
X534526D03*
Y278511D03*
X529526D03*
X524526D03*
X519526D03*
G54D152*
X889700Y23000D03*
X895300D03*
G54D107*
X228800Y160600D03*
X217800D03*
X464389Y324210D03*
X475389D03*
G54D125*
X336141Y323975D03*
Y325945D03*
Y327915D03*
Y329885D03*
X345341D03*
Y327915D03*
Y325945D03*
Y323975D03*
X872850Y-1435D03*
Y530D03*
Y2500D03*
Y4470D03*
Y6435D03*
X889150D03*
Y4470D03*
Y2500D03*
Y530D03*
Y-1435D03*
G54D143*
X635953Y346807D03*
X633984D03*
X632016D03*
X630047D03*
Y366393D03*
X632016D03*
X633984D03*
X635953D03*
X628079Y346807D03*
Y366393D03*
X637921Y346807D03*
Y366393D03*
G54D14*
X22000Y174800D03*
X48400Y272800D03*
X38500Y284400D03*
X47300Y713200D03*
X72300Y265500D03*
X95223Y392504D03*
X68500Y424300D03*
X74000Y564800D03*
X80500Y566300D03*
X84000D03*
X98500Y601800D03*
X81000Y585800D03*
X81500Y637800D03*
X74600Y731100D03*
X104050Y135260D03*
X100900Y181400D03*
X121799Y363564D03*
X108400Y392000D03*
X118351Y578236D03*
X113851D03*
X145809Y578430D03*
X152319Y578520D03*
X159751Y578436D03*
X153700Y736200D03*
X150200D03*
X146500Y791300D03*
X143000D03*
X186000Y712300D03*
X182500D03*
X186000Y767800D03*
X182500D03*
X205200Y199900D03*
X213500Y513800D03*
X209500D03*
X221000Y521800D03*
X246500Y529300D03*
X282300Y503000D03*
X459200Y376100D03*
X462700D03*
X515950Y133860D03*
X519450D03*
X524450D03*
X527950D03*
X532950D03*
X536450D03*
X525409Y324341D03*
X541450Y133860D03*
X544950D03*
X554400Y342900D03*
X600800Y133700D03*
X588000Y133800D03*
X584500D03*
X577730Y133780D03*
X574300D03*
X593000Y133800D03*
X596500D03*
X604300Y133700D03*
X638000Y133800D03*
X634500D03*
X627676D03*
X624176D03*
X609500Y367913D03*
X646000Y133800D03*
X642500D03*
X861752Y17800D03*
X858252D03*
X854500Y49300D03*
X878800Y56400D03*
X1043418Y35766D03*
X1142000Y133800D03*
X1138500D03*
X1161407Y134454D03*
X1157907D03*
X1199500Y133800D03*
X1196000D03*
X1190935Y133848D03*
X1207949Y133730D03*
X1204449D03*
X1187435Y133848D03*
X1178661Y133927D03*
X1182161D03*
X1243000Y133800D03*
X1239500D03*
X1234309Y133912D03*
X1230809D03*
X1225448Y133909D03*
X1221948D03*
X1277365Y133622D03*
X1273865D03*
X1258544Y133719D03*
X1262044D03*
X1296117Y133427D03*
X1292617D03*
X1286643Y133530D03*
X1283143D03*
X1319000Y282300D03*
X1378160Y184601D03*
G54D23*
X28000Y321200D03*
X43300Y394400D03*
X64700Y417000D03*
X87230Y273800D03*
X87685Y489504D03*
Y486004D03*
X75700Y719300D03*
X100800Y306700D03*
X108751Y638436D03*
X124100Y714300D03*
Y710800D03*
X143269Y640420D03*
X143251Y648436D03*
X133751Y643936D03*
X143251D03*
X177821Y598436D03*
X277700Y122000D03*
X274500Y634900D03*
X325292Y295900D03*
X315700Y534500D03*
X619763Y213608D03*
X887600Y51500D03*
X904700Y45000D03*
Y48500D03*
X941981Y25374D03*
X1019063Y17398D03*
X1076700Y57000D03*
Y60500D03*
Y53500D03*
Y50000D03*
X1126100Y129800D03*
Y133300D03*
X1317200Y286500D03*
G54D32*
X24050Y691400D03*
X31550Y687525D03*
Y695275D03*
X43950Y690300D03*
X51450Y686425D03*
Y694175D03*
X152435Y331811D03*
X159935Y327936D03*
Y335686D03*
X137167Y333265D03*
X144667Y337140D03*
Y329390D03*
X213607Y130425D03*
X206107Y134300D03*
X213607Y138175D03*
X739750Y44500D03*
X747250Y40625D03*
X762250D03*
X747250Y48375D03*
X754750Y44500D03*
X762250Y48375D03*
X824450Y60025D03*
X816950Y63900D03*
X824450Y67775D03*
X935350Y67400D03*
X942850Y63525D03*
Y71275D03*
G54D41*
X37200Y204900D03*
X52550Y200100D03*
X58300Y775300D03*
X87950Y199400D03*
X73400Y204800D03*
X91250Y702150D03*
X159800Y783000D03*
Y804000D03*
X199300Y704000D03*
Y725000D03*
X167000Y727900D03*
Y748900D03*
X199300Y759500D03*
Y780500D03*
X213800Y530000D03*
X291800Y126000D03*
X288500Y630200D03*
X310639Y340501D03*
X312300Y712400D03*
X476000Y367800D03*
Y388800D03*
X529500Y829700D03*
X651700Y814500D03*
X733509Y68898D03*
X713824D03*
X753194D03*
X851734Y-1815D03*
X1175500Y814200D03*
X1302406Y7874D03*
Y31496D03*
Y55118D03*
Y78740D03*
X1304600Y818400D03*
X1346800Y246500D03*
G54D171*
G01X41900Y204900D02*
X40300Y206500D01*
Y207900D01*
X41650Y209250D01*
G01X41900Y204900D02*
X40325Y203325D01*
Y197675D01*
X41900Y196100D01*
X45462D01*
X50230Y191332D01*
Y188370D01*
X51002Y187598D01*
X53551D01*
G01X53000Y207950D02*
X54325Y209275D01*
Y211003D01*
X53400Y211928D01*
G01X49595Y177598D02*
X51998D01*
X52916Y178516D01*
Y180616D01*
X58550Y186250D01*
Y190040D01*
X54325Y194265D01*
Y198525D01*
X52750Y200100D01*
G01D02*
X54250Y201600D01*
Y203200D01*
X53000Y204450D01*
G01X37400Y204900D02*
X38950Y206450D01*
Y207950D01*
X37650Y209250D01*
G01X37400Y204900D02*
X38975Y203325D01*
Y197115D01*
X41340Y194750D01*
X44902D01*
X48880Y190772D01*
Y188380D01*
X48098Y187598D01*
X45559D01*
G01X57000Y207950D02*
X55675Y209275D01*
Y211003D01*
X56600Y211928D01*
G01X57250Y200100D02*
X55675Y198525D01*
Y194825D01*
X59900Y190600D01*
Y185690D01*
X54266Y180056D01*
Y178598D01*
X55266Y177598D01*
X57587D01*
G01X57250Y200100D02*
X55600Y201750D01*
Y203050D01*
X57000Y204450D01*
G01X65579Y177598D02*
X67998D01*
X68900Y178500D01*
Y180200D01*
X63650Y185450D01*
Y190060D01*
X75175Y201585D01*
Y203224D01*
X75174Y203225D01*
Y203226D01*
X73600Y204800D01*
G01X41650Y212750D02*
X40325Y214075D01*
Y215803D01*
X41250Y216728D01*
G01X37650Y212750D02*
X38975Y214075D01*
Y215803D01*
X38050Y216728D01*
G01X63700Y260725D02*
X62772Y261653D01*
X60747D01*
X59450Y262950D01*
Y269460D01*
X62901Y272911D01*
Y277599D01*
X62642Y277858D01*
Y280483D01*
G01X55800Y266293D02*
X54871Y267222D01*
X53436D01*
X52350Y268308D01*
Y271760D01*
X57100Y276510D01*
Y277544D01*
X56736Y277908D01*
Y280483D01*
G01X63700Y263925D02*
X62778Y263003D01*
X61307D01*
X60800Y263510D01*
Y268900D01*
X64251Y272351D01*
Y277551D01*
X64610Y277910D01*
Y280483D01*
G01X58705D02*
Y277834D01*
X58450Y277579D01*
Y275950D01*
X53700Y271200D01*
Y268868D01*
X53996Y268572D01*
X54879D01*
X55800Y269493D01*
G01X66579Y280483D02*
Y283102D01*
X66888Y283411D01*
Y284195D01*
X66475Y284608D01*
X64469D01*
X63124Y285953D01*
Y287332D01*
X62200Y288256D01*
G01X78100Y204800D02*
X76525Y203225D01*
Y201025D01*
X65000Y189500D01*
Y186010D01*
X70250Y180760D01*
Y178598D01*
X71250Y177598D01*
X73571D01*
G01X78100Y204800D02*
X76475Y206425D01*
Y208025D01*
X77800Y209350D01*
G01X88800Y210851D02*
X89650Y210001D01*
Y208600D01*
X88400Y207350D01*
G01X69615Y187598D02*
X71798D01*
X72936Y188736D01*
Y191892D01*
X74894Y193850D01*
X86975D01*
X89725Y196600D01*
Y197825D01*
X88150Y199400D01*
G01D02*
X89800Y201050D01*
Y202450D01*
X88400Y203850D01*
G01X73600Y204800D02*
X75125Y206325D01*
Y208025D01*
X73800Y209350D01*
G01X92000Y210851D02*
X91000Y209851D01*
Y208750D01*
X92400Y207350D01*
G01X92650Y199400D02*
X91075Y197825D01*
Y196040D01*
X87535Y192500D01*
X75454D01*
X74286Y191332D01*
Y188598D01*
X75286Y187598D01*
X77607D01*
G01X92650Y199400D02*
X91150Y200900D01*
Y202600D01*
X92400Y203850D01*
G01X88259Y223184D02*
X89776Y221667D01*
Y220126D01*
X88400Y218750D01*
G01X92659Y223184D02*
X91126Y221651D01*
Y220024D01*
X92400Y218750D01*
G01X77800Y224350D02*
X76475Y225675D01*
Y227764D01*
X78000Y229289D01*
G01X73800Y224350D02*
X75125Y225675D01*
Y227764D01*
X73600Y229289D01*
G01X77800Y212850D02*
X76475Y214175D01*
Y215603D01*
X77400Y216528D01*
G01D02*
X76475Y217453D01*
Y219525D01*
X77800Y220850D01*
G01X88800Y210851D02*
X89725Y211776D01*
Y213925D01*
X88400Y215250D01*
G01X73800Y212850D02*
X75125Y214175D01*
Y215603D01*
X74200Y216528D01*
G01D02*
X75125Y217453D01*
Y219525D01*
X73800Y220850D01*
G01X92000Y210851D02*
X91075Y211776D01*
Y213925D01*
X92400Y215250D01*
G01X73125Y288231D02*
X74062Y287294D01*
Y286521D01*
X72792Y285251D01*
Y283332D01*
X72484Y283024D01*
Y280483D01*
G01X76325Y288231D02*
X75412Y287318D01*
Y285961D01*
X74142Y284691D01*
Y283348D01*
X74453Y283037D01*
Y280483D01*
G01X68547D02*
Y283135D01*
X68238Y283444D01*
Y284755D01*
X67035Y285958D01*
X65029D01*
X64474Y286513D01*
Y287330D01*
X65400Y288256D01*
G01X235713Y68589D02*
X228163D01*
G01X235713Y78589D02*
X228163D01*
G01X250181Y68589D02*
X257759D01*
G01X250181Y78589D02*
X257731D01*
G54D162*
X1307100Y296700D03*
X1298300Y300700D03*
Y292700D03*
G54D60*
X54300Y734900D03*
G54D117*
X263488Y578165D03*
Y583165D03*
Y588165D03*
Y593165D03*
X293229Y343640D03*
Y338640D03*
Y333640D03*
Y328640D03*
X273229D03*
Y333640D03*
Y338640D03*
Y343640D03*
X283488Y578165D03*
Y593165D03*
Y588165D03*
Y583165D03*
X493909Y324041D03*
Y329041D03*
Y334041D03*
Y339041D03*
X513909D03*
Y334041D03*
Y329041D03*
Y324041D03*
X875000Y31000D03*
Y36000D03*
Y41000D03*
Y46000D03*
X895000Y41000D03*
Y36000D03*
Y31000D03*
Y46000D03*
X1001300Y55400D03*
Y60400D03*
Y65400D03*
Y70400D03*
X1021300D03*
Y65400D03*
Y60400D03*
Y55400D03*
G54D153*
X885300Y64650D03*
Y57150D03*
X892900Y64650D03*
G54D144*
X623007Y349710D03*
Y363490D03*
X642993D03*
Y349710D03*
G54D126*
X476614Y167493D03*
Y162493D03*
Y157493D03*
G54D108*
X215338Y436405D03*
Y433845D03*
Y431285D03*
X207938Y436405D03*
Y433845D03*
Y431285D03*
X249800Y348840D03*
Y351400D03*
Y353960D03*
X257200Y348840D03*
Y351400D03*
Y353960D03*
X257600Y433160D03*
Y430600D03*
Y428040D03*
X250200Y433160D03*
Y430600D03*
Y428040D03*
X269000Y501360D03*
Y498800D03*
Y496240D03*
X276400D03*
Y498800D03*
Y501360D03*
Y508440D03*
Y511000D03*
X269000D03*
Y508440D03*
X276400Y513560D03*
X269000D03*
G54D51*
X59550Y367033D03*
Y358033D03*
X78500Y615500D03*
X70000D03*
X78500Y624500D03*
X70000D03*
G54D42*
X47700Y204900D03*
X63050Y200100D03*
X43300Y414000D03*
X83900Y204800D03*
X98450Y199400D03*
X85600Y736400D03*
X85700Y749300D03*
X85600Y762400D03*
X118532Y268820D03*
X128500Y761300D03*
Y756300D03*
X145100Y306400D03*
X134600D03*
X145301Y411131D03*
X133100Y835000D03*
X177500Y748900D03*
Y727900D03*
X170300Y783000D03*
Y804000D03*
X215800Y473500D03*
X209800Y704000D03*
Y725000D03*
Y780500D03*
Y759500D03*
X266600Y651900D03*
X348700Y730900D03*
X497288Y7874D03*
Y31496D03*
Y55118D03*
Y78740D03*
X486500Y367800D03*
Y388800D03*
X569331Y384080D03*
X600163Y257608D03*
X658300Y357600D03*
X723563Y-3650D03*
X873152Y741450D03*
X889400Y739800D03*
X890937Y812539D03*
X1068154Y68898D03*
X1048469D03*
X1087839D03*
G54D135*
X560531Y358080D03*
G54D24*
X27000Y362700D03*
X53000Y207900D03*
X57000D03*
X37650Y212700D03*
X41650D03*
X53422Y357814D03*
X53200Y477700D03*
X64000Y494200D03*
X46900Y493900D03*
X31200Y712600D03*
X57200Y686400D03*
X60800Y766500D03*
X56700D03*
X52300Y766600D03*
X35000Y766800D03*
X39000D03*
X92400Y207300D03*
X88400D03*
X92400Y218700D03*
X77800Y212800D03*
X73800Y224300D03*
X88400Y218700D03*
X73800Y212800D03*
X77800Y224300D03*
X76170Y262620D03*
X96043Y434143D03*
X72500Y424200D03*
X84900Y585700D03*
X66000Y594200D03*
X80950Y705350D03*
X91800Y723100D03*
X74300Y766100D03*
X108050Y135160D03*
X106500Y280600D03*
X108500Y290600D03*
X117761Y372506D03*
X104507Y392134D03*
X127400Y408300D03*
X120252Y443752D03*
X100079Y426717D03*
X116235Y451235D03*
X103500Y461200D03*
X115500D03*
X106900Y728000D03*
X162900Y240990D03*
X146000Y370700D03*
X155700Y409700D03*
X134571Y409796D03*
X135250Y443690D03*
X146200Y461200D03*
X150632Y453555D03*
X146431Y453478D03*
X138769Y578420D03*
X153700Y744100D03*
X164500Y778200D03*
X160000Y816200D03*
X146500Y799200D03*
X186418Y199756D03*
X185500Y574200D03*
X189500D03*
X195500Y601700D03*
X191500Y594200D03*
Y586700D03*
X199500Y737200D03*
X186000Y720200D03*
X184700Y736100D03*
X171700Y723100D03*
X186000Y775700D03*
X167200Y761100D03*
X199500Y792700D03*
X177500Y791200D03*
X225900Y105300D03*
X200300Y199800D03*
X225000Y529200D03*
X229000Y521800D03*
X205500Y574200D03*
X204000Y699200D03*
X217000Y712200D03*
X204000Y754700D03*
X217000Y767700D03*
X240400Y233800D03*
X266729Y357340D03*
X260600Y476500D03*
X242500Y521200D03*
X257500Y529200D03*
X253500Y521200D03*
X237300Y639100D03*
X281500Y137200D03*
X281100Y208500D03*
X278100Y478000D03*
X284200Y474500D03*
X282500Y495200D03*
X274406Y723098D03*
X278406D03*
X286500Y779700D03*
X291000Y772100D03*
X295079Y772050D03*
X299148Y772305D03*
X286500Y772200D03*
X308300Y336000D03*
X301929Y358440D03*
X304000Y779900D03*
X307406Y772098D03*
X311406D03*
X315406D03*
X303300Y772000D03*
X337410Y295860D03*
X461900Y68900D03*
X455800Y98900D03*
Y106400D03*
X466905Y122328D03*
X462868Y122324D03*
X462700Y384000D03*
X470200Y68900D03*
X478400D03*
X480881Y140014D03*
X498903Y168592D03*
X498400Y201900D03*
X480700Y363000D03*
X493700Y376000D03*
X476200Y401000D03*
X487906Y775098D03*
X491906D03*
X500100Y824100D03*
X507700Y171500D03*
X507300Y182400D03*
X531232Y236924D03*
X522899Y236937D03*
X517599D03*
X527131Y236880D03*
X535295Y236958D03*
X524177Y294640D03*
X532921Y294517D03*
X536953Y294760D03*
X520906Y824098D03*
X504406D03*
X524906D03*
X508500Y824100D03*
X512579Y824050D03*
X528906Y824098D03*
X516679Y824050D03*
X532906Y824098D03*
X565690Y133430D03*
X569700D03*
X550400Y165000D03*
X567200Y164700D03*
X554500Y165000D03*
X563100Y164700D03*
X542490Y163801D03*
X575600Y164600D03*
X571400Y164700D03*
X613709Y133281D03*
X617711D03*
X627363Y231808D03*
X628000Y337300D03*
X624000D03*
X632000Y324300D03*
X615100Y365200D03*
X613500Y357083D03*
X632000Y379300D03*
X627500D03*
X636300D03*
X617000Y390300D03*
X627500Y387300D03*
X623000Y390300D03*
X640500Y379300D03*
X724890Y59830D03*
X765300Y107600D03*
X791800Y29300D03*
X781100Y138600D03*
X815500Y20500D03*
X820018Y51079D03*
X824118D03*
X850300Y17700D03*
X867500Y23700D03*
Y16200D03*
X857406Y752098D03*
X861406D03*
X869756Y801098D03*
X873850Y801100D03*
X870900Y808800D03*
X896500Y16700D03*
X886520Y16702D03*
X899200Y65100D03*
X906500Y93200D03*
X893000D03*
X897500D03*
X884000D03*
X879500D03*
X902000D03*
X888500D03*
X875000D03*
X895000Y309300D03*
X891000D03*
X886276Y803748D03*
X890406Y801098D03*
X877949Y803700D03*
X894406Y801098D03*
X882049Y803700D03*
X898406Y801098D03*
X955400Y72400D03*
X951500Y93200D03*
X947000D03*
X942500D03*
X996230Y46444D03*
X1033000Y69700D03*
X1037000Y105200D03*
X1041500D03*
X1024000D03*
X1028000D03*
X1032500D03*
X1020000D03*
X1015948D03*
X1068673Y24345D03*
X1070733Y44623D03*
X1050500Y105200D03*
X1046000D03*
X1173479Y133571D03*
X1169467Y133576D03*
X1216752Y133515D03*
X1212748D03*
X1270005Y133621D03*
X1265997Y133622D03*
X1258500Y342200D03*
X1270500D03*
X1262500D03*
X1266500D03*
X1277500Y401200D03*
Y393700D03*
X1307000Y282200D03*
X1301500Y393700D03*
X1293500D03*
X1297500D03*
X1285500D03*
X1305500D03*
X1289500D03*
X1302128Y680567D03*
X1306128D03*
X1335071Y137811D03*
X1317300Y301600D03*
X1321400D03*
X1315000Y282200D03*
X1313000Y293200D03*
X1314628Y729567D03*
X1326128D03*
X1330128D03*
X1334128D03*
X1338128D03*
X1326100Y737600D03*
X1361500Y270200D03*
G54D33*
X25100Y746900D03*
Y733400D03*
Y729400D03*
X42300Y276800D03*
Y280900D03*
X35700Y394100D03*
X55800Y483000D03*
Y502000D03*
X55400Y708900D03*
X53200Y770800D03*
X97800Y276300D03*
X67143Y354737D03*
X70800Y506500D03*
Y510500D03*
Y514500D03*
X81000Y529300D03*
X66940Y527270D03*
X80800Y542300D03*
Y546300D03*
X98300Y569500D03*
X80700Y550400D03*
X80800Y554500D03*
Y558500D03*
X98300Y592500D03*
X73800Y586000D03*
X86800Y642000D03*
Y646000D03*
X95000Y681900D03*
X78400Y731300D03*
Y727300D03*
X79600Y740900D03*
Y744900D03*
Y766900D03*
X100800Y298900D03*
Y302900D03*
X112300Y388600D03*
X112234Y441150D03*
X107300Y561500D03*
Y565500D03*
X102500Y681900D03*
X116200Y714300D03*
X99200Y727800D03*
X129000Y745200D03*
X118300Y775000D03*
X149614Y322277D03*
X142113Y322350D03*
X132814Y373985D03*
X157400Y379200D03*
X143298Y420306D03*
X137200Y732300D03*
X164300Y808500D03*
X169084Y186686D03*
Y181686D03*
X194000Y251100D03*
X190615Y289501D03*
X179154Y446672D03*
X171500Y753400D03*
X200560Y289306D03*
X210038Y425645D03*
X209838Y441945D03*
X206000Y446000D03*
X209800Y465000D03*
Y469000D03*
Y482000D03*
Y486000D03*
X209900Y494400D03*
X209800Y490000D03*
Y525500D03*
Y521500D03*
Y554500D03*
X222670Y568020D03*
X230300Y586000D03*
Y590000D03*
X203800Y729500D03*
Y785000D03*
X236300Y139500D03*
X250528Y124804D03*
X253200Y438600D03*
X255900Y422500D03*
X250000Y443300D03*
X252320Y581381D03*
X269800Y126000D03*
X269400Y467300D03*
Y485800D03*
X274600Y638900D03*
X282100Y643900D03*
X311300Y221900D03*
X315700Y542500D03*
X335200Y222000D03*
X334900Y335500D03*
X344600Y318500D03*
X460149Y210989D03*
X496832Y130548D03*
X480809Y339041D03*
Y334041D03*
X480500Y393300D03*
X526600Y165815D03*
Y157715D03*
Y161815D03*
X515709Y202072D03*
X508009Y202172D03*
X522400Y340500D03*
X558270Y136909D03*
X550800Y137597D03*
X558331Y334980D03*
X589763Y215308D03*
X572400Y238400D03*
X619663Y217608D03*
X612163Y213608D03*
X605000Y344200D03*
X663800Y212000D03*
X689200Y212200D03*
X677800Y212000D03*
X722513Y2380D03*
X733063Y31882D03*
X717305Y14964D03*
X720959Y28613D03*
X734930Y63910D03*
X714300Y64000D03*
X713410Y55860D03*
Y51796D03*
X752600Y53800D03*
X757750Y75900D03*
X757900Y86500D03*
Y90600D03*
Y102900D03*
Y82300D03*
X765500Y121200D03*
Y133500D03*
X755800Y118800D03*
X774900Y74000D03*
X794900Y74200D03*
X806800Y86500D03*
Y90600D03*
X835400Y105600D03*
X808713Y118898D03*
X846181Y5499D03*
X861800Y32000D03*
Y40000D03*
X862300Y52800D03*
Y48500D03*
X904800Y37000D03*
X900300Y358500D03*
Y350000D03*
Y345600D03*
X886470Y808230D03*
X928900Y78600D03*
X955381Y64624D03*
X989011Y14160D03*
X989169Y27248D03*
Y23121D03*
X1021360Y2024D03*
X1033416Y33563D03*
X1032192Y11076D03*
X1039967Y11296D03*
X1075859Y5500D03*
Y500D03*
X1051300Y22200D03*
X1075869Y22450D03*
X1076424Y39554D03*
X1075869Y26950D03*
X1076424Y35054D03*
X1075139Y14070D03*
X1054800Y48700D03*
X1049400Y64100D03*
X1120300Y235000D03*
X1134300Y234500D03*
X1148800D03*
X1289300Y300000D03*
X1315300Y274500D03*
X1356800Y278500D03*
G54D15*
X26977Y151614D03*
X96189D03*
G54D172*
G01X179940Y483799D02*
X180372D01*
X181909Y482262D01*
X183727D01*
X184089Y482624D01*
X184216D01*
G01X188420Y491573D02*
X186322D01*
X186318Y491577D01*
X183943D01*
X183941Y491575D01*
X181773D01*
X181771Y491573D01*
G54D16*
X21900Y195900D03*
X21800Y184400D03*
X23100Y220500D03*
X31500D03*
X38500Y276800D03*
X41500Y265300D03*
X43900Y303500D03*
X54600Y325200D03*
X61799Y376157D03*
X42900Y766800D03*
X67600Y330900D03*
X84700Y331800D03*
X81300D03*
X74000Y575800D03*
X84000Y574300D03*
X80500D03*
X100900Y194200D03*
X130051Y651946D03*
X133299Y578520D03*
X190520Y838101D03*
X194520D03*
X222500Y513800D03*
X226000D03*
X221000Y529300D03*
X207118Y838101D03*
X203118D03*
X219717D03*
X215717D03*
X232315D03*
X228315D03*
X239600Y149700D03*
X244300Y233800D03*
X246500Y521300D03*
X259857Y513748D03*
X241300Y639200D03*
X266906Y772198D03*
X254362Y838101D03*
X250362D03*
X266961D03*
X262961D03*
X267300Y296800D03*
X297729Y358440D03*
X279559Y838101D03*
X275559D03*
X329241Y328730D03*
X301500Y487100D03*
X313354Y838101D03*
X317354D03*
X329953D03*
X325953D03*
X367748D03*
X363748D03*
X342551D03*
X338551D03*
X351150D03*
X355150D03*
X389796D03*
X385796D03*
X398394D03*
X402394D03*
X410993D03*
X414993D03*
X423591D03*
X427591D03*
X459071Y122341D03*
X480406Y824198D03*
X505477Y295540D03*
X525409Y332341D03*
X542120Y218605D03*
X544851Y838101D03*
X548851D03*
X557449D03*
X561449D03*
X570048D03*
X604170Y334140D03*
X574048Y838101D03*
X586646D03*
X582646D03*
X599245D03*
X595245D03*
X619363Y231908D03*
X609500Y357183D03*
X611843Y838101D03*
X607843D03*
X624442D03*
X620442D03*
X637040D03*
X633040D03*
X659087D03*
X655087D03*
X671685D03*
X667685D03*
X684284D03*
X680284D03*
X696882D03*
X692882D03*
X724379D03*
X728379D03*
X736977D03*
X740977D03*
X749576D03*
X753576D03*
X762174D03*
X766174D03*
X774772D03*
X778772D03*
X787370D03*
X791370D03*
X799969D03*
X803969D03*
X812567D03*
X816567D03*
X837764D03*
X849906Y801198D03*
X841764Y838101D03*
X850362D03*
X854362D03*
X896000Y6300D03*
X900522Y16766D03*
X905500Y334800D03*
X1039675Y18887D03*
X1014451Y45106D03*
X1040914Y838101D03*
X1044914D03*
X1053512D03*
X1057512D03*
X1066111D03*
X1070111D03*
X1091307D03*
X1095307D03*
X1103906D03*
X1107906D03*
X1078709D03*
X1082709D03*
X1120504D03*
X1116504D03*
X1129103D03*
X1133103D03*
X1141701D03*
X1145701D03*
X1154299D03*
X1158299D03*
X1176347D03*
X1180347D03*
X1192945D03*
X1188945D03*
X1224441D03*
X1220441D03*
X1237040D03*
X1233040D03*
X1257500Y393800D03*
X1254000D03*
X1249638Y838101D03*
X1245638D03*
X1258237D03*
X1262237D03*
X1274835D03*
X1270835D03*
X1294628Y729667D03*
X1287433Y838101D03*
X1283433D03*
X1312630D03*
X1308630D03*
X1325229D03*
X1321229D03*
X1337827D03*
X1333827D03*
X1346425D03*
X1350425D03*
G54D70*
X95252Y576388D03*
Y585612D03*
X101748Y576388D03*
Y585612D03*
G54D118*
X244100Y607400D03*
X246500D03*
X244100Y604400D03*
X246500D03*
X351200Y166200D03*
X348800D03*
X351200Y173600D03*
X348800D03*
X351200Y169900D03*
X348800D03*
X351200Y162500D03*
X348800D03*
X351200Y181000D03*
X348800D03*
X351200Y177300D03*
X348800D03*
X593231Y339580D03*
X590831D03*
X700000Y251500D03*
X702400D03*
X700000Y269500D03*
X702400D03*
X700000Y272500D03*
X702400D03*
X700000Y254500D03*
X702400D03*
X700000Y257500D03*
X702400D03*
X700000Y260500D03*
X702400D03*
X700000Y263500D03*
X702400D03*
X700000Y266500D03*
X702400D03*
X1219300Y224900D03*
X1221700D03*
X1219300Y239900D03*
X1221700D03*
X1219300Y236900D03*
X1221700D03*
X1219300Y233900D03*
X1221700D03*
X1219300Y230900D03*
X1221700D03*
X1219300Y227900D03*
X1221700D03*
X1219300Y242900D03*
X1221700D03*
X1219300Y266900D03*
X1221700D03*
X1219300Y254900D03*
X1221700D03*
X1219300Y269900D03*
X1221700D03*
X1219300Y251900D03*
X1221700D03*
X1219300Y248900D03*
X1221700D03*
X1219300Y245900D03*
X1221700D03*
X1219300Y257900D03*
X1221700D03*
X1219300Y260900D03*
X1221700D03*
X1219300Y263900D03*
X1221700D03*
G54D109*
X204910Y586660D03*
Y589220D03*
Y591780D03*
Y594340D03*
X221090D03*
Y591780D03*
Y589220D03*
Y586660D03*
X773638Y98060D03*
Y95500D03*
Y92940D03*
Y90380D03*
Y87820D03*
Y85260D03*
Y82700D03*
Y80140D03*
X795838D03*
Y82700D03*
Y85260D03*
Y87820D03*
Y90380D03*
Y92940D03*
Y95500D03*
Y98060D03*
X776538Y129460D03*
Y126900D03*
Y124340D03*
Y121780D03*
Y119220D03*
Y116660D03*
Y114100D03*
Y111540D03*
X798738D03*
Y114100D03*
Y116660D03*
Y119220D03*
Y121780D03*
Y124340D03*
Y126900D03*
Y129460D03*
G54D145*
X623207Y361521D03*
Y351679D03*
Y359553D03*
Y357584D03*
Y355616D03*
Y353647D03*
X642793Y361521D03*
Y359553D03*
Y357584D03*
Y355616D03*
Y353647D03*
Y351679D03*
G54D43*
X42100Y204900D03*
X57450Y200100D03*
X37700Y414000D03*
X78300Y204800D03*
X92850Y199400D03*
X80000Y736400D03*
X80100Y749300D03*
X80000Y762400D03*
X112932Y268820D03*
X129000Y306400D03*
X122900Y761300D03*
Y756300D03*
X127500Y835000D03*
X139500Y306400D03*
X139701Y411131D03*
X164700Y783000D03*
Y804000D03*
X171900Y748900D03*
Y727900D03*
X210200Y473500D03*
X204200Y704000D03*
Y725000D03*
Y780500D03*
Y759500D03*
X261000Y651900D03*
X343100Y730900D03*
X491688Y7874D03*
Y31496D03*
Y55118D03*
Y78740D03*
X480900Y367800D03*
Y388800D03*
X563731Y384080D03*
X594563Y257608D03*
X652700Y357600D03*
X717963Y-3650D03*
X867552Y741450D03*
X883800Y739800D03*
X885337Y812539D03*
X1042869Y68898D03*
X1062554D03*
X1082239D03*
G54D25*
X27000Y359300D03*
X37650Y209300D03*
X53000Y204500D03*
X41650Y209300D03*
X57000Y204500D03*
X53422Y354414D03*
X53200Y474300D03*
X64000Y490800D03*
X46900Y490500D03*
X31200Y709200D03*
X57200Y683000D03*
X60800Y763100D03*
X56700D03*
X52300Y763200D03*
X35000Y763400D03*
X39000D03*
X92400Y203900D03*
X88400D03*
X77800Y209400D03*
X73800D03*
X92400Y215300D03*
X73800Y220900D03*
X88400Y215300D03*
X77800Y220900D03*
X76170Y259220D03*
X96043Y430743D03*
X72500Y420800D03*
X84900Y582300D03*
X66000Y590800D03*
X80950Y701950D03*
X91800Y719700D03*
X74300Y762700D03*
X108050Y131760D03*
X106500Y277200D03*
X108500Y287200D03*
X117761Y369106D03*
X104507Y388734D03*
X127400Y404900D03*
X120252Y440352D03*
X100079Y423317D03*
X116235Y447835D03*
X103500Y457800D03*
X115500D03*
X106900Y724600D03*
X162900Y237590D03*
X146000Y367300D03*
X155700Y406300D03*
X134571Y406396D03*
X135250Y440290D03*
X146200Y457800D03*
X150632Y450155D03*
X146431Y450078D03*
X138769Y575020D03*
X153700Y740700D03*
X164500Y774800D03*
X160000Y812800D03*
X146500Y795800D03*
X186418Y196356D03*
X185500Y570800D03*
X189500D03*
X195500Y598300D03*
X191500Y590800D03*
Y583300D03*
X199500Y733800D03*
X186000Y716800D03*
X184700Y732700D03*
X171700Y719700D03*
X186000Y772300D03*
X167200Y757700D03*
X199500Y789300D03*
X177500Y787800D03*
X225900Y101900D03*
X200300Y196400D03*
X225000Y525800D03*
X229000Y518400D03*
X205500Y570800D03*
X204000Y695800D03*
X217000Y708800D03*
X204000Y751300D03*
X217000Y764300D03*
X240400Y230400D03*
X266729Y353940D03*
X260600Y473100D03*
X242500Y517800D03*
X257500Y525800D03*
X253500Y517800D03*
X237300Y635700D03*
X281500Y133800D03*
X281100Y205100D03*
X278100Y474600D03*
X284200Y471100D03*
X282500Y491800D03*
X274406Y719698D03*
X278406D03*
X286500Y776300D03*
X291000Y768700D03*
X295079Y768650D03*
X299148Y768905D03*
X286500Y768800D03*
X308300Y332600D03*
X301929Y355040D03*
X304000Y776500D03*
X307406Y768698D03*
X311406D03*
X315406D03*
X303300Y768600D03*
X337410Y292460D03*
X461900Y65500D03*
X455800Y95500D03*
Y103000D03*
X466905Y118928D03*
X462868Y118924D03*
X462700Y380600D03*
X470200Y65500D03*
X478400D03*
X480881Y136614D03*
X498903Y165192D03*
X498400Y198500D03*
X480700Y359600D03*
X493700Y372600D03*
X476200Y397600D03*
X487906Y771698D03*
X491906D03*
X500100Y820700D03*
X507700Y168100D03*
X507300Y179000D03*
X531232Y233524D03*
X522899Y233537D03*
X517599D03*
X527131Y233480D03*
X535295Y233558D03*
X524177Y291240D03*
X532921Y291117D03*
X536953Y291360D03*
X520906Y820698D03*
X504406D03*
X524906D03*
X508500Y820700D03*
X512579Y820650D03*
X528906Y820698D03*
X516679Y820650D03*
X532906Y820698D03*
X565690Y130030D03*
X569700D03*
X550400Y161600D03*
X567200Y161300D03*
X554500Y161600D03*
X563100Y161300D03*
X542490Y160401D03*
X575600Y161200D03*
X571400Y161300D03*
X613709Y129881D03*
X617711D03*
X627363Y228408D03*
X628000Y333900D03*
X624000D03*
X632000Y320900D03*
X615100Y361800D03*
X632000Y375900D03*
X613500Y353683D03*
X627500Y375900D03*
X636300D03*
X617000Y386900D03*
X627500Y383900D03*
X623000Y386900D03*
X640500Y375900D03*
X724890Y56430D03*
X765300Y104200D03*
X791800Y25900D03*
X781100Y135200D03*
X815500Y17100D03*
X820018Y47679D03*
X824118D03*
X850300Y14300D03*
X867500Y20300D03*
Y12800D03*
X857406Y748698D03*
X861406D03*
X869756Y797698D03*
X873850Y797700D03*
X870900Y805400D03*
X896500Y13300D03*
X886520Y13302D03*
X899200Y61700D03*
X906500Y89800D03*
X893000D03*
X897500D03*
X884000D03*
X879500D03*
X902000D03*
X888500D03*
X875000D03*
X895000Y305900D03*
X891000D03*
X886276Y800348D03*
X890406Y797698D03*
X877949Y800300D03*
X894406Y797698D03*
X882049Y800300D03*
X898406Y797698D03*
X955400Y69000D03*
X951500Y89800D03*
X947000D03*
X942500D03*
X996230Y43044D03*
X1033000Y66300D03*
X1037000Y101800D03*
X1041500D03*
X1024000D03*
X1028000D03*
X1032500D03*
X1020000D03*
X1015948D03*
X1070733Y41223D03*
X1068673Y20945D03*
X1050500Y101800D03*
X1046000D03*
X1173479Y130171D03*
X1169467Y130176D03*
X1216752Y130115D03*
X1212748D03*
X1270005Y130221D03*
X1265997Y130222D03*
X1258500Y338800D03*
X1270500D03*
X1262500D03*
X1266500D03*
X1277500Y397800D03*
Y390300D03*
X1307000Y278800D03*
X1301500Y390300D03*
X1293500D03*
X1297500D03*
X1285500D03*
X1305500D03*
X1289500D03*
X1302128Y677167D03*
X1306128D03*
X1335071Y134411D03*
X1317300Y298200D03*
X1321400D03*
X1315000Y278800D03*
X1313000Y289800D03*
X1314628Y726167D03*
X1326128D03*
X1330128D03*
X1334128D03*
X1338128D03*
X1326100Y734200D03*
X1361500Y266800D03*
G54D34*
X28500Y746900D03*
Y733400D03*
Y729400D03*
X45700Y276800D03*
Y280900D03*
X39100Y394100D03*
X59200Y483000D03*
Y502000D03*
X58800Y708900D03*
X56600Y770800D03*
X70543Y354737D03*
X74200Y506500D03*
Y510500D03*
Y514500D03*
X84400Y529300D03*
X70340Y527270D03*
X84200Y542300D03*
Y546300D03*
X84100Y550400D03*
X84200Y554500D03*
Y558500D03*
X77200Y586000D03*
X90200Y642000D03*
Y646000D03*
X98400Y681900D03*
X81800Y731300D03*
Y727300D03*
X83000Y740900D03*
Y744900D03*
Y766900D03*
X101200Y276300D03*
X104200Y298900D03*
Y302900D03*
X115700Y388600D03*
X115634Y441150D03*
X101700Y569500D03*
X110700Y561500D03*
Y565500D03*
X101700Y592500D03*
X105900Y681900D03*
X119600Y714300D03*
X102600Y727800D03*
X121700Y775000D03*
X153014Y322277D03*
X145513Y322350D03*
X136214Y373985D03*
X160800Y379200D03*
X146698Y420306D03*
X140600Y732300D03*
X132400Y745200D03*
X172484Y186686D03*
Y181686D03*
X197400Y251100D03*
X194015Y289501D03*
X182554Y446672D03*
X174900Y753400D03*
X167700Y808500D03*
X203960Y289306D03*
X213438Y425645D03*
X213238Y441945D03*
X209400Y446000D03*
X213200Y465000D03*
Y469000D03*
Y482000D03*
Y486000D03*
X213300Y494400D03*
X213200Y490000D03*
Y525500D03*
Y521500D03*
Y554500D03*
X226070Y568020D03*
X207200Y729500D03*
Y785000D03*
X239700Y139500D03*
X253928Y124804D03*
X256600Y438600D03*
X259300Y422500D03*
X253400Y443300D03*
X255720Y581381D03*
X233700Y586000D03*
Y590000D03*
X273200Y126000D03*
X272800Y467300D03*
Y485800D03*
X278000Y638900D03*
X285500Y643900D03*
X314700Y221900D03*
X319100Y542500D03*
X338600Y222000D03*
X338300Y335500D03*
X348000Y318500D03*
X463549Y210989D03*
X500232Y130548D03*
X484209Y339041D03*
Y334041D03*
X483900Y393300D03*
X530000Y165815D03*
Y157715D03*
Y161815D03*
X519109Y202072D03*
X511409Y202172D03*
X525800Y340500D03*
X561670Y136909D03*
X554200Y137597D03*
X561731Y334980D03*
X593163Y215308D03*
X575800Y238400D03*
X623063Y217608D03*
X615563Y213608D03*
X608400Y344200D03*
X667200Y212000D03*
X692600Y212200D03*
X681200Y212000D03*
X725913Y2380D03*
X736463Y31882D03*
X720705Y14964D03*
X724359Y28613D03*
X738330Y63910D03*
X717700Y64000D03*
X716810Y55860D03*
Y51796D03*
X756000Y53800D03*
X761150Y75900D03*
X761300Y86500D03*
Y90600D03*
Y102900D03*
Y82300D03*
X768900Y121200D03*
Y133500D03*
X759200Y118800D03*
X778300Y74000D03*
X798300Y74200D03*
X838800Y105600D03*
X810200Y86500D03*
Y90600D03*
X812113Y118898D03*
X849581Y5499D03*
X865200Y32000D03*
Y40000D03*
X865700Y52800D03*
Y48500D03*
X903700Y358500D03*
Y350000D03*
Y345600D03*
X889870Y808230D03*
X908200Y37000D03*
X932300Y78600D03*
X958781Y64624D03*
X992411Y14160D03*
X992569Y27248D03*
Y23121D03*
X1024760Y2024D03*
X1036816Y33563D03*
X1035592Y11076D03*
X1054700Y22200D03*
X1043367Y11296D03*
X1058200Y48700D03*
X1052800Y64100D03*
X1079259Y5500D03*
Y500D03*
X1079269Y22450D03*
X1079824Y39554D03*
X1079269Y26950D03*
X1079824Y35054D03*
X1078539Y14070D03*
X1123700Y235000D03*
X1137700Y234500D03*
X1152200D03*
X1292700Y300000D03*
X1318700Y274500D03*
X1360200Y278500D03*
G54D61*
X64700Y717400D03*
G54D52*
X48000Y426000D03*
G54D163*
X1356988Y55905D03*
G54D136*
X598808Y205137D03*
X602808Y213937D03*
X606808Y205137D03*
G54D154*
X892900Y57935D03*
X1049935Y28600D03*
G54D127*
X473231Y235560D03*
Y274930D03*
X487404Y255245D03*
G54D173*
G01X62400Y342700D02*
X64100Y341000D01*
Y339426D01*
X65826Y337700D01*
X68150D01*
X69800Y336050D01*
Y324468D01*
X68980Y323648D01*
Y318342D01*
X68547Y317909D01*
Y315317D01*
G01X66800Y342700D02*
X65300Y341200D01*
Y339924D01*
X66324Y338900D01*
X68648D01*
X71000Y336548D01*
Y323970D01*
X70180Y323150D01*
Y318222D01*
X70516Y317886D01*
Y315317D01*
G01X83500Y344200D02*
G03X82477Y342500I901J-1700D01*
G01Y339423D01*
X83600Y338300D01*
Y332850D01*
X84700Y331750D01*
G01X80300Y344200D02*
G02X81277Y342500I-991J-1700D01*
G01Y338925D01*
X82400Y337802D01*
Y332850D01*
X81300Y331750D01*
G01X74453Y315317D02*
Y318382D01*
X76311Y320240D01*
Y321360D01*
X77421Y322470D01*
G01X72484Y315317D02*
Y318111D01*
X75111Y320738D01*
Y321580D01*
X74221Y322470D01*
G01X84700Y328250D02*
X83570Y327120D01*
Y323250D01*
X79940Y319620D01*
Y318801D01*
X80358Y318383D01*
Y315317D01*
G01X81300Y328250D02*
X82370Y327180D01*
Y323748D01*
X78740Y320118D01*
Y318733D01*
X78390Y318383D01*
Y315317D01*
G01X87735Y486004D02*
X86550Y487189D01*
X85490D01*
G03X85109Y487031I0J-538D01*
G01X77608Y479530D01*
G03X77031Y478471I1510J-1509D01*
G01X74646Y467425D01*
Y466728D01*
X74782Y465296D01*
X76415Y457610D01*
G03X77240Y455618I5785J1229D01*
G01X83746Y445602D01*
X88210Y442473D01*
G03X88337Y442392I1138J1644D01*
G01X88340Y442390D01*
X88851Y442086D01*
G03X89481Y441844I1022J1719D01*
G01X91984Y441344D01*
G03X92714Y441334I392J1961D01*
G01X93100Y441400D01*
G03X96351Y443000I0J4103D01*
G01Y438600D02*
G03X93198Y440198I-3250J-2503D01*
G01X93193D01*
X92917Y440151D01*
G02X91749Y440167I-541J3154D01*
G01X89246Y440667D01*
G02X88237Y441054I625J3139D01*
G01X87726Y441359D01*
G02X87523Y441488I1614J2763D01*
G01X82952Y444692D01*
G02X82809Y444840I308J441D01*
G01X76233Y454964D01*
G02X75241Y457361I5967J3873D01*
G01X73593Y465114D01*
X73446Y466671D01*
Y467554D01*
X75857Y478725D01*
G02X76759Y480379I3260J-705D01*
G01X84260Y487880D01*
G02X85490Y488389I1229J-1230D01*
G01X86620D01*
X87735Y489504D01*
G01X96860Y496307D02*
X96360Y495807D01*
X87560D01*
X75056Y487624D01*
X70095Y480268D01*
X67388Y466348D01*
X70590Y451286D01*
X70589D01*
X70590Y451284D01*
X82201Y434046D01*
G03X82965Y433283I2332J1571D01*
G01X89961Y428587D01*
G03X91455Y428133I1493J2228D01*
G01X94688D01*
X96044Y426778D01*
X96046Y426780D01*
G01D02*
X97262Y427996D01*
X98850D01*
X100079Y426767D01*
G01X96860Y494107D02*
X96360Y494607D01*
X92470D01*
X91808Y493945D01*
X90194D01*
X89532Y494607D01*
X87918D01*
X83597Y491779D01*
X83406Y490863D01*
X82055Y489979D01*
X81139Y490170D01*
X79725Y489245D01*
X79533Y488328D01*
X78183Y487444D01*
X77266Y487636D01*
X75916Y486752D01*
X71227Y479799D01*
X70351Y475295D01*
X70874Y474519D01*
X70566Y472935D01*
X69790Y472411D01*
X69482Y470827D01*
X70005Y470051D01*
X69697Y468467D01*
X68921Y467943D01*
X68613Y466359D01*
X69823Y460667D01*
X70608Y460158D01*
X70944Y458579D01*
X70434Y457794D01*
X70770Y456215D01*
X71555Y455705D01*
X71890Y454126D01*
X71380Y453341D01*
X71716Y451762D01*
X73024Y449820D01*
X73943Y449640D01*
X74845Y448302D01*
X74665Y447383D01*
X75567Y446044D01*
X76486Y445865D01*
X77388Y444527D01*
X77208Y443608D01*
X78110Y442269D01*
X79029Y442089D01*
X79931Y440751D01*
X79751Y439832D01*
X80653Y438493D01*
X81572Y438313D01*
X82474Y436975D01*
X82294Y436056D01*
X83196Y434717D01*
G03X83634Y434280I1336J901D01*
G01X84974Y433381D01*
X85893Y433561D01*
X87233Y432662D01*
X87414Y431743D01*
X90630Y429584D01*
G03X91455Y429333I825J1230D01*
G01X94683D01*
X96043Y430693D01*
G01D02*
X97540Y429196D01*
X98592D01*
X100076Y430680D01*
G01X120098Y493248D02*
X119138Y493889D01*
G03X118188Y494397I-3052J-4565D01*
G01X117688Y494604D01*
G03X117120Y494717I-568J-1371D01*
G01X116800D01*
G03X115805Y494305I0J-1407D01*
G01X109920Y488419D01*
G02X107518Y486536I-8977J8978D01*
G01X104940Y484974D01*
X98188Y482300D01*
X90740D01*
G03X88581Y481661I-1J-3963D01*
G01X84351Y478913D01*
G03X82317Y476879I3769J-5803D01*
G01X80479Y474049D01*
G03X79567Y471846I5485J-3561D01*
G01X78760Y468046D01*
G03Y465838I5199J-1104D01*
G01X80006Y459971D01*
G03X80840Y457956I5851J1241D01*
G01X84684Y452037D01*
X85181Y451540D01*
G03X85334Y451404I1227J1226D01*
G03X86029Y450954I2764J3506D01*
G03X88100Y450445I2070J3955D01*
G01X88600D01*
G02X89040Y450402I-3J-2306D01*
G01X89131Y450389D01*
G02X89305Y450333I-72J-521D01*
G01X89653Y450147D01*
G02X90429Y449572I-1538J-2887D01*
G01X91200Y448800D01*
G01X116948Y493248D02*
G03X116881Y493246I3J-1212D01*
G03X116160Y492961I0J-1055D01*
G01X110769Y487570D01*
G02X108140Y485509I-9826J9827D01*
G01X105476Y483895D01*
X98417Y481100D01*
X90740D01*
G03X89235Y480654I0J-2762D01*
G01X85005Y477906D01*
G03X83324Y476225I3115J-4796D01*
G01X81486Y473395D01*
G03X80741Y471597I4478J-2909D01*
G01X79934Y467797D01*
G03Y466087I4025J-855D01*
G01X81180Y460220D01*
G03X81847Y458610I4676J994D01*
G01X85622Y452797D01*
X86030Y452389D01*
G03X86078Y452347I375J380D01*
G03X86586Y452018I2021J2563D01*
G03X88099Y451645I1535J2973D01*
G01X88903D01*
G03X89342Y451732I1J1147D01*
G01X89570Y451827D01*
G03X90345Y452345I-916J2209D01*
G01X91200Y453200D01*
G01X116948Y496397D02*
G03X116299Y496666I-649J-649D01*
G01X114064D01*
X112823Y495425D01*
Y494223D01*
X111961Y493361D01*
X110759D01*
X109618Y492220D01*
Y491018D01*
X108757Y490157D01*
X107555D01*
X106376Y488978D01*
G02X104748Y488304I-1627J1627D01*
G01X102943D01*
X102205Y487566D01*
X100591D01*
X99853Y488304D01*
X98239D01*
X97501Y487566D01*
X95887D01*
X95149Y488304D01*
X93535D01*
X91235Y486004D01*
G01Y489504D02*
X104748D01*
G03X105527Y489827I0J1101D01*
G01X113566Y497866D01*
X117100D01*
G02X120098Y496397I0J-3794D01*
G01X107608Y427004D02*
X108634Y428030D01*
X109395D01*
X110041Y427384D01*
Y420594D01*
G03X110546Y419369I1734J-2D01*
G01X110825Y419090D01*
G02Y417486I-802J-802D01*
G01X110406Y417067D01*
G01X107612Y430420D02*
X108802Y429230D01*
X109893D01*
X111241Y427882D01*
Y420594D01*
G03X111397Y420217I534J0D01*
G01X111674Y419939D01*
G03X113278I802J802D01*
G01X113518Y420179D01*
G01X100079Y426767D02*
X101352Y428040D01*
X103072D01*
X104108Y427004D01*
G01X100076Y430680D02*
X101516Y429240D01*
X102932D01*
X104112Y430420D01*
G01X123247Y546791D02*
G02X122900Y547700I1017J909D01*
G01Y548700D01*
X117232Y554368D01*
G02X116500Y556136I1768J1768D01*
G01Y559601D01*
G03X115158Y562840I-4582J-1D01*
G01X114395Y563604D01*
G03X113193Y564100I-1200J-1204D01*
G01X112300D01*
G02X110750Y565500I0J1558D01*
G01Y561500D02*
G02X112300Y562900I1550J-158D01*
G01X113193D01*
G02X113546Y562754I0J-500D01*
G01X114299Y562000D01*
X114300Y562001D01*
X114309Y561991D01*
G02X115300Y559600I-2391J-2392D01*
G01Y556134D01*
G03X116384Y553517I3700J0D01*
G01X117525Y552376D01*
Y551510D01*
X118667Y550369D01*
X119533D01*
X121700Y548202D01*
Y547100D01*
X121391Y546791D01*
X120098D01*
G01X102870Y565740D02*
X104510Y564100D01*
X105850D01*
X107250Y565500D01*
G01Y561500D02*
X105850Y562900D01*
X104430D01*
X102870Y561340D01*
G01X153130Y170531D02*
Y165458D01*
G02X152895Y164893I-799J1D01*
G01X148037Y160035D01*
G03X147100Y157772I2262J-2262D01*
G01Y156876D01*
G02X146869Y156318I-789J0D01*
G01X144094Y153543D01*
G01X167484Y186086D02*
X165072D01*
X163772Y184786D01*
X160692D01*
X158058Y187420D01*
X153782D01*
X151199Y184837D01*
Y177711D01*
X153130Y175780D01*
Y170531D01*
G01X151968Y153543D02*
X149511D01*
G02X148878Y153805I0J896D01*
G01X148720Y153963D01*
G02X148300Y154977I1014J1014D01*
G01Y157772D01*
G02X148886Y159186I1999J0D01*
G01X153744Y164044D01*
G03X154330Y165458I-1413J1414D01*
G01Y167330D01*
X155190Y168190D01*
Y172950D01*
X154330Y173810D01*
Y176278D01*
X153130Y177478D01*
Y181131D01*
G01D02*
Y185070D01*
X154280Y186220D01*
X157560D01*
X160194Y183586D01*
X163772D01*
X165072Y182286D01*
X167484D01*
G01X148444Y543641D02*
X149913Y545110D01*
Y549374D01*
X147451Y551836D01*
G01X154743Y543641D02*
Y544713D01*
X156212Y546182D01*
Y549598D01*
X155064Y550746D01*
Y554063D01*
X151989Y557138D01*
G01X161043Y543641D02*
X162723Y545321D01*
Y547400D01*
X169855Y554532D01*
Y571998D01*
X168653Y573200D01*
X165902D01*
X164700Y571998D01*
Y559198D01*
X164062Y558560D01*
X162042D01*
X161882Y558400D01*
X161280D01*
G01X148444Y546791D02*
X148713Y547060D01*
Y548876D01*
X148053Y549536D01*
X147451D01*
G01X161043Y546791D02*
X161523Y547271D01*
Y547898D01*
X168655Y555030D01*
Y571500D01*
X168155Y572000D01*
X166400D01*
X165900Y571500D01*
Y558700D01*
X164560Y557360D01*
X162540D01*
X161280Y556100D01*
G01X154743Y546791D02*
X155012Y547060D01*
Y549100D01*
X153864Y550248D01*
Y553565D01*
X152591Y554838D01*
X151989D01*
G01X136095Y599921D02*
X137669Y601495D01*
G01X139244Y599921D02*
Y602039D01*
X139705Y602500D01*
X140357D01*
X140818Y602039D01*
Y601495D01*
G01X145543Y612519D02*
X147117Y610945D01*
G01X161291Y599921D02*
Y602000D01*
X161791Y602500D01*
X162365D01*
X162865Y602000D01*
Y601495D01*
G01X148693Y612519D02*
Y610700D01*
X149193Y610200D01*
X149768D01*
X150268Y610700D01*
Y610944D01*
G01X158142Y599921D02*
X159716Y601495D01*
G01X206297Y188492D02*
X207481Y187308D01*
Y185727D01*
X205654Y183900D01*
X203786D01*
X203174Y184512D01*
X201560D01*
X200948Y183900D01*
X199334D01*
X198722Y184512D01*
X197108D01*
X196496Y183900D01*
X194882D01*
X194270Y184512D01*
X192656D01*
X192044Y183900D01*
X190430D01*
X189818Y184512D01*
X188204D01*
X187592Y183900D01*
X181698D01*
X180812Y184786D01*
X177796D01*
X176496Y186086D01*
X174084D01*
G01X209866Y188492D02*
X208681Y187307D01*
Y185229D01*
X206152Y182700D01*
X181200D01*
X180314Y183586D01*
X177796D01*
X176496Y182286D01*
X174084D01*
G01X167484Y186086D02*
X168434D01*
X169034Y186686D01*
G01X167484Y182286D02*
X168434D01*
X169034Y181686D01*
G01X209750Y506000D02*
X205900D01*
X204585Y507315D01*
X182481D01*
X181012Y505846D01*
X179940D01*
G01X176791Y508996D02*
X178365Y507422D01*
G01X209750Y502000D02*
X208387D01*
X207886Y502501D01*
Y504005D01*
X207091Y504800D01*
X205402D01*
X204087Y506115D01*
X196955D01*
X196303Y505463D01*
X194689D01*
X194037Y506115D01*
X192423D01*
X191771Y505463D01*
X190157D01*
X189505Y506115D01*
X187891D01*
X187239Y505463D01*
X185625D01*
X184973Y506115D01*
X183359D01*
X183090Y505846D01*
G01X173641Y508996D02*
X175215Y507422D01*
G01X181496Y887970D02*
Y883411D01*
G03X181642Y883058I500J0D01*
G01X182325Y882375D01*
G02X182471Y882022I-354J-353D01*
G01Y880783D01*
G02X182178Y880076I-1000J0D01*
G01X181075Y878973D01*
G03X180431Y877418I1556J-1555D01*
G01Y832569D01*
X228707Y784293D01*
G02X229500Y782379I-1913J-1914D01*
G01Y774625D01*
G02X228811Y772961I-2354J0D01*
G01X228550Y772700D01*
G01X184646Y887970D02*
Y883353D01*
G02X184500Y883000I-500J0D01*
G01X183817Y882317D01*
G03X183671Y881964I354J-353D01*
G01Y880782D01*
G02X183027Y879227I-2200J0D01*
G01X181924Y878124D01*
G03X181631Y877417I707J-707D01*
G01Y833067D01*
X229556Y785142D01*
G02X230700Y782379I-2763J-2762D01*
G01Y775235D01*
G03X231750Y772700I3585J0D01*
G01X194520Y834551D02*
X193326Y833356D01*
G03X193095Y832800I556J-557D01*
G01Y831848D01*
G03X193464Y830957I1260J0D01*
G01X194120Y830301D01*
G01X190520Y834551D02*
X191629Y833442D01*
G02X191895Y832800I-642J-642D01*
G01Y831800D01*
G02X191524Y830906I-1265J1D01*
G01X190920Y830301D01*
G01X194095Y887970D02*
Y885151D01*
G02X193426Y883152I-3325J1D01*
G03X193121Y882416I736J-736D01*
G01Y841428D01*
G03X194520Y838051I4776J0D01*
G01X190945Y887970D02*
Y885152D01*
X190946Y885151D01*
G03X191608Y883160I3325J0D01*
G02X191920Y882407I-753J-753D01*
G01Y841431D01*
G02X190520Y838051I-4780J0D01*
G01X404040Y318900D02*
G03X402440Y320500I-1600J0D01*
G01X392602D01*
X386300Y326802D01*
Y345702D01*
X365602Y366400D01*
X292494D01*
X289846Y369048D01*
X253798D01*
X237200Y352450D01*
Y349054D01*
X225121Y336975D01*
X222920D01*
G03X221460Y335515I0J-1460D01*
G01Y335475D01*
G01Y339875D02*
G03X223160Y338175I1700J0D01*
G01X224623D01*
X236000Y349552D01*
Y352948D01*
X253300Y370248D01*
X290344D01*
X292992Y367600D01*
X366100D01*
X387500Y346200D01*
Y327300D01*
X393100Y321700D01*
X402644D01*
G03X404040Y323300I0J1409D01*
G01X260407Y502674D02*
X259408Y503673D01*
Y504509D01*
X257759Y506158D01*
X252835D01*
X251177Y504500D01*
X231802D01*
X227740Y500438D01*
X225755D01*
X221662Y504531D01*
X214719D01*
X213250Y506000D01*
G01X257207Y502674D02*
X258208Y503675D01*
Y504011D01*
X257261Y504958D01*
X253333D01*
X251675Y503300D01*
X232300D01*
X228238Y499238D01*
X225257D01*
X221164Y503331D01*
X214581D01*
X213250Y502000D01*
G01X232315Y834551D02*
X231121Y833356D01*
G03X230890Y832800I556J-557D01*
G01Y831849D01*
G03X231260Y830956I1263J0D01*
G01X231915Y830301D01*
G01X219717Y834551D02*
X218523Y833356D01*
G03X218292Y832800I556J-557D01*
G01Y831822D01*
G03X218643Y830976I1197J1D01*
G01X219317Y830301D01*
G01X207118Y834551D02*
X205924Y833356D01*
G03X205693Y832800I556J-557D01*
G01Y831942D01*
G03X206129Y830891I1487J1D01*
G01X206718Y830301D01*
G01X228315Y834551D02*
X229424Y833442D01*
G02X229690Y832800I-642J-642D01*
G01Y831817D01*
G02X229307Y830894I-1306J1D01*
G01X228715Y830301D01*
G01X215717Y834551D02*
X216826Y833442D01*
G02X217092Y832800I-642J-642D01*
G01Y831822D01*
G02X216706Y830890I-1318J0D01*
G01X216117Y830301D01*
G01X203118Y834551D02*
X204227Y833442D01*
G02X204493Y832800I-642J-642D01*
G01Y831900D01*
G02X204052Y830835I-1506J0D01*
G01X203518Y830301D01*
G01X231890Y887970D02*
Y885151D01*
G02X231221Y883152I-3325J1D01*
G03X230916Y882416I736J-736D01*
G01Y841428D01*
G03X232315Y838051I4776J0D01*
G01X219292Y887970D02*
Y885151D01*
G02X218623Y883152I-3325J1D01*
G03X218318Y882416I736J-736D01*
G01Y841428D01*
G03X219717Y838051I4776J0D01*
G01X206693Y887970D02*
Y885151D01*
G02X206024Y883152I-3325J1D01*
G03X205719Y882416I736J-736D01*
G01Y841428D01*
G03X207118Y838051I4776J0D01*
G01X228740Y887970D02*
Y885152D01*
X228741Y885151D01*
G03X229403Y883160I3325J0D01*
G02X229715Y882407I-753J-753D01*
G01Y841431D01*
G02X228315Y838051I-4780J0D01*
G01X216142Y887970D02*
Y885152D01*
X216143Y885151D01*
G03X216805Y883160I3325J0D01*
G02X217117Y882407I-753J-753D01*
G01Y841431D01*
G02X215717Y838051I-4780J0D01*
G01X203544Y887970D02*
Y885151D01*
G03X204206Y883160I3325J0D01*
G02X204518Y882407I-753J-753D01*
G01Y841431D01*
G02X203118Y838051I-4780J0D01*
G01X266961Y834551D02*
X265767Y833356D01*
G03X265536Y832800I556J-557D01*
G01Y831887D01*
G02Y831877I-2675J-5D01*
G03X265926Y830937I1330J1D01*
G01X266561Y830301D01*
G01X254362Y834551D02*
X253168Y833356D01*
G03X252937Y832800I556J-557D01*
G01Y831989D01*
G03X253406Y830857I1601J0D01*
G01X253962Y830301D01*
G01X262961Y834551D02*
X264070Y833442D01*
G02X264336Y832800I-642J-642D01*
G01Y831887D01*
G02X263904Y830844I-1475J0D01*
G01X263361Y830301D01*
G01X250362Y834551D02*
X251471Y833442D01*
G02X251737Y832800I-642J-642D01*
G01Y831989D01*
G02X251233Y830772I-1721J0D01*
G01X250762Y830301D01*
G01X266536Y887970D02*
Y885151D01*
G02X265867Y883152I-3325J1D01*
G03X265562Y882416I736J-736D01*
G01Y841428D01*
G03X266961Y838051I4776J0D01*
G01X253937Y887970D02*
Y885151D01*
G02X253268Y883152I-3325J1D01*
G03X252963Y882416I736J-736D01*
G01Y841428D01*
G03X254362Y838051I4776J0D01*
G01X263386Y887970D02*
Y885152D01*
X263387Y885151D01*
G03X264049Y883160I3325J0D01*
G02X264361Y882407I-753J-753D01*
G01Y841431D01*
G02X262961Y838051I-4780J0D01*
G01X250788Y887970D02*
Y885151D01*
G03X251450Y883160I3325J0D01*
G02X251762Y882407I-753J-753D01*
G01Y841431D01*
G02X250362Y838051I-4780J0D01*
G01X279559Y834551D02*
X278365Y833356D01*
G03X278134Y832800I556J-557D01*
G01Y831944D01*
G03X278571Y830889I1492J0D01*
G01X279159Y830301D01*
G01X275559Y834551D02*
X276668Y833442D01*
G02X276934Y832800I-642J-642D01*
G01Y831882D01*
G02X276505Y830848I-1463J1D01*
G01X275959Y830301D01*
G01X279134Y887970D02*
Y885151D01*
G02X278465Y883152I-3325J1D01*
G03X278160Y882416I736J-736D01*
G01Y841428D01*
G03X279559Y838051I4776J0D01*
G01X275985Y887970D02*
Y885151D01*
G03X276647Y883160I3325J0D01*
G02X276959Y882407I-753J-753D01*
G01Y841431D01*
G02X275559Y838051I-4780J0D01*
G01X329953Y834551D02*
X328759Y833356D01*
G03X328528Y832800I556J-557D01*
G01Y831943D01*
G03X328964Y830889I1490J-1D01*
G01X329553Y830301D01*
G01X317354Y834551D02*
X316160Y833356D01*
G03X315929Y832800I556J-557D01*
G01Y831746D01*
G03X316226Y831029I1014J0D01*
G01X316954Y830301D01*
G01X325953Y834551D02*
X327062Y833442D01*
G02X327328Y832800I-642J-642D01*
G01Y831900D01*
G02X326887Y830835I-1506J0D01*
G01X326353Y830301D01*
G01X313354Y834551D02*
X314463Y833442D01*
G02X314729Y832800I-642J-642D01*
G01Y831700D01*
G02X314429Y830976I-1024J0D01*
G01X313754Y830301D01*
G01X329528Y887970D02*
Y885151D01*
G02X328859Y883152I-3325J1D01*
G03X328554Y882416I736J-736D01*
G01Y841428D01*
G03X329953Y838051I4776J0D01*
G01X316929Y887970D02*
Y885151D01*
G02X316260Y883152I-3325J1D01*
G03X315955Y882416I736J-736D01*
G01Y841428D01*
G03X317354Y838051I4776J0D01*
G01X326378Y887970D02*
Y885152D01*
X326379Y885151D01*
G03X327041Y883160I3325J0D01*
G02X327353Y882407I-753J-753D01*
G01Y841431D01*
G02X325953Y838051I-4780J0D01*
G01X313780Y887970D02*
Y885151D01*
G03X314442Y883160I3325J0D01*
G02X314754Y882407I-753J-753D01*
G01Y841431D01*
G02X313354Y838051I-4780J0D01*
G01X436614Y887970D02*
Y885151D01*
G02X435945Y883152I-3325J1D01*
G03X435640Y882416I736J-736D01*
G01Y830752D01*
G02X433615Y824328I-11200J-1D01*
G01X409995Y790596D01*
X378693Y768678D01*
X364478Y748378D01*
X362104Y734918D01*
Y733013D01*
G03X362263Y732631I540J0D01*
G01X362694Y732200D01*
G03X363657Y731801I963J963D01*
G01X364354D01*
G01X433465Y887970D02*
Y887901D01*
X433464Y887900D01*
Y885152D01*
X433465Y885151D01*
G03X434127Y883160I3325J0D01*
G02X434439Y882407I-753J-753D01*
G01Y873301D01*
X434440Y873300D01*
Y830753D01*
G02X432632Y825017I-10000J-1D01*
G01X409133Y791458D01*
X377831Y769540D01*
X363342Y748848D01*
X360904Y735024D01*
Y733012D01*
G03X361414Y731782I1740J1D01*
G01X361845Y731351D01*
G02X362091Y730757I-594J-594D01*
G01Y729538D01*
G01X367748Y834551D02*
X366554Y833356D01*
G03X366323Y832800I556J-557D01*
G01Y831924D01*
G03X366746Y830903I1444J0D01*
G01X367348Y830301D01*
G01X355150Y834551D02*
X353956Y833356D01*
G03X353725Y832800I556J-557D01*
G01Y832025D01*
G03X354219Y830831I1688J-1D01*
G01X354750Y830301D01*
G01X342551Y834551D02*
X341357Y833356D01*
G03X341126Y832800I556J-557D01*
G01Y831943D01*
G03X341562Y830889I1490J-1D01*
G01X342151Y830301D01*
G01X363748Y834551D02*
X364857Y833442D01*
G02X365123Y832800I-642J-642D01*
G01Y831923D01*
G02X364666Y830818I-1562J-1D01*
G01X364148Y830301D01*
G01X351150Y834551D02*
X352259Y833442D01*
G02X352525Y832800I-642J-642D01*
G01Y832025D01*
G02X351995Y830747I-1808J1D01*
G01X351550Y830301D01*
G01X338551Y834551D02*
X339660Y833442D01*
G02X339926Y832800I-642J-642D01*
G01Y831900D01*
G02X339485Y830835I-1506J0D01*
G01X338951Y830301D01*
G01X367323Y887970D02*
Y885151D01*
G02X366654Y883152I-3325J1D01*
G03X366349Y882416I736J-736D01*
G01Y841428D01*
G03X367748Y838051I4776J0D01*
G01X354725Y887970D02*
Y885151D01*
G02X354056Y883152I-3325J1D01*
G03X353751Y882416I736J-736D01*
G01Y841428D01*
G03X355150Y838051I4776J0D01*
G01X342126Y887970D02*
Y885151D01*
G02X341457Y883152I-3325J1D01*
G03X341152Y882416I736J-736D01*
G01Y841428D01*
G03X342551Y838051I4776J0D01*
G01X364174Y887970D02*
Y885151D01*
G03X364836Y883160I3325J0D01*
G02X365148Y882407I-753J-753D01*
G01Y841431D01*
G02X363748Y838051I-4780J0D01*
G01X351575Y887970D02*
Y885152D01*
X351576Y885151D01*
G03X352238Y883160I3325J0D01*
G02X352550Y882407I-753J-753D01*
G01Y841431D01*
G02X351150Y838051I-4780J0D01*
G01X338977Y887970D02*
Y885151D01*
G03X339639Y883160I3325J0D01*
G02X339951Y882407I-753J-753D01*
G01Y841431D01*
G02X338551Y838051I-4780J0D01*
G01X402394Y834551D02*
X401200Y833356D01*
G03X400969Y832800I556J-557D01*
G01Y831867D01*
G02Y831818I-2627J-25D01*
G03X401317Y830978I1188J0D01*
G01X401994Y830301D01*
G01X389796Y834551D02*
X388602Y833356D01*
G03X388371Y832800I556J-557D01*
G01Y831848D01*
G03X388740Y830957I1260J0D01*
G01X389396Y830301D01*
G01X398394Y834551D02*
X399503Y833442D01*
G02X399769Y832800I-642J-642D01*
G01Y831867D01*
G02X399351Y830858I-1427J0D01*
G01X398794Y830301D01*
G01X385796Y834551D02*
X386905Y833442D01*
G02X387171Y832800I-642J-642D01*
G01Y831800D01*
G02X386800Y830906I-1265J1D01*
G01X386196Y830301D01*
G01X401969Y887970D02*
Y885151D01*
G02X401300Y883152I-3325J1D01*
G03X400995Y882416I736J-736D01*
G01Y841428D01*
G03X402394Y838051I4776J0D01*
G01X389370Y887970D02*
Y885152D01*
X389371Y885151D01*
G02X388702Y883152I-3325J1D01*
G03X388397Y882416I736J-736D01*
G01Y841428D01*
G03X389796Y838051I4776J0D01*
G01X398819Y887970D02*
Y885152D01*
X398820Y885151D01*
G03X399482Y883160I3325J0D01*
G02X399794Y882407I-753J-753D01*
G01Y841431D01*
G02X398394Y838051I-4780J0D01*
G01X386221Y887970D02*
Y885152D01*
X386222Y885151D01*
G03X386884Y883160I3325J0D01*
G02X387196Y882407I-753J-753D01*
G01Y841431D01*
G02X385796Y838051I-4780J0D01*
G01X427591Y834551D02*
X426397Y833356D01*
G03X426166Y832800I556J-557D01*
G01Y832046D01*
G03X426675Y830817I1738J0D01*
G01X427191Y830301D01*
G01X414993Y834551D02*
X413799Y833356D01*
G03X413568Y832800I556J-557D01*
G01Y831864D01*
G02Y831854I-2620J-5D01*
G03X413941Y830952I1275J-1D01*
G01X414593Y830301D01*
G01X423591Y834551D02*
X424700Y833442D01*
G02X424966Y832800I-642J-642D01*
G01Y831982D01*
G02X424467Y830777I-1704J0D01*
G01X423991Y830301D01*
G01X410993Y834551D02*
X412102Y833442D01*
G02X412368Y832800I-642J-642D01*
G01Y831864D01*
G02X411952Y830860I-1420J0D01*
G01X411393Y830301D01*
G01X427166Y887970D02*
Y885151D01*
G02X426497Y883152I-3325J1D01*
G03X426192Y882416I736J-736D01*
G01Y841428D01*
G03X427591Y838051I4776J0D01*
G01X414567Y887970D02*
Y885152D01*
X414568Y885151D01*
G02X413899Y883152I-3325J1D01*
G03X413594Y882416I736J-736D01*
G01Y841428D01*
G03X414993Y838051I4776J0D01*
G01X424016Y887970D02*
Y885152D01*
X424017Y885151D01*
G03X424679Y883160I3325J0D01*
G02X424991Y882407I-753J-753D01*
G01Y841431D01*
G02X423591Y838051I-4780J0D01*
G01X411418Y887970D02*
Y885152D01*
X411419Y885151D01*
G03X412081Y883160I3325J0D01*
G02X412393Y882407I-753J-753D01*
G01Y841431D01*
G02X410993Y838051I-4780J0D01*
G01X524151Y99725D02*
X524152Y98672D01*
G03X525021Y97556I1152J1D01*
G03X525893Y97808I1J1630D01*
G03X525987Y97872I-870J1379D01*
G03X526174Y98033I-967J1313D01*
G01X526380Y98240D01*
X526917Y98993D01*
X526956Y99040D01*
G03X526809Y102003I-1710J1400D01*
G01X509776Y119036D01*
G03X508391Y119610I-1385J-1384D01*
G01X506490D01*
G02X501573Y124527I0J4917D01*
G01Y128700D01*
G03X500282Y130548I-1968J0D01*
G01X500238Y134000D02*
G03X501705Y136504I-1404J2504D01*
G01Y141995D01*
G02X502452Y143800I2552J1D01*
G01X505037Y146385D01*
G02X507487Y147399I2449J-2450D01*
G01Y147400D01*
X507488Y147399D01*
X517559D01*
G03X520348Y148554I0J3945D01*
G01X520809Y149015D01*
G03X521504Y150692I-1677J1678D01*
G01Y151675D01*
X521500D01*
Y164574D01*
G03X521287Y165087I-726J-1D01*
G03X520774Y165300I-514J-513D01*
G01X520186D01*
G03X518686Y163800I0J-1500D01*
G01X527104Y94213D02*
X527103Y94214D01*
Y96357D01*
G02X527183Y97018I2748J3D01*
G02X527206Y97107I2672J-643D01*
G02X527349Y97496I2644J-751D01*
G01X527403Y97607D01*
X527870Y98261D01*
X527884Y98278D01*
G03X527658Y102852I-2638J2162D01*
G01X510625Y119885D01*
G03X508390Y120810I-2233J-2233D01*
G01X506490D01*
G02X502773Y124527I0J3717D01*
G01Y128700D01*
G02X504248Y130500I1836J0D01*
G01X535962Y79252D02*
Y80707D01*
X536049Y81668D01*
X536104Y81723D01*
G02X536151Y82117I1666J1D01*
G02X536152Y82124I1650J-232D01*
G02X536158Y82151I1630J-348D01*
G02X536165Y82175I1603J-455D01*
G02X536167Y82179I1467J-731D01*
G02X536544Y82851I1602J-457D01*
G02X536647Y83018I3649J-2135D01*
G02X537200Y83699I3540J-2310D01*
G01X538283Y84784D01*
X540168Y87562D01*
G02X542045Y88984I3038J-2060D01*
G01X546676Y90526D01*
G03X548298Y91527I-1307J3933D01*
G01X550240Y93469D01*
G03X552052Y97120I-4512J4515D01*
G01X552110Y97179D01*
Y105865D01*
G03X550958Y108655I-3952J1D01*
G01X535773Y123909D01*
G02X535300Y125054I1149J1145D01*
G01Y128400D01*
G02X536450Y130310I2161J0D01*
G01X535962Y94213D02*
Y96357D01*
G02X536042Y97018I2748J3D01*
G02X536065Y97107I2672J-643D01*
G02X536208Y97496I2644J-751D01*
G02X536767Y98300I2500J-1142D01*
G03X537128Y98927I-2319J1753D01*
G03X537262Y99327I-2682J1121D01*
G03X537354Y100051I-2815J726D01*
G01Y103000D01*
G03X536767Y105567I-5899J2D01*
G03X535629Y107169I-5298J-2558D01*
G01X518933Y123865D01*
G02X518300Y125395I1530J1529D01*
G01Y128400D01*
G02X519450Y130310I2161J0D01*
G01X532950D02*
G02X534100Y128400I-1011J-1910D01*
G01Y125054D01*
G03X534922Y123062I2823J-1D01*
G01X550107Y107808D01*
G02X550909Y105865I-1950J-1942D01*
G01X550910Y105866D01*
Y97982D01*
X550909Y97983D01*
G02X550861Y97282I-5182J3D01*
G02X549391Y94318I-5135J700D01*
G01X547449Y92377D01*
G02X546297Y91665I-2082J2080D01*
G01X541665Y90123D01*
G03X539175Y88236I1542J-4620D01*
G01X537353Y85552D01*
X536351Y84548D01*
G03X535640Y83672I3836J-3840D01*
G03X535583Y83582I4557J-2949D01*
G03X535377Y83330I2362J-2141D01*
G02X534929Y82891I-1573J1157D01*
G02X534916Y82884I-949J1746D01*
G02X534381Y82690I-938J1751D01*
G02X534007Y82703I-7J5184D01*
G02X533072Y83323I0J1015D01*
G02X533010Y83720I1252J399D01*
G01Y84764D01*
G01X515950Y130310D02*
G02X517100Y128400I-1011J-1910D01*
G01Y125395D01*
G03X518084Y123016I3364J-2D01*
G01X534778Y106322D01*
G02X535686Y105044I-3322J-3322D01*
G02X536154Y103000I-4230J-2044D01*
G01Y100052D01*
G02X536100Y99626I-1707J0D01*
G01X536099Y99624D01*
G02X536021Y99391I-1653J424D01*
G02X535847Y99077I-1571J665D01*
G03X535239Y98240I2863J-2719D01*
G01X535033Y98033D01*
G02X533880Y97556I-1152J1153D01*
G02X533011Y98672I283J1117D01*
G01X533010Y98673D01*
Y99725D01*
G01X536450Y133810D02*
X535847Y134412D01*
G02X535300Y135734I1322J1321D01*
G01Y139714D01*
G02X536032Y141482I2500J0D01*
G01X537497Y142947D01*
G02X538953Y143550I1456J-1456D01*
G01X541787D01*
G03X544935Y144854I0J4452D01*
G01X546780Y146699D01*
G03X547603Y148686I-1987J1987D01*
G01Y150940D01*
G02X548700Y152200I1272J0D01*
G01X519300Y138871D02*
G03X518300Y137871I0J-1000D01*
G01Y135590D01*
G03X518745Y134514I1521J-1D01*
G01X519450Y133810D01*
G01X527950D02*
G02X526800Y135400I524J1590D01*
G02X527057Y136019I876J-1D01*
G01X528423Y137385D01*
G03X529175Y139101I-1822J1821D01*
G01X529191Y139500D01*
G02X530177Y140708I1297J-52D01*
G01X532950Y133810D02*
X533553Y134412D01*
G03X534100Y135734I-1322J1321D01*
G01Y139715D01*
G02X535184Y142332I3700J0D01*
G01X536648Y143796D01*
G02X538953Y144750I2304J-2306D01*
G01X541787D01*
G03X544086Y145703I-1J3251D01*
G01X545931Y147548D01*
G03X546403Y148686I-1138J1139D01*
G01Y150940D01*
G03X545500Y152200I-1331J0D01*
G01X516100Y138871D02*
G02X517100Y137871I0J-1000D01*
G01Y135590D01*
G02X516655Y134514I-1521J-1D01*
G01X515950Y133810D01*
G01X524450D02*
G03X525600Y135400I-524J1590D01*
G02X526208Y136868I2076J0D01*
G01X527574Y138234D01*
G03X527977Y139207I-973J973D01*
G01Y139708D01*
G03X526977Y140708I-1000J0D01*
G01X544821Y94213D02*
Y96875D01*
G02X544847Y97146I1403J2D01*
G02X544851Y97165I1375J-280D01*
G02X544876Y97266I1374J-286D01*
G02X544977Y97518I1347J-394D01*
G02X545232Y97867I1247J-643D01*
G03X545810Y98852I-1600J1601D01*
G01X545867Y99055D01*
G03X545983Y99894I-2962J837D01*
G01Y101799D01*
G03X544853Y104526I-3858J-1D01*
G01X527345Y122032D01*
G02X526800Y123349I1317J1316D01*
G01Y128400D01*
G02X527950Y130310I2161J0D01*
G01X524450D02*
G02X525600Y128400I-1011J-1910D01*
G01Y123349D01*
G03X526496Y121183I3062J-2D01*
G01X544004Y103677D01*
G02X544783Y101798I-1879J-1880D01*
G01Y99893D01*
X544782D01*
G02X544712Y99381I-1878J-4D01*
G01X544711D01*
X544655Y99178D01*
G02X544383Y98716I-1022J291D01*
G03X543910Y98070I1839J-1843D01*
G02X542211Y98041I-857J444D01*
G02X541868Y99264I2005J1222D01*
G01Y99725D01*
G01X518686Y168200D02*
Y168050D01*
G03X520236Y166500I1550J0D01*
G01X520774D01*
G02X522136Y165936I0J-1927D01*
G02X522700Y164574I-1363J-1362D01*
G01Y152875D01*
X522704D01*
Y150691D01*
G02X521658Y148166I-3572J1D01*
G01X521197Y147705D01*
G02X517559Y146199I-3637J3639D01*
G01X507487D01*
G03X505886Y145536I0J-2264D01*
G01X503301Y142951D01*
G03X502905Y141995I956J-956D01*
G01Y136515D01*
G03X504248Y134000I3026J0D01*
G01X570411Y49331D02*
X570131Y49611D01*
G03X568430Y50638I-2931J-2932D01*
G03X567200Y50825I-1231J-3958D01*
G01X566033D01*
G02X565446Y50872I0J3688D01*
G02X562671Y52288I809J5012D01*
G01X562132Y52827D01*
G02X561400Y54596I1770J1768D01*
G01Y111209D01*
G03X561093Y111949I-1045J0D01*
G01X556112Y116930D01*
G02X555602Y118160I1230J1231D01*
G01Y131801D01*
G03X554230Y133550I-1801J0D01*
G01X558263Y133470D02*
G03X556802Y132009I0J-1461D01*
G01Y118161D01*
G03X556961Y117779I540J0D01*
G01X561942Y112798D01*
G02X562600Y111210I-1588J-1588D01*
G01Y54596D01*
G03X562981Y53676I1301J0D01*
G01X563519Y53138D01*
G03X565637Y52057I2737J2746D01*
G03X566036Y52025I399J2469D01*
G01X567891D01*
G03Y54843I0J1409D01*
G01X567458D01*
G01Y99725D02*
Y98920D01*
G03X567930Y97780I1612J0D01*
G03X568600Y97600I670J1155D01*
G03X569115Y97814I-1J729D01*
G01X569720Y98418D01*
G03X569860Y98575I-1281J1283D01*
G03X570251Y99699I-1422J1125D01*
G01Y101741D01*
G03X569519Y103509I-2500J0D01*
G01X568179Y104849D01*
G02X567095Y107466I2616J2617D01*
G01Y128300D01*
G03X565690Y129980I-1707J0D01*
G01X570411Y94213D02*
Y96704D01*
G02X570463Y97139I1816J3D01*
G02X570802Y97830I1763J-436D01*
G03X571451Y99700I-2365J1868D01*
G01Y101742D01*
G03X570367Y104359I-3700J0D01*
G01X569027Y105699D01*
G02X568295Y107467I1768J1768D01*
G01Y128342D01*
G02X569700Y129980I1657J0D01*
G01X544821Y79252D02*
Y81314D01*
G02X544932Y82107I2865J3D01*
G02X545192Y82725I2753J-795D01*
G02X545660Y83340I2493J-1412D01*
G01X547411Y85091D01*
G02X548288Y85633I1584J-1583D01*
G01X551171Y86591D01*
X552962Y87390D01*
G03X554812Y88664I-2534J5659D01*
G01X555385Y89237D01*
G03X557200Y93621I-4385J4383D01*
G01Y107360D01*
G03X555736Y110894I-5000J-1D01*
G01X545264Y121366D01*
G02X543800Y124901I3536J3535D01*
G01Y128400D01*
G02X544950Y130310I2161J0D01*
G01X541868Y84764D02*
Y83977D01*
G03X542276Y82992I1393J0D01*
G01X542403Y82865D01*
G03X543695I646J646D01*
G01X544147Y83317D01*
G02X544811Y84189I3537J-2005D01*
G01X546562Y85940D01*
G02X547909Y86772I2433J-2432D01*
G01X550736Y87711D01*
X550743Y87715D01*
X552471Y88486D01*
G03X553963Y89513I-2042J4564D01*
G01X554536Y90086D01*
G03X556000Y93621I-3536J3535D01*
G01Y107359D01*
G03X554887Y110045I-3800J-1D01*
G01X544415Y120517D01*
G02X542600Y124901I4385J4383D01*
G01Y128400D01*
G03X541450Y130310I-2161J0D01*
G01X544950Y133810D02*
X544219Y134540D01*
G02X543800Y135553I1013J1012D01*
G01Y136544D01*
G02X544800Y137769I1250J0D01*
G01X541450Y133810D02*
X542442Y134801D01*
G03X542600Y135182I-380J381D01*
G01Y136769D01*
G03X541600Y137769I-1000J0D01*
G01X561449Y834551D02*
Y834549D01*
X560256Y833356D01*
G03X560025Y832800I556J-557D01*
G01Y831748D01*
G03X560323Y831027I1019J-1D01*
G01X561050Y830301D01*
G01X548851Y834551D02*
X547657Y833356D01*
G03X547426Y832800I556J-557D01*
G01Y831826D01*
G03X547780Y830973I1207J1D01*
G01X548451Y830301D01*
G01X557449Y834551D02*
X557450D01*
X558559Y833442D01*
G02X558825Y832800I-642J-642D01*
G01Y831700D01*
G02X558525Y830976I-1024J0D01*
G01X557850Y830301D01*
G01X544851Y834551D02*
X545960Y833442D01*
G02X546226Y832800I-642J-642D01*
G01Y832100D01*
G02X545643Y830694I-1989J1D01*
G01X545251Y830301D01*
G01X561024Y887970D02*
Y885152D01*
X561025Y885151D01*
G02X560356Y883152I-3325J1D01*
G03X560051Y882416I736J-736D01*
G01Y841426D01*
G03X561449Y838051I4773J0D01*
G01X548426Y887970D02*
Y885151D01*
G02X547757Y883152I-3325J1D01*
G03X547452Y882416I736J-736D01*
G01Y841428D01*
G03X548851Y838051I4776J0D01*
G01X557874Y887970D02*
Y885153D01*
X557876Y885151D01*
G03X558538Y883160I3325J0D01*
G02X558850Y882407I-753J-753D01*
G01Y841431D01*
G02X557451Y838052I-4778J-1D01*
G01X557449Y838051D01*
G01X545276Y887970D02*
Y885152D01*
X545277Y885151D01*
G03X545939Y883160I3325J0D01*
G02X546251Y882407I-753J-753D01*
G01Y841431D01*
G02X544851Y838051I-4780J0D01*
G01X596500Y130250D02*
G03X595350Y128600I609J-1650D01*
G01Y96634D01*
G02X594266Y94017I-3700J0D01*
G01X591663Y91414D01*
G02X588203Y89981I-3460J3461D01*
G01X587594D01*
X586531Y89989D01*
X585465Y89997D01*
X583524Y88676D01*
X582504Y86731D01*
X581480Y84779D01*
X581150Y84450D01*
X580500Y83800D01*
G03X579460Y82082I2972J-2973D01*
G03X579431Y81985I4012J-1252D01*
G03X579423Y81956I4048J-1132D01*
G03X579419Y81941I4059J-1090D01*
G03X579395Y81849I4055J-1107D01*
G03X579269Y80828I4077J-1021D01*
G01Y79252D01*
G01Y94213D02*
G02X579674Y97935I17305J0D01*
G01X580470Y99145D01*
G03X581020Y100501I-3130J2059D01*
G01X581128Y101067D01*
G03X581160Y101405I-1769J338D01*
G01Y119809D01*
G03X579977Y122664I-4041J-2D01*
G01X576580Y126061D01*
Y128500D01*
G02X577730Y130230I1876J0D01*
G01X588000Y130250D02*
G03X586850Y128600I609J-1650D01*
G01Y106586D01*
G03X587232Y105667I1300J2D01*
G01X588717Y104181D01*
G02X589800Y101564I-2618J-2616D01*
G01Y100734D01*
G02X588717Y98117I-3701J-1D01*
G03X588171Y97111I1422J-1423D01*
G03X588167Y97097I1929J-559D01*
G03X588163Y97074I1979J-356D01*
G03X588128Y96695I1977J-374D01*
G01Y94213D01*
G01X604300Y130150D02*
G03X603150Y128500I609J-1650D01*
G01Y97929D01*
G02X602066Y95312I-3700J0D01*
G01X592418Y85664D01*
G02X591724Y85111I-2791J2791D01*
G02X590712Y84726I-1469J2338D01*
G01X590682Y84722D01*
G03X590294Y84610I303J-1777D01*
G01X590289Y84608D01*
X590281Y84605D01*
X590263Y84597D01*
G03X590243Y84589I528J-1350D01*
G03X589775Y84276I556J-1338D01*
G01X589500Y84000D01*
X589150Y83650D01*
G03X588234Y82036I2467J-2467D01*
G03X588128Y81183I3383J-853D01*
G01Y79252D01*
G01X576317Y84764D02*
G03X578151Y83149I968J-749D01*
G01X580501Y85499D01*
X582600Y89500D01*
X585100Y91200D01*
X587599Y91181D01*
X588202D01*
G03X590814Y92263I0J3694D01*
G01X593418Y94867D01*
G03X594150Y96635I-1768J1768D01*
G01Y128600D01*
G03X593000Y130250I-1759J0D01*
G01X574300Y130230D02*
G02X575380Y128500I-846J-1730D01*
G01Y125563D01*
X579128Y121815D01*
G02X579960Y119808I-2009J-2009D01*
G01Y101405D01*
G02X579949Y101292I-601J1D01*
G01X579841Y100726D01*
G02X579467Y99805I-2501J479D01*
G01X578374Y98144D01*
G02X577122Y97695I-925J609D01*
G01X576676Y97988D01*
G02X576317Y99725I688J1048D01*
G01X585175D02*
Y98848D01*
G03X585674Y97643I1704J0D01*
G03X586100Y97550I427J933D01*
G03X586701Y97799I0J850D01*
G01X587868Y98966D01*
G03X588600Y100734I-1769J1768D01*
G01Y101564D01*
G03X587868Y103332I-2501J0D01*
G01X586382Y104818D01*
G02X585650Y106586I1769J1768D01*
G01Y128600D01*
G03X584500Y130250I-1759J0D01*
G01X600800Y130150D02*
G02X601950Y128500I-609J-1650D01*
G01Y97930D01*
G02X601218Y96162I-2500J0D01*
G01X591569Y86513D01*
G02X591086Y86128I-1943J1942D01*
G02X590517Y85911I-830J1322D01*
G01X590486Y85906D01*
G03X589835Y85719I498J-2961D01*
G01X589783Y85698D01*
G03X588925Y85125I1015J-2448D01*
G01X588650Y84848D01*
X586801Y82999D01*
X586687Y82884D01*
G02X586000Y82600I-686J687D01*
G02X585523Y82797I-1J674D01*
G01X585314Y83007D01*
G02X585175Y83626I1312J620D01*
G01Y84764D01*
G01X596500Y133750D02*
G02X595350Y136762I3369J3012D01*
G01Y140268D01*
G02X595825Y141415I1622J0D01*
G03X596300Y142562I-1147J1147D01*
G01Y147700D01*
G02X597350Y149950I2936J0D01*
G01X577730Y133730D02*
X577053Y134407D01*
G02X576650Y135380I973J973D01*
G01Y136176D01*
G02X577077Y137207I1458J0D01*
G01X577650Y137780D01*
G01X588000Y133750D02*
X587274Y134475D01*
G02X586850Y135500I1025J1024D01*
G01Y136196D01*
G02X587277Y137227I1458J0D01*
G01X587850Y137800D01*
G01X604300Y133650D02*
G02X603320Y135460I1181J1810D01*
G01Y136140D01*
G02X604450Y137780I1755J0D01*
G01X593000Y133750D02*
G03X594150Y136762I-3369J3012D01*
G01Y140268D01*
G02X594976Y142264I2823J1D01*
G03X595100Y142562I-298J299D01*
G01Y148000D01*
G03X594150Y149950I-2476J0D01*
G01X574300Y133730D02*
X575096Y134527D01*
G03X575450Y135380I-853J854D01*
G01Y136176D01*
G03X575023Y137207I-1458J0D01*
G01X574450Y137780D01*
G01X584500Y133750D02*
X585296Y134547D01*
G03X585650Y135400I-853J854D01*
G01Y136196D01*
G03X585223Y137227I-1458J0D01*
G01X584650Y137800D01*
G01X600800Y133650D02*
G03X602120Y135460I-581J1810D01*
G01Y136140D01*
G03X601250Y137780I-1981J0D01*
G01X599245Y834551D02*
X598051Y833356D01*
G03X597820Y832800I556J-557D01*
G01Y831799D01*
G03X598154Y830991I1142J-1D01*
G01X598845Y830301D01*
G01X586646Y834551D02*
X585452Y833356D01*
G03X585221Y832800I556J-557D01*
G01Y831822D01*
G03X585572Y830976I1197J1D01*
G01X586246Y830301D01*
G01X574048Y834551D02*
X572854Y833356D01*
G03X572623Y832800I556J-557D01*
G01Y831924D01*
G03X573046Y830903I1444J0D01*
G01X573648Y830301D01*
G01X595245Y834551D02*
X596354Y833442D01*
G02X596620Y832800I-642J-642D01*
G01Y831800D01*
G02X596249Y830906I-1265J1D01*
G01X595645Y830301D01*
G01X582646Y834551D02*
X583755Y833442D01*
G02X584021Y832800I-642J-642D01*
G01Y831821D01*
G02X583636Y830890I-1316J-1D01*
G01X583046Y830301D01*
G01X570048Y834551D02*
X571157Y833442D01*
G02X571423Y832800I-642J-642D01*
G01Y831923D01*
G02X570966Y830818I-1562J-1D01*
G01X570448Y830301D01*
G01X598819Y887970D02*
Y885152D01*
X598820Y885151D01*
G02X598151Y883152I-3325J1D01*
G03X597846Y882416I736J-736D01*
G01Y841428D01*
G03X599245Y838051I4776J0D01*
G01X586221Y887970D02*
Y885151D01*
G02X585552Y883152I-3325J1D01*
G03X585247Y882416I736J-736D01*
G01Y841428D01*
G03X586646Y838051I4776J0D01*
G01X573623Y887970D02*
Y885151D01*
G02X572954Y883152I-3325J1D01*
G03X572649Y882416I736J-736D01*
G01Y841428D01*
G03X574048Y838051I4776J0D01*
G01X595670Y887970D02*
Y885152D01*
X595671Y885151D01*
G03X596333Y883160I3325J0D01*
G02X596645Y882407I-753J-753D01*
G01Y841431D01*
G02X595245Y838051I-4780J0D01*
G01X583071Y887970D02*
Y885152D01*
X583072Y885151D01*
G03X583734Y883160I3325J0D01*
G02X584046Y882407I-753J-753D01*
G01Y841431D01*
G02X582646Y838051I-4780J0D01*
G01X570473Y887970D02*
Y885152D01*
X570474Y885151D01*
G03X571136Y883160I3325J0D01*
G02X571448Y882407I-753J-753D01*
G01Y841431D01*
G02X570048Y838051I-4780J0D01*
G01X613709Y129831D02*
X615017Y128523D01*
Y118700D01*
G02X614858Y118318I-540J0D01*
G01X613002Y116462D01*
G03X612001Y114044I2418J-2417D01*
G01Y106817D01*
G03X612230Y105587I3416J0D01*
G01X612256Y105521D01*
G03X612951Y104452I2874J1108D01*
G01X613451Y103952D01*
X613461Y103941D01*
G02X613985Y103097I-1541J-1542D01*
G02X614219Y101675I-4201J-1422D01*
G01Y100577D01*
G02X613773Y99286I-2091J0D01*
G02X613651Y99149I-1204J949D01*
G01X612460Y97958D01*
G02X611902Y97727I-558J558D01*
G01X611559D01*
G02X611184Y97871I354J1481D01*
G02X610766Y98880I1009J1009D01*
G01Y99725D01*
G01X617711Y129831D02*
X616217Y128337D01*
Y118699D01*
G02X615707Y117469I-1740J1D01*
G01X613851Y115613D01*
G03X613201Y114044I1569J-1569D01*
G01Y106818D01*
G03X613350Y106020I2216J1D01*
G03X613850Y105251I2068J797D01*
G01X614308Y104793D01*
G02X614971Y103855I-2395J-2396D01*
G02X615122Y103481I-3053J-1450D01*
G02X615419Y101675I-5338J-1805D01*
G01Y100578D01*
G02X614717Y98545I-3291J-1D01*
G01Y98544D01*
G03X613718Y96132I2412J-2412D01*
G01Y94213D01*
G01X622577Y79252D02*
Y80777D01*
G02X622713Y81855I4346J-1D01*
G02X622750Y81993I4216J-1056D01*
G02X622845Y82279I4170J-1226D01*
G02X623850Y83850I4078J-1502D01*
G01X624717Y84717D01*
X626719Y88285D01*
X628929Y89900D01*
X633164D01*
G03X635781Y90983I1J3701D01*
G01X637617Y92819D01*
G03X638700Y95434I-2618J2616D01*
G01Y98383D01*
G02X639207Y99607I1731J0D01*
G01X643766Y104166D01*
G03X644850Y106783I-2616J2617D01*
G01Y128600D01*
G02X646000Y130250I1759J0D01*
G01X622577Y94213D02*
Y96076D01*
G02X623567Y98467I3383J0D01*
G01X623568Y98468D01*
G03X624300Y100236I-1769J1768D01*
G01Y117763D01*
G02X624503Y118253I693J0D01*
G01X626017Y119767D01*
G03X626526Y120997I-1230J1229D01*
G01Y128600D01*
G02X627676Y130250I1759J0D01*
G01X638000D02*
G03X636850Y128600I609J-1650D01*
G01Y115113D01*
G02X635675Y112275I-4010J-2D01*
G01X631008Y107608D01*
G03X630850Y107227I380J-381D01*
G01Y106086D01*
G03X631231Y105167I1301J1D01*
G01X632117Y104281D01*
G02X633200Y101664I-2618J-2616D01*
G01Y100734D01*
G02X632117Y98117I-3701J-1D01*
G03X631435Y96471I1646J-1646D01*
G01Y94213D01*
G01Y79252D02*
G02X631000Y80302I1050J1050D01*
G01Y81000D01*
G02X631778Y82878I2656J0D01*
G01X632750Y83850D01*
G02X633357Y84281I1570J-1568D01*
G02X634319Y84500I961J-2000D01*
G01X635300D01*
G03X636503Y84742I2J3101D01*
G03X637490Y85405I-1196J2846D01*
G01Y85404D01*
X642584Y90498D01*
X660926Y116717D01*
X670981Y123758D01*
G02X672288Y124299I1873J-2677D01*
G01X684242Y126406D01*
G02X686071Y126405I912J-5161D01*
G01X689820Y125737D01*
G02X691540Y125023I-756J-4251D01*
G01X704079Y116240D01*
G03X705668Y115582I2278J3252D01*
G01X708121Y115150D01*
X711500D01*
G02X713250Y114000I0J-1907D01*
G01X619624Y84764D02*
Y83590D01*
G03X621227Y82926I939J0D01*
G01X623751Y85449D01*
X625800Y89100D01*
X628537Y91100D01*
X633165D01*
G03X634932Y91833I-2J2501D01*
G01Y91832D01*
X636768Y93668D01*
G03X637500Y95435I-1769J1768D01*
G01Y98383D01*
G02X638358Y100456I2931J1D01*
G01X642917Y105015D01*
G03X643649Y106783I-1767J1767D01*
G01X643650Y106782D01*
Y128600D01*
G03X642500Y130250I-1759J0D01*
G01X619624Y99725D02*
Y98708D01*
G03X620017Y97759I1342J0D01*
G03X620600Y97600I583J990D01*
G03X621287Y97884I1J971D01*
G01X622718Y99317D01*
Y99316D01*
X622719Y99317D01*
G03X623100Y100236I-920J920D01*
G01Y117763D01*
G02X623654Y119102I1893J1D01*
G01X625168Y120616D01*
G03X625325Y120997I-381J380D01*
G01X625326Y120996D01*
Y128600D01*
G03X624176Y130250I-1759J0D01*
G01X628482Y99725D02*
Y98679D01*
G03X628844Y97805I1236J0D01*
G03X629600Y97600I755J1287D01*
G03X630115Y97814I-1J729D01*
G01X631268Y98966D01*
G03X632000Y100734I-1769J1768D01*
G01Y101664D01*
G03X631268Y103432I-2501J0D01*
G01X630382Y104318D01*
G02X629650Y106085I1769J1768D01*
G01Y107227D01*
G02X630159Y108457I1739J1D01*
G01X634826Y113124D01*
G03X635649Y115113I-1987J1987D01*
G01X635650Y115112D01*
Y128600D01*
G03X634500Y130250I-1759J0D01*
G01X713250Y117500D02*
G02X711500Y116350I-1750J757D01*
G01X708226D01*
X705876Y116764D01*
G02X704768Y117224I483J2727D01*
G01X692229Y126007D01*
G03X690031Y126919I-3164J-4521D01*
G01X686281Y127587D01*
G03X684033Y127588I-1127J-6342D01*
G01X672080Y125481D01*
G03X670292Y124742I772J-4400D01*
G01X660063Y117579D01*
X641660Y91273D01*
X636641Y86254D01*
G02X635300Y85700I-1341J1346D01*
G01X634318D01*
G03X632837Y85363I-1J-3419D01*
G01X632776Y85334D01*
G03X631951Y84749I1303J-2712D01*
G01X630887Y83684D01*
G02X629423Y83823I-648J955D01*
G01X628482Y84764D01*
G01X627676Y133750D02*
G02X626696Y135560I1181J1810D01*
G01Y136240D01*
G02X627826Y137880I1755J0D01*
G01X638000Y133750D02*
G02X637020Y135560I1181J1810D01*
G01Y136240D01*
G02X638150Y137880I1755J0D01*
G01X624176Y133750D02*
G03X625496Y135560I-581J1810D01*
G01Y136240D01*
G03X624626Y137880I-1981J0D01*
G01X634500Y133750D02*
G03X635820Y135560I-581J1810D01*
G01Y136240D01*
G03X634950Y137880I-1981J0D01*
G01X636950Y149650D02*
G02X638090Y147110I-2260J-2540D01*
G03X639714Y143188I5546J-1D01*
G01X642945Y139957D01*
G02X643650Y138256I-1702J-1702D01*
G01Y135600D01*
G02X643155Y134405I-1690J0D01*
G01X642500Y133750D01*
G01X635953Y346807D02*
Y345557D01*
G02X635738Y345038I-734J0D01*
G03X635523Y344534I519J-519D01*
G01Y343175D01*
X637892Y340806D01*
G02X638599Y339099I-1707J-1707D01*
G03X638847Y338502I846J1D01*
G01X640000Y337350D01*
G01X636000Y333850D02*
X636658Y333193D01*
G02X637400Y331400I-1793J-1792D01*
G01Y328852D01*
X641600Y324652D01*
Y323299D01*
G02X641070Y322019I-1811J0D01*
G01X640550Y321500D01*
G01X633984Y346807D02*
Y345379D01*
G03X634154Y344969I579J0D01*
G02X634323Y344561I-408J-408D01*
G01Y342677D01*
X637000Y340000D01*
X637046Y339953D01*
G02X637400Y339100I-853J-854D01*
G02X636826Y338175I-2262J763D01*
G01X636000Y337350D01*
G01X636300Y375850D02*
X637245Y374905D01*
G02Y373144I-880J-881D01*
G01X635000Y370899D01*
G03X634400Y369450I1449J-1449D01*
G01Y368494D01*
G02X634192Y367992I-710J0D01*
G03X633984Y367490I502J-502D01*
G01Y366393D01*
G01X635953D02*
Y367698D01*
G03X635778Y368123I-604J0D01*
G01X635777Y368124D01*
G02X635600Y368550I425J426D01*
G01Y369426D01*
G02X635865Y370066I905J0D01*
G01X637742Y371943D01*
G03X640500Y375850I-9953J9953D01*
G01X636300Y379350D02*
Y383400D01*
X637000Y384100D01*
G01X637040Y834551D02*
X635846Y833356D01*
G03X635615Y832800I556J-557D01*
G01Y831800D01*
G03X635950Y830991I1144J0D01*
G01X636640Y830301D01*
G01X624442Y834551D02*
X623248Y833356D01*
G03X623017Y832800I556J-557D01*
G01Y831700D01*
G03X623281Y831061I903J-1D01*
G01X624042Y830301D01*
G01X611843Y834551D02*
X610649Y833356D01*
G03X610418Y832800I556J-557D01*
G01Y831700D01*
G03X610682Y831061I903J-1D01*
G01X611443Y830301D01*
G01X633040Y834551D02*
X634149Y833442D01*
G02X634415Y832800I-642J-642D01*
G01Y831800D01*
G02X634044Y830906I-1265J1D01*
G01X633440Y830301D01*
G01X620442Y834551D02*
X621551Y833442D01*
G02X621817Y832800I-642J-642D01*
G01Y831700D01*
G02X621517Y830976I-1024J0D01*
G01X620842Y830301D01*
G01X607843Y834551D02*
X608952Y833442D01*
G02X609218Y832800I-642J-642D01*
G01Y831800D01*
G02X608847Y830906I-1265J1D01*
G01X608243Y830301D01*
G01X636615Y887970D02*
Y885151D01*
G02X635946Y883152I-3325J1D01*
G03X635641Y882416I736J-736D01*
G01Y841428D01*
G03X637040Y838051I4776J0D01*
G01X624016Y887970D02*
Y885152D01*
X624017Y885151D01*
G02X623348Y883152I-3325J1D01*
G03X623043Y882416I736J-736D01*
G01Y841428D01*
G03X624442Y838051I4776J0D01*
G01X611418Y887970D02*
Y885151D01*
G02X610749Y883152I-3325J1D01*
G03X610444Y882416I736J-736D01*
G01Y841428D01*
G03X611843Y838051I4776J0D01*
G01X633465Y887970D02*
Y885152D01*
X633466Y885151D01*
G03X634128Y883160I3325J0D01*
G02X634440Y882407I-753J-753D01*
G01Y841431D01*
G02X633040Y838051I-4780J0D01*
G01X620867Y887970D02*
Y885152D01*
X620868Y885151D01*
G03X621530Y883160I3325J0D01*
G02X621842Y882407I-753J-753D01*
G01Y841431D01*
G02X620442Y838051I-4780J0D01*
G01X608268Y887970D02*
Y885152D01*
X608269Y885151D01*
G03X608931Y883160I3325J0D01*
G02X609243Y882407I-753J-753D01*
G01Y841431D01*
G02X607843Y838051I-4780J0D01*
G01X713360Y51796D02*
X711786Y53370D01*
X699898D01*
X699021Y53369D01*
G02X696686Y54336I0J3301D01*
G01X695420Y55602D01*
G03X691466Y57240I-3954J-3953D01*
G01X675417D01*
X665646Y58962D01*
G03X665213Y59000I-434J-2462D01*
G01X661232D01*
G03X660200Y57968I0J-1032D01*
G01Y57430D01*
G02X659049Y54651I-3930J0D01*
G01X658099Y53701D01*
G03X657025Y51108I2593J-2593D01*
G01Y49331D01*
G01X713360Y55860D02*
X712070Y54570D01*
X699020D01*
G02X697535Y55185I0J2101D01*
G01X696269Y56451D01*
G03X691466Y58440I-4802J-4803D01*
G01X675522D01*
X665854Y60144D01*
G03X665211Y60200I-641J-3644D01*
G01X661232D01*
G03X659000Y57968I0J-2232D01*
G01Y57429D01*
X658999Y57430D01*
G02X658200Y55500I-2729J0D01*
G01X657250Y54550D01*
Y54551D01*
X657153Y54454D01*
G02X656300Y54100I-854J853D01*
G01X655600D01*
G02X654261Y54654I-1J1893D01*
G01X654073Y54843D01*
G01X735350Y114020D02*
Y113536D01*
G02X734145Y112331I-1205J0D01*
G01X731121D01*
G03X728938Y111427I0J-3088D01*
G01X727890Y110379D01*
G02X727218Y110100I-673J672D01*
G01X712945D01*
G02X710864Y110282I0J11990D01*
G01X705100Y111299D01*
G02X703187Y112091I829J4709D01*
G01X691658Y120165D01*
G03X689692Y120978I-2816J-4027D01*
G01X684026Y121977D01*
G03X682138I-944J-5357D01*
G01X675753Y120851D01*
G03X674329Y120261I617J-3503D01*
G01X670935Y117885D01*
G03X669049Y115999I4407J-6293D01*
G01X665566Y111026D01*
G03X664981Y109610I2897J-2026D01*
G01X664814Y108660D01*
G02X664236Y107265I-3429J603D01*
G01X662526Y104823D01*
X661682Y103980D01*
X659511Y102463D01*
X658101Y100399D01*
X657451Y99749D01*
X656856Y99153D01*
G02X656000Y98799I-855J856D01*
G01X655700D01*
G02X654504Y99295I1J1692D01*
G01X654073Y99725D01*
G01X735330Y109410D02*
Y109946D01*
G03X734145Y111131I-1185J0D01*
G01X731121D01*
G03X729787Y110578I1J-1887D01*
G01X728739Y109530D01*
G02X727218Y108900I-1521J1521D01*
G01X712946D01*
G02X710656Y109100I-2J13190D01*
G01X704892Y110117D01*
G02X702498Y111107I1035J5892D01*
G01X690969Y119181D01*
G03X689484Y119796I-2130J-3042D01*
G01X683818Y120795D01*
G03X682346I-736J-4175D01*
G01X675961Y119669D01*
G03X675018Y119278I410J-2320D01*
G01X671624Y116901D01*
G03X670033Y115310I3719J-5310D01*
G01X666550Y110337D01*
G03X666163Y109402I1912J-1339D01*
G01X665996Y108452D01*
G02X665219Y106576I-4611J811D01*
G01X663449Y104049D01*
X662457Y103056D01*
X660379Y101604D01*
X659092Y99722D01*
Y99721D01*
X659029Y99629D01*
X658951Y99550D01*
X658196Y98795D01*
G03X657025Y95893I3011J-2902D01*
G01Y94213D01*
G01X665884Y79252D02*
Y81096D01*
G02X666333Y82843I3619J1D01*
G02X666416Y82986I3171J-1745D01*
G02X666944Y83655I3085J-1892D01*
G01X668220Y84931D01*
X669340Y87763D01*
X670511Y89091D01*
X672460Y89871D01*
X677427Y89265D01*
X703424D01*
G02X705150Y88550I0J-2441D01*
G01X706526Y87174D01*
G03X709000Y86150I2473J2475D01*
G01X710474D01*
G02X713250Y85000I0J-3926D01*
G01Y102000D02*
G03X711100Y103150I-2150J-1435D01*
G01X707700D01*
G02X701861Y104627I0J12280D01*
G01X688135Y114235D01*
G03X686588Y114949I-2754J-3935D01*
G01X684887Y115391D01*
G03X682028Y115504I-1689J-6512D01*
G01X677958Y114785D01*
G03X676973Y114377I427J-2424D01*
G01X675468Y113322D01*
G03X674778Y112632I1614J-2304D01*
G01X671191Y107510D01*
G03X671063Y107200I635J-444D01*
G01X670861Y106053D01*
G02X670352Y104338I-7734J1362D01*
G01X669829Y103111D01*
G02X669030Y101930I-3437J1465D01*
G01X668509Y101410D01*
G03X666882Y99188I6319J-6334D01*
G03X666460Y98242I7934J-4106D01*
G03X666387Y98043I8349J-3176D01*
G03X666330Y97871I8450J-2896D01*
G03X665884Y95084I8486J-2787D01*
G01Y94213D01*
G01X662931Y84764D02*
X663375Y84320D01*
G03X664500Y83854I1125J1125D01*
G01X665000D01*
G03X665759Y84169I-1J1074D01*
G01X665795Y84204D01*
X667195Y85604D01*
X668300Y88400D01*
X669800Y90100D01*
X672300Y91100D01*
X677500Y90465D01*
X703425D01*
G02X705999Y89399I0J-3641D01*
G01X707375Y88023D01*
G03X709000Y87350I1625J1625D01*
G01X710475D01*
G03X713250Y88500I-1J3926D01*
G01X662931Y99725D02*
X663546Y99110D01*
G03X664659Y98649I1113J1113D01*
G03X665506Y99084I-254J1536D01*
G02X665816Y99740I9310J-3998D01*
G02X667661Y102260I9012J-4663D01*
G01X668181Y102780D01*
X668182D01*
G03X668724Y103582I-1791J1795D01*
G01X669247Y104809D01*
G03X669679Y106261I-6118J2611D01*
G01X669881Y107408D01*
G02X670207Y108198I1945J-340D01*
G01X673794Y113321D01*
G02X674779Y114305I3286J-2305D01*
G01X676284Y115360D01*
G02X677749Y115967I2101J-2999D01*
G01X681819Y116686D01*
G02X685189Y116553I1380J-7807D01*
G01X686890Y116111D01*
G02X688824Y115219I-1508J-5812D01*
G01X702491Y105651D01*
G03X707700Y104350I5209J9779D01*
G01X711100D01*
G03X713250Y105500I0J2585D01*
G01X640150Y149650D02*
G03X639290Y147110I3321J-2540D01*
G03X640563Y144037I4346J0D01*
G01X643794Y140806D01*
G02X644850Y138256I-2551J-2550D01*
G01Y135600D01*
G03X645345Y134405I1690J0D01*
G01X646000Y133750D01*
G01X640000Y333850D02*
X639342Y333193D01*
G03X638600Y331400I1793J-1792D01*
G01Y329350D01*
X642800Y325150D01*
Y323300D01*
G03X643401Y321849I2052J0D01*
G01X643750Y321500D01*
G01X642793Y353647D02*
X644108D01*
G02X644526Y353474I0J-591D01*
G03X644945Y353300I419J417D01*
G01X645977D01*
G02X647549Y352649I0J-2224D01*
G01X648599Y351599D01*
X648713Y351484D01*
G03X649400Y351200I686J687D01*
G01X650249D01*
G03X651275Y351625I0J1451D01*
G01X652250Y352600D01*
G01X655750Y367100D02*
X655870Y367220D01*
X660380D01*
X660500Y367100D01*
G01X642793Y361521D02*
X644040D01*
G02X644448Y361352I0J-577D01*
G03X644856Y361183I408J408D01*
G01Y361179D01*
G02X644987Y361183I125J-1931D01*
G01X645336D01*
G03X646443Y361642I0J1565D01*
G01X646442D01*
G03X646900Y362748I-1106J1106D01*
G01Y362811D01*
G02X647600Y364500I2390J-1D01*
G01X647656Y364556D01*
G02X649212Y365200I1555J-1556D01*
G01X649900D01*
G03X650668Y365518I0J1086D01*
G01X652250Y367100D01*
G01X642793Y351679D02*
X644081D01*
G03X644590Y351890I0J719D01*
G02X645098Y352100I508J-509D01*
G01X645976D01*
G02X646700Y351800I0J-1024D01*
G01X647850Y350650D01*
X647863Y350636D01*
G03X649400Y350000I1536J1537D01*
G01X650100D01*
G02X651381Y349470I1J-1811D01*
G01X652250Y348600D01*
G01X655750Y362100D02*
X660300D01*
X660500Y362300D01*
G01X642793Y359553D02*
X643949D01*
G03X644468Y359768I0J734D01*
G02X644987Y359983I519J-519D01*
G01X645335D01*
G03X647292Y360793I2J2765D01*
G03X648100Y362748I-1957J1953D01*
G01Y362810D01*
G02X648449Y363651I1190J-1D01*
G01X648505Y363707D01*
G02X649212Y364000I707J-706D01*
G01X649936D01*
G02X650643Y363707I0J-999D01*
G01X652250Y362100D01*
G01X655750Y352600D02*
X657120Y351230D01*
X659274D01*
X660244Y352200D01*
G01X655750Y348600D02*
X657180Y350030D01*
X659214D01*
X660244Y349000D01*
G01X640500Y379350D02*
Y382600D01*
X642000Y384100D01*
G01X671685Y834551D02*
X670491Y833356D01*
G03X670260Y832800I556J-557D01*
G01Y831846D01*
G02Y831830I-2575J-8D01*
G03X670616Y830969I1217J-1D01*
G01X671285Y830301D01*
G01X659087Y834551D02*
X657893Y833356D01*
G03X657662Y832800I556J-557D01*
G01Y831850D01*
G03X658033Y830956I1265J1D01*
G01X658687Y830301D01*
G01X667685Y834551D02*
X668794Y833442D01*
G02X669060Y832800I-642J-642D01*
G01Y831845D01*
G02X668658Y830873I-1374J-1D01*
G01X668085Y830301D01*
G01X655087Y834551D02*
X656196Y833442D01*
G02X656462Y832800I-642J-642D01*
G01Y831850D01*
G02X656056Y830870I-1386J0D01*
G01X655487Y830301D01*
G01X671260Y887970D02*
Y885151D01*
G02X670591Y883152I-3325J1D01*
G03X670286Y882416I736J-736D01*
G01Y841428D01*
G03X671685Y838051I4776J0D01*
G01X658662Y887970D02*
Y885151D01*
G02X657993Y883152I-3325J1D01*
G03X657688Y882416I736J-736D01*
G01Y841428D01*
G03X659087Y838051I4776J0D01*
G01X668111Y887970D02*
Y885151D01*
G03X668773Y883160I3325J0D01*
G02X669085Y882407I-753J-753D01*
G01Y841431D01*
G02X667685Y838051I-4780J0D01*
G01X655512Y887970D02*
Y885152D01*
X655513Y885151D01*
G03X656175Y883160I3325J0D01*
G02X656487Y882407I-753J-753D01*
G01Y841431D01*
G02X655087Y838051I-4780J0D01*
G01X713250Y93000D02*
G03X711200Y94018I-2050J-1555D01*
G01X685703D01*
G02X683086Y95102I0J3700D01*
G01X679419Y98769D01*
G03X677827Y99468I-1692J-1692D01*
G03X676859Y99307I-100J-2391D01*
G03X676164Y98875I806J-2071D01*
G03X674742Y95442I3433J-3433D01*
G01Y94213D01*
G01Y79252D02*
Y80922D01*
G02X675306Y82981I4036J1D01*
G02X675924Y83776I3471J-2060D01*
G02X676542Y84211I1570J-1574D01*
G02X677496Y84427I956J-2007D01*
G01X677890D01*
Y84426D01*
G02X678659Y84283I0J-2137D01*
G02X679401Y83801I-768J-1994D01*
G01X680079Y83123D01*
G02X680751Y81500I-1624J-1623D01*
G03X681423Y79877I2296J0D01*
G01X681450Y79850D01*
G03X683139Y79150I1689J1688D01*
G01X710474D01*
G02X713250Y78000I0J-3926D01*
G01Y96500D02*
G02X711200Y95218I-2050J998D01*
G01X685704D01*
G02X683936Y95950I0J2500D01*
G01X680266Y99620D01*
G03X677877Y100668I-2538J-2538D01*
G03X676424Y100426I-149J-3591D01*
G03X675350Y99757I1241J-3189D01*
G03X675246Y99657I2320J-2517D01*
G02X673658Y99000I-1588J1590D01*
G01X673539D01*
G02X671789Y99725I0J2475D01*
G01Y84764D02*
X672012Y84539D01*
G03X672391Y84226I1774J1762D01*
G01X672929Y83864D01*
G03X673773I422J1018D01*
G01X674578Y84198D01*
G03X674690Y84257I-243J597D01*
G03X674788Y84338I-380J560D01*
G01X675275Y84825D01*
G02X675775Y85177I1268J-1269D01*
G01X676027Y85297D01*
G02X677497Y85627I1467J-3094D01*
G01X677891D01*
G02X679091Y85404I1J-3336D01*
G02X680250Y84650I-1200J-3113D01*
G01X680928Y83972D01*
G02X681951Y81500I-2473J-2471D01*
G03X682272Y80726I1096J1D01*
G01X682299Y80699D01*
G03X683139Y80350I841J838D01*
G01X710474D01*
G03X713250Y81500I0J3926D01*
G01X696882Y834551D02*
X695688Y833356D01*
G03X695457Y832800I556J-557D01*
G01Y831839D01*
G03X695820Y830964I1238J1D01*
G01X696482Y830301D01*
G01X684284Y834551D02*
X683090Y833356D01*
G03X682859Y832800I556J-557D01*
G01Y831842D01*
G03X683224Y830961I1246J0D01*
G01X683884Y830301D01*
G01X692882Y834551D02*
X693991Y833442D01*
G02X694257Y832800I-642J-642D01*
G01Y831838D01*
G02X693860Y830878I-1357J-1D01*
G01X693282Y830301D01*
G01X680284Y834551D02*
X681393Y833442D01*
G02X681659Y832800I-642J-642D01*
G01Y831842D01*
G02X681259Y830876I-1366J0D01*
G01X680684Y830301D01*
G01X696457Y887970D02*
Y885151D01*
G02X695788Y883152I-3325J1D01*
G03X695483Y882416I736J-736D01*
G01Y841428D01*
G03X696882Y838051I4776J0D01*
G01X683859Y887970D02*
Y885151D01*
G02X683190Y883152I-3325J1D01*
G03X682885Y882416I736J-736D01*
G01Y841428D01*
G03X684284Y838051I4776J0D01*
G01X693308Y887970D02*
Y885151D01*
G03X693970Y883160I3325J0D01*
G02X694282Y882407I-753J-753D01*
G01Y841431D01*
G02X692882Y838051I-4780J0D01*
G01X680709Y887970D02*
Y885152D01*
X680710Y885151D01*
G03X681372Y883160I3325J0D01*
G02X681684Y882407I-753J-753D01*
G01Y841431D01*
G02X680284Y838051I-4780J0D01*
G01X732500Y98421D02*
G03X731455Y99466I-1045J0D01*
G01X729759D01*
G03X729030Y99163I2J-1032D01*
G01X728052Y98186D01*
G03X727841Y97677I508J-509D01*
G01Y92921D01*
G02X726794Y90395I-3573J1D01*
G01X723518Y87119D01*
G02X721302Y86200I-2218J2217D01*
G01X719400D01*
G03X716750Y85000I0J-3526D01*
G01Y102000D02*
X717475Y102726D01*
G02X718500Y103150I1024J-1025D01*
G01X719079D01*
G02X720310Y102640I0J-1741D01*
G01X720800Y102150D01*
G01X716750Y93000D02*
X717475Y93726D01*
G02X718500Y94150I1024J-1025D01*
G01X719179D01*
G02X720239Y93711I0J-1499D01*
G01X720800Y93150D01*
G01Y78150D02*
G03X719380Y79150I-1420J-508D01*
G01X718240D01*
G03X717658Y78908I1J-823D01*
G01X716750Y78000D01*
G01X732500Y101621D02*
G02X731545Y100666I-955J0D01*
G01X729759D01*
G03X728181Y100013I0J-2233D01*
G01X727203Y99035D01*
G03X726641Y97677I1358J-1357D01*
G01Y92922D01*
G02X725945Y91244I-2373J1D01*
G01X722669Y87968D01*
G02X721301Y87400I-1370J1368D01*
G01X719400D01*
G02X716750Y88500I0J3742D01*
G01Y105500D02*
X717547Y104704D01*
G03X718400Y104350I854J853D01*
G01X719079D01*
G03X720310Y104860I0J1741D01*
G01X720800Y105350D01*
G01X716750Y96500D02*
X717038Y96213D01*
G03X717842Y95674I1768J1768D01*
G01X718096Y95568D01*
G03X718501Y95485I415J998D01*
G01X719221D01*
G03X720440Y95990I0J1724D01*
G01X720800Y96350D01*
G01Y81350D02*
G02X719379Y80350I-1421J510D01*
G01X718497D01*
G02X717480Y80771I0J1439D01*
G01X716750Y81500D01*
G01Y114000D02*
X717475Y114726D01*
G02X718500Y115150I1024J-1025D01*
G01X719136D01*
G02X720269Y114680I-1J-1603D01*
G01X720800Y114150D01*
G01X716750Y117500D02*
X717547Y116704D01*
G03X718400Y116350I854J853D01*
G01X719056D01*
G03X720326Y116876I0J1796D01*
G01X720800Y117350D01*
G01X728379Y834551D02*
X727184Y833356D01*
G03X726953Y832800I556J-557D01*
G01Y831829D01*
G03X727309Y830971I1214J1D01*
G01X727978Y830301D01*
G01X736977Y834551D02*
X738086Y833442D01*
G02X738352Y832800I-642J-642D01*
G01Y831826D01*
G02X737963Y830887I-1328J0D01*
G01X737377Y830301D01*
G01X724379Y834551D02*
X724378D01*
X725487Y833442D01*
G02X725753Y832800I-642J-642D01*
G01Y831828D01*
G02X725363Y830885I-1333J-1D01*
G01X724778Y830301D01*
G01X727953Y887970D02*
Y885151D01*
G02X727284Y883152I-3325J1D01*
G03X726979Y882416I736J-736D01*
G01Y841428D01*
G03X728377Y838053I4773J0D01*
G01X728379Y838051D01*
G01X737402Y887970D02*
Y885152D01*
X737403Y885151D01*
G03X738065Y883160I3325J0D01*
G02X738377Y882407I-753J-753D01*
G01Y841431D01*
G02X736977Y838051I-4780J0D01*
G01X724804Y887970D02*
Y885151D01*
G03X725466Y883160I3325J0D01*
G02X725778Y882407I-753J-753D01*
G01Y841428D01*
G02X724379Y838051I-4776J0D01*
G01X766174Y834551D02*
X764980Y833356D01*
G03X764749Y832800I556J-557D01*
G01Y831918D01*
G03X765168Y830908I1429J1D01*
G01X765774Y830301D01*
G01X753576Y834551D02*
X752381Y833356D01*
G03X752150Y832800I556J-557D01*
G01Y831861D01*
G03X752528Y830947I1292J-1D01*
G01X753175Y830301D01*
G01X740977Y834551D02*
X739783Y833356D01*
G03X739552Y832800I556J-557D01*
G01Y831826D01*
G03X739906Y830973I1207J1D01*
G01X740577Y830301D01*
G01X762174Y834551D02*
X763283Y833442D01*
G02X763549Y832800I-642J-642D01*
G01Y831918D01*
G02X763095Y830822I-1550J0D01*
G01X762574Y830301D01*
G01X749576Y834551D02*
Y834550D01*
X750684Y833442D01*
G02X750950Y832800I-642J-642D01*
G01Y831821D01*
G02X750565Y830890I-1316J-1D01*
G01X749975Y830301D01*
G01X765749Y887970D02*
Y885151D01*
G02X765080Y883152I-3325J1D01*
G03X764775Y882416I736J-736D01*
G01Y841428D01*
G03X766174Y838051I4776J0D01*
G01X753150Y887970D02*
Y885151D01*
G02X752481Y883152I-3325J1D01*
G03X752176Y882416I736J-736D01*
G01Y841428D01*
G03X753574Y838053I4773J0D01*
G01X753576Y838051D01*
G01X740552Y887970D02*
Y885151D01*
G02X739883Y883152I-3325J1D01*
G03X739578Y882416I736J-736D01*
G01Y841428D01*
G03X740977Y838051I4776J0D01*
G01X762599Y887970D02*
Y885152D01*
X762600Y885151D01*
G03X763262Y883160I3325J0D01*
G02X763574Y882407I-753J-753D01*
G01Y841431D01*
G02X762174Y838051I-4780J0D01*
G01X750000Y887970D02*
Y885152D01*
X750001Y885151D01*
G03X750663Y883160I3325J0D01*
G02X750975Y882407I-753J-753D01*
G01Y841428D01*
G02X749576Y838051I-4776J0D01*
G01X792760Y180443D02*
G03X794360Y178943I1600J103D01*
G01X797342D01*
X799165Y177760D01*
X800188Y176188D01*
X801236Y172060D01*
X802630Y169912D01*
X803633Y169261D01*
X809978Y167912D01*
X810704Y168383D01*
X812283Y168048D01*
X812754Y167322D01*
X814333Y166986D01*
X855149Y175792D01*
X871300D01*
G01X792760Y176043D02*
G02X794360Y177743I1600J97D01*
G01X796986D01*
X798298Y176892D01*
X799073Y175700D01*
X800121Y171572D01*
X801762Y169044D01*
X803167Y168133D01*
X814335Y165758D01*
X855277Y174592D01*
X871300D01*
G01X778807Y183890D02*
G03X780614Y182272I1807J200D01*
G01X783371D01*
X786819Y178821D01*
X787541Y175431D01*
X791936Y168667D01*
G03X793075Y167528I3247J2108D01*
G01X802436Y161452D01*
X810109Y159820D01*
X812865Y160565D01*
X834110D01*
X835236Y161691D01*
G01Y158240D02*
X834111Y159365D01*
X813025D01*
X810143Y158585D01*
X802187Y160278D01*
Y160277D01*
X801969Y160324D01*
X792422Y166521D01*
G02X790929Y168013I2760J4255D01*
G01X786413Y174963D01*
X785719Y178224D01*
X782873Y181072D01*
X780235D01*
G03X778807Y179644I0J-1428D01*
G01Y179490D01*
G01X880315Y181102D02*
X879537Y180323D01*
G02X879149Y180064I-844J844D01*
G02X879004Y180035I-145J350D01*
G01X871907D01*
X861673Y187200D01*
X856124Y188379D01*
X855652Y189105D01*
X854073Y189441D01*
X853348Y188969D01*
X851769Y189305D01*
X851297Y190030D01*
X849719Y190366D01*
X848993Y189895D01*
X847414Y190230D01*
X812802Y182872D01*
X798260Y185963D01*
X791472Y190367D01*
X790684Y191580D01*
X790450Y192682D01*
Y193900D01*
G02X792000Y195778I2077J-136D01*
G01X787600Y195804D02*
G02X789250Y193945I-223J-1859D01*
G01Y192555D01*
X789556Y191113D01*
X790604Y189499D01*
X797793Y184835D01*
X812802Y181645D01*
X847414Y189003D01*
X856662Y187037D01*
X858530Y186640D01*
X861078Y186099D01*
G02X861275Y186013I-112J-526D01*
G01X871389Y178932D01*
G03X871698Y178835I308J441D01*
G01X878779D01*
G03X884252Y181102I0J7740D01*
G01X803969Y834551D02*
X802775Y833356D01*
G03X802544Y832800I556J-557D01*
G01Y831845D01*
G03X802911Y830959I1253J0D01*
G01X803569Y830301D01*
G01X791370Y834551D02*
X790176Y833356D01*
G03X789945Y832800I556J-557D01*
G01Y831908D01*
G03X790357Y830915I1405J1D01*
G01X790970Y830301D01*
G01X778772Y834551D02*
X777578Y833356D01*
G03X777347Y832800I556J-557D01*
G01Y831829D01*
G03X777703Y830971I1214J1D01*
G01X778372Y830301D01*
G01X799969Y834551D02*
X801078Y833442D01*
G02X801344Y832800I-642J-642D01*
G01Y831806D01*
G02X800969Y830901I-1280J0D01*
G01X800369Y830301D01*
G01X787370Y834551D02*
X788479Y833442D01*
G02X788745Y832800I-642J-642D01*
G01Y831909D01*
G02X788297Y830829I-1528J1D01*
G01X787770Y830301D01*
G01X774772Y834551D02*
X775881Y833442D01*
G02X776147Y832800I-642J-642D01*
G01Y831828D01*
G02X775757Y830885I-1333J-1D01*
G01X775172Y830301D01*
G01X803544Y887970D02*
Y885151D01*
G02X802875Y883152I-3325J1D01*
G03X802570Y882416I736J-736D01*
G01Y841428D01*
G03X803969Y838051I4776J0D01*
G01X790945Y887970D02*
Y885151D01*
G02X790276Y883152I-3325J1D01*
G03X789971Y882416I736J-736D01*
G01Y841428D01*
G03X791370Y838051I4776J0D01*
G01X778347Y887970D02*
Y885151D01*
G02X777678Y883152I-3325J1D01*
G03X777373Y882416I736J-736D01*
G01Y841428D01*
G03X778772Y838051I4776J0D01*
G01X800394Y887970D02*
Y885152D01*
X800395Y885151D01*
G03X801057Y883160I3325J0D01*
G02X801369Y882407I-753J-753D01*
G01Y841431D01*
G02X799969Y838051I-4780J0D01*
G01X787796Y887970D02*
Y885151D01*
G03X788458Y883160I3325J0D01*
G02X788770Y882407I-753J-753D01*
G01Y841431D01*
G02X787370Y838051I-4780J0D01*
G01X775197Y887970D02*
Y885152D01*
X775198Y885151D01*
G03X775860Y883160I3325J0D01*
G02X776172Y882407I-753J-753D01*
G01Y841431D01*
G02X774772Y838051I-4780J0D01*
G01X838736Y161691D02*
X839862Y160565D01*
X844221D01*
X844833Y161177D01*
X846447D01*
X847059Y160565D01*
X848673D01*
X849285Y161177D01*
X850899D01*
X851511Y160565D01*
X853125D01*
X853737Y161177D01*
X855351D01*
X855963Y160565D01*
X860225D01*
G03X863305Y161841I0J4355D01*
G01X871048Y169584D01*
G01X838736Y158240D02*
X839861Y159365D01*
X860225D01*
G03X864154Y160992I1J5556D01*
G01X871897Y168735D01*
G01X816567Y834551D02*
X815373Y833356D01*
G03X815142Y832800I556J-557D01*
G01Y831955D01*
G03X815587Y830881I1519J0D01*
G01X816167Y830301D01*
G01X837764Y834551D02*
X838873Y833442D01*
G02X839139Y832800I-642J-642D01*
G01Y831894D01*
G02X838702Y830839I-1492J0D01*
G01X838164Y830301D01*
G01X812567Y834551D02*
X813676Y833442D01*
G02X813942Y832800I-642J-642D01*
G01Y831901D01*
G02X813500Y830834I-1509J0D01*
G01X812967Y830301D01*
G01X816142Y887970D02*
Y885151D01*
G02X815473Y883152I-3325J1D01*
G03X815168Y882416I736J-736D01*
G01Y841428D01*
G03X816567Y838051I4776J0D01*
G01X838189Y887970D02*
Y885152D01*
X838190Y885151D01*
G03X838852Y883160I3325J0D01*
G02X839164Y882407I-753J-753D01*
G01Y841431D01*
G02X837764Y838051I-4780J0D01*
G01X812993Y887970D02*
Y885153D01*
X812992Y885152D01*
X812993Y885151D01*
G03X813655Y883160I3325J0D01*
G02X813967Y882407I-753J-753D01*
G01Y841431D01*
G02X812567Y838051I-4780J0D01*
G01X854362Y834551D02*
X853168Y833356D01*
G03X852937Y832800I556J-557D01*
G01Y831789D01*
G03X853264Y830998I1118J-1D01*
G01X853962Y830301D01*
G01X841764Y834551D02*
X840570Y833356D01*
G03X840339Y832800I556J-557D01*
G01Y831894D01*
G03X840741Y830925I1371J1D01*
G01X841364Y830301D01*
G01X850362Y834551D02*
X851471Y833442D01*
G02X851737Y832800I-642J-642D01*
G01Y831789D01*
G02X851374Y830914I-1238J1D01*
G01X850762Y830301D01*
G01X853937Y887970D02*
Y885151D01*
G02X853268Y883152I-3325J1D01*
G03X852963Y882416I736J-736D01*
G01Y841428D01*
G03X854362Y838051I4776J0D01*
G01X841339Y887970D02*
Y885151D01*
G02X840670Y883152I-3325J1D01*
G03X840365Y882416I736J-736D01*
G01Y841428D01*
G03X841764Y838051I4776J0D01*
G01X850788Y887970D02*
Y885151D01*
G03X851450Y883160I3325J0D01*
G02X851762Y882407I-753J-753D01*
G01Y841431D01*
G02X850362Y838051I-4780J0D01*
G01X888189Y141732D02*
X886221Y139764D01*
G01X892126Y137795D02*
X890158Y135827D01*
G01X888189Y133858D02*
X886221Y131890D01*
G01X892126Y141732D02*
X890158Y139764D01*
G01X896063Y137795D02*
X894095Y135827D01*
G01X892126Y133858D02*
X890158Y131890D01*
G01X876378Y141732D02*
X874410Y139764D01*
G01X880315Y137795D02*
X878347Y135827D01*
G01X876378Y133858D02*
X874410Y131890D01*
G01X876378Y122047D02*
X874410Y120079D01*
G01X880315Y118110D02*
X878347Y116142D01*
G01X884252Y122047D02*
X882284Y120079D01*
G01X888189Y118110D02*
X886221Y116142D01*
G01X892126Y122047D02*
X890158Y120079D01*
G01X896063Y118110D02*
X894095Y116142D01*
G01X900000Y122047D02*
X898032Y120079D01*
G01X903937Y118110D02*
X901969Y116142D01*
G01X880315Y141732D02*
X878347Y139764D01*
G01X884252Y137795D02*
X882284Y135827D01*
G01X880315Y133858D02*
X878347Y131890D01*
G01X876378Y125984D02*
X874410Y124016D01*
G01X880315Y122047D02*
X878347Y120079D01*
G01X884252Y125984D02*
X882300Y124032D01*
G01X888189Y122047D02*
X886221Y120079D01*
G01X892126Y125984D02*
X890158Y124016D01*
G01X896063Y122047D02*
X894095Y120079D01*
G01X900000Y125984D02*
X898032Y124016D01*
G01X903937Y122047D02*
X901969Y120079D01*
G01X892126Y161417D02*
X890158Y159449D01*
G01X888189Y157480D02*
X886221Y155512D01*
G01X892126Y153543D02*
X890158Y151575D01*
G01X888189Y149606D02*
X886221Y147638D01*
G01X892126Y145669D02*
X890158Y143701D01*
G01X896063Y161417D02*
X894095Y159449D01*
G01X892126Y157480D02*
X890158Y155512D01*
G01X896063Y153543D02*
X894095Y151575D01*
G01X892126Y149606D02*
X890158Y147638D01*
G01X896063Y145669D02*
X894095Y143701D01*
G01X880315Y161417D02*
X878347Y159449D01*
G01X876378Y157480D02*
X874410Y155512D01*
G01X880315Y153543D02*
X878347Y151575D01*
G01X876378Y149606D02*
X874410Y147638D01*
G01X880315Y145669D02*
X878347Y143701D01*
G01X884252Y161417D02*
X882284Y159449D01*
G01X880315Y157480D02*
X878347Y155512D01*
G01X884252Y153543D02*
X882284Y151575D01*
G01X880315Y149606D02*
X878347Y147638D01*
G01X884252Y145669D02*
X882284Y143701D01*
G01X892126Y208661D02*
Y209282D01*
G03X892026Y209724I-1030J-1D01*
G01X891937Y209912D01*
G03X891316Y210397I-794J-377D01*
G01X890158Y210629D01*
G01X888189Y204724D02*
Y205188D01*
G03X887748Y206252I-1504J0D01*
G01X887692Y206308D01*
G03X886764Y206692I-928J-929D01*
G01X886221D01*
G01X892126Y196850D02*
Y197613D01*
G03X891800Y198400I-1113J0D01*
G03X890791Y198818I-1009J-1009D01*
G01X890158D01*
G01X888189Y192913D02*
G03X887554Y194446I-2168J0D01*
G01X887400Y194600D01*
G03X886722Y194881I-678J-678D01*
G01X886221D01*
G01X892126Y188976D02*
X890158Y190944D01*
G01X888189Y185039D02*
X886221Y183071D01*
G01X892126Y181102D02*
X890158Y179134D01*
G01X896063Y208661D02*
X894095Y210629D01*
G01X892126Y204724D02*
X890158Y206692D01*
G01X896063Y196850D02*
X894095Y198818D01*
G01X892126Y192913D02*
X890158Y194881D01*
G01X896063Y188976D02*
X894095Y190944D01*
G01X892126Y185039D02*
X890158Y183071D01*
G01X896063Y181102D02*
X894095Y179134D01*
G01X880315Y208661D02*
X878347Y210629D01*
G01X876378Y204724D02*
X874410Y206692D01*
G01X880315Y196850D02*
X878347Y198818D01*
G01X876378Y192913D02*
X874410Y194881D01*
G01X880315Y188976D02*
X878347Y190944D01*
G01X876378Y185039D02*
Y183639D01*
G02X876352Y183508I-340J-1D01*
G01X876324Y183441D01*
G02X875514Y182900I-810J336D01*
G01X874823D01*
G02X874410Y183071I0J584D01*
G01X884252Y208661D02*
X882284Y210629D01*
G01X880315Y204724D02*
X878347Y206692D01*
G01X884252Y196850D02*
X882284Y198818D01*
G01X880315Y192913D02*
X878347Y194881D01*
G01X884252Y188976D02*
X882284Y190944D01*
G01X880315Y185039D02*
X878347Y183071D01*
G01X892126Y232283D02*
G03X891600Y233800I-2451J0D01*
G03X890158Y234251I-1050J-828D01*
G01X888189Y228346D02*
Y228431D01*
G03X887638Y229763I-1883J1D01*
G01X887392Y230009D01*
G03X886654Y230314I-738J-740D01*
G01X886221D01*
G01X892126Y224409D02*
Y224966D01*
G03X892045Y225372I-1058J0D01*
G01X891985Y225517D01*
G03X891319Y226182I-1136J-472D01*
G01X891002Y226313D01*
G03X890683Y226377I-320J-770D01*
G01X890158D01*
G01X888189Y220472D02*
Y221070D01*
G03X888082Y221533I-1051J1D01*
G03X887193Y222229I-1164J-570D01*
G01X886221Y222440D01*
G01X892126Y216535D02*
X891661Y217657D01*
G03X891294Y218206I-1564J-648D01*
G03X890578Y218503I-717J-716D01*
G01X890158D01*
G01X888189Y212598D02*
Y213025D01*
G03X888093Y213509I-1266J0D01*
G01X887948Y213860D01*
G03X887402Y214406I-932J-386D01*
G01X887192Y214493D01*
G03X886825Y214566I-367J-886D01*
G01X886221D01*
G01X907874Y240157D02*
X905906Y242125D01*
G01X900000Y240157D02*
X898032Y242125D01*
G01X892126Y240157D02*
X890158Y242125D01*
G01X884252Y240157D02*
X882284Y242125D01*
G01X896063Y232283D02*
X894095Y234251D01*
G01X892126Y228346D02*
X890158Y230314D01*
G01X896063Y224409D02*
X894095Y226377D01*
G01X892126Y220472D02*
X890158Y222440D01*
G01X896063Y216535D02*
X894095Y218503D01*
G01X892126Y212598D02*
X890158Y214566D01*
G01X880315Y232283D02*
X878347Y234251D01*
G01X876378Y228346D02*
X874410Y230314D01*
G01X880315Y224409D02*
X878347Y226377D01*
G01X876378Y220472D02*
X874410Y222440D01*
G01X880315Y216535D02*
X878347Y218503D01*
G01X876378Y212598D02*
X874410Y214566D01*
G01X884252Y232283D02*
X882284Y234251D01*
G01X880315Y228346D02*
X878347Y230314D01*
G01X884252Y224409D02*
X882284Y226377D01*
G01X880315Y220472D02*
X878347Y222440D01*
G01X884252Y216535D02*
X882284Y218503D01*
G01X880315Y212598D02*
X878347Y214566D01*
G01X907874Y244094D02*
X905906Y246062D01*
G01X903937Y248031D02*
X901969Y249999D01*
G01X900000Y244094D02*
X898032Y246062D01*
G01X896063Y248031D02*
X894095Y249999D01*
G01X892126Y244094D02*
X890158Y246062D01*
G01X888189Y248031D02*
X886221Y249999D01*
G01X884252Y244094D02*
X882284Y246062D01*
G01X880315Y248031D02*
X878347Y249999D01*
G01X903937Y244094D02*
X901969Y246062D01*
G01X896063Y244094D02*
X894095Y246062D01*
G01X888189Y244094D02*
X886221Y246062D01*
G01X880315Y244094D02*
X878347Y246062D01*
G01X907874Y255905D02*
X905906Y257873D01*
G01X903937Y259842D02*
X901969Y261810D01*
G01X900000Y255905D02*
X898032Y257873D01*
G01X896063Y259842D02*
X894095Y261810D01*
G01X892126Y255905D02*
X890158Y257873D01*
G01X888189Y259842D02*
X886221Y261810D01*
G01X884252Y255905D02*
X882284Y257873D01*
G01X880315Y259842D02*
X878347Y261810D01*
G01X907874Y251968D02*
X905906Y253936D01*
G01X903937Y255905D02*
X901969Y257873D01*
G01X900000Y251968D02*
X898032Y253936D01*
G01X896063Y255905D02*
X894095Y257873D01*
G01X892126Y251968D02*
X890158Y253936D01*
G01X888189Y255905D02*
X886221Y257873D01*
G01X884252Y251968D02*
X882284Y253936D01*
G01X880315Y255905D02*
X878347Y257873D01*
G01X935433Y133858D02*
X933465Y131890D01*
G01X935433Y137795D02*
X933465Y135827D01*
G01X939370Y133858D02*
X937402Y131890D01*
G01X939370Y137795D02*
X937402Y135827D01*
G01X931496Y133858D02*
X929528Y131890D01*
G01X931496Y137795D02*
X929528Y135827D01*
G01X927559Y133858D02*
X925591Y131890D01*
G01X927559Y137795D02*
X925591Y135827D01*
G01X911811Y122047D02*
X909843Y120079D01*
G01X915748Y118110D02*
X913780Y116142D01*
G01X919685Y122047D02*
X917717Y120079D01*
G01X923622Y118110D02*
X921654Y116142D01*
G01X927559Y122047D02*
X925591Y120079D01*
G01X931496Y118110D02*
X929528Y116142D01*
G01X935433Y122047D02*
X933465Y120079D01*
G01X939370Y118110D02*
X937402Y116142D01*
G01X911811Y125984D02*
X909843Y124016D01*
G01X915748Y122047D02*
X913780Y120079D01*
G01X919685Y125984D02*
X917717Y124016D01*
G01X923622Y122047D02*
X921654Y120079D01*
G01X927559Y125984D02*
X925591Y124016D01*
G01X931496Y122047D02*
X929528Y120079D01*
G01X935433Y125984D02*
X933465Y124016D01*
G01X939370Y122047D02*
X937402Y120079D01*
G01X935433Y145669D02*
X933465Y143701D01*
G01X935433Y149606D02*
X933465Y147638D01*
G01X939370Y145669D02*
X937402Y143701D01*
G01X939370Y149606D02*
X937402Y147638D01*
G01X931496Y145669D02*
X929528Y143701D01*
G01X931496Y149606D02*
X929528Y147638D01*
G01X935433Y240157D02*
X933465Y242125D01*
G01X927559Y240157D02*
X925591Y242125D01*
G01X919685Y240157D02*
X917717Y242125D01*
G01X939370Y248031D02*
X937402Y249999D01*
G01X935433Y244094D02*
X933465Y246062D01*
G01X931496Y248031D02*
X929528Y249999D01*
G01X927559Y244094D02*
X925591Y246062D01*
G01X923622Y248031D02*
X921654Y249999D01*
G01X919685Y244094D02*
X917717Y246062D01*
G01X915748Y248031D02*
X913780Y249999D01*
G01X939370Y244094D02*
X937402Y246062D01*
G01X931496Y244094D02*
X929528Y246062D01*
G01X923622Y244094D02*
X921654Y246062D01*
G01X915748Y244094D02*
X913780Y246062D01*
G01X939370Y259842D02*
X937402Y261810D01*
G01X935433Y255905D02*
X933465Y257873D01*
G01X931496Y259842D02*
X929528Y261810D01*
G01X927559Y255905D02*
X925591Y257873D01*
G01X923622Y259842D02*
X921654Y261810D01*
G01X919685Y255905D02*
X917717Y257873D01*
G01X915748Y259842D02*
X913780Y261810D01*
G01X939370Y255905D02*
X937402Y257873D01*
G01X935433Y251968D02*
X933465Y253936D01*
G01X931496Y255905D02*
X929528Y257873D01*
G01X927559Y251968D02*
X925591Y253936D01*
G01X923622Y255905D02*
X921654Y257873D01*
G01X919685Y251968D02*
X917717Y253936D01*
G01X915748Y255905D02*
X913780Y257873D01*
G01X943307Y133858D02*
X941339Y131890D01*
G01X943307Y137795D02*
X941339Y135827D01*
G01X955118Y118110D02*
X957086Y116142D01*
G01X959055Y122047D02*
X961023Y120079D01*
G01X962992Y118110D02*
X964960Y116142D01*
G01X966929Y122047D02*
X968897Y120079D01*
G01X970866Y118110D02*
X972834Y116142D01*
G01X974803Y122047D02*
X976771Y120079D01*
G01X955118Y122047D02*
X957086Y120079D01*
G01X959055Y125984D02*
X961023Y124016D01*
G01X962992Y122047D02*
X964960Y120079D01*
G01X966929Y125984D02*
X968897Y124016D01*
G01X970866Y122047D02*
X972834Y120079D01*
G01X974803Y125984D02*
X976771Y124016D01*
G01X943307Y145669D02*
X941339Y143701D01*
G01X943307Y149606D02*
X941339Y147638D01*
G01X947244Y145669D02*
X949212Y143701D01*
G01X947244Y149606D02*
X949212Y147638D01*
G01X974803Y240157D02*
X976771Y242125D01*
G01X966929Y240157D02*
X968897Y242125D01*
G01X959055Y240157D02*
X961023Y242125D01*
G01X951181Y240157D02*
X953149Y242125D01*
G01X943307Y240157D02*
X941339Y242125D01*
G01X974803Y244094D02*
X976771Y246062D01*
G01X970866Y248031D02*
X972834Y249999D01*
G01X966929Y244094D02*
X968897Y246062D01*
G01X962992Y248031D02*
X964960Y249999D01*
G01X959055Y244094D02*
X961023Y246062D01*
G01X955118Y248031D02*
X957086Y249999D01*
G01X951181Y244094D02*
X953149Y246062D01*
G01X943307Y244094D02*
X941339Y246062D01*
G01X970866Y244094D02*
X972834Y246062D01*
G01X962992Y244094D02*
X964960Y246062D01*
G01X955118Y244094D02*
X957086Y246062D01*
G01X974803Y255905D02*
X976771Y257873D01*
G01X970866Y259842D02*
X972834Y261810D01*
G01X966929Y255905D02*
X968897Y257873D01*
G01X962992Y259842D02*
X964960Y261810D01*
G01X959055Y255905D02*
X961023Y257873D01*
G01X955118Y259842D02*
X957086Y261810D01*
G01X951181Y255905D02*
X953149Y257873D01*
G01X943307Y255905D02*
X941339Y257873D01*
G01X974803Y251968D02*
X976771Y253936D01*
G01X970866Y255905D02*
X972834Y257873D01*
G01X966929Y251968D02*
X968897Y253936D01*
G01X962992Y255905D02*
X964960Y257873D01*
G01X959055Y251968D02*
X961023Y253936D01*
G01X955118Y255905D02*
X957086Y257873D01*
G01X951181Y251968D02*
X953149Y253936D01*
G01X943307Y251968D02*
X941339Y253936D01*
G01X1006299Y141732D02*
X1008267Y139764D01*
G01X978740Y118110D02*
X980708Y116142D01*
G01X982677Y122047D02*
X984645Y120079D01*
G01X1006299Y133858D02*
X1008267Y131890D01*
G01X1002362Y137795D02*
X1004330Y135827D01*
G01X1002362Y141732D02*
X1004330Y139764D01*
G01X978740Y122047D02*
X980708Y120079D01*
G01X982677Y125984D02*
X984645Y124016D01*
G01X1002362Y133858D02*
X1004330Y131890D01*
G01X998425Y137795D02*
X1000393Y135827D01*
G01X990551Y118110D02*
X992519Y116142D01*
Y115742D01*
G01X994488Y122047D02*
X996456Y120079D01*
G01X998425Y118110D02*
X1000393Y116142D01*
G01X1002362Y122047D02*
X1004330Y120079D01*
G01X1006299Y118110D02*
X1008267Y116142D01*
G01X990551Y122047D02*
X992519Y120079D01*
G01X994488Y125984D02*
X996456Y124016D01*
G01X998425Y122047D02*
X1000393Y120079D01*
G01X1002362Y125984D02*
X1004330Y124016D01*
G01X1006299Y122047D02*
X1008267Y120079D01*
G01X1002362Y145669D02*
X1004330Y143701D01*
G01X1006299Y149606D02*
X1008267Y147638D01*
G01X1002362Y153543D02*
X1004330Y151575D01*
G01X1006299Y157480D02*
X1008267Y155512D01*
G01X1002362Y161417D02*
X1004330Y159449D01*
G01X1006299Y169291D02*
X1008267Y167323D01*
G01X1002362Y173228D02*
X1004330Y171260D01*
G01X1006299Y177165D02*
X1008267Y175197D01*
G01X998425Y145669D02*
X1000393Y143701D01*
G01X1002362Y149606D02*
X1004330Y147638D01*
G01X998425Y153543D02*
X1000393Y151575D01*
G01X1002362Y157480D02*
X1004330Y155512D01*
G01X998425Y161417D02*
X1000393Y159449D01*
G01X1002362Y169291D02*
X1004330Y167323D01*
G01X998425Y173228D02*
X1000393Y171260D01*
G01X1002362Y177165D02*
X1004330Y175197D01*
G01X1002362Y181102D02*
X1004330Y179134D01*
G01X1006299Y185039D02*
X1008267Y183071D01*
G01X1002362Y188976D02*
X1004330Y190944D01*
G01X1006299Y192913D02*
X1008267Y194881D01*
G01X1002362Y196850D02*
X1004330Y198818D01*
G01X1006299Y204724D02*
X1008267Y206692D01*
G01X1002362Y208661D02*
X1004330Y210629D01*
G01X998425Y181102D02*
X1000393Y179134D01*
G01X1002362Y185039D02*
X1004330Y183071D01*
G01X998425Y188976D02*
X1000393Y190944D01*
G01X1002362Y192913D02*
X1004330Y194881D01*
G01X998425Y196850D02*
X1000393Y198818D01*
G01X1002362Y204724D02*
X1004330Y206692D01*
G01X998425Y208661D02*
X1000393Y210629D01*
G01X1006299Y212598D02*
X1008267Y214566D01*
G01X1002362Y216535D02*
X1004330Y218503D01*
G01X1006299Y220472D02*
X1008267Y222440D01*
G01X1002362Y224409D02*
X1004330Y226377D01*
G01X1006299Y228346D02*
X1008267Y230314D01*
G01X1002362Y232283D02*
X1004330Y234251D01*
G01X1002362Y212598D02*
X1004330Y214566D01*
G01X998425Y216535D02*
X1000393Y218503D01*
G01X1002362Y220472D02*
X1004330Y222440D01*
G01X998425Y224409D02*
X1000393Y226377D01*
G01X1002362Y228346D02*
X1004330Y230314D01*
G01X998425Y232283D02*
X1000393Y234251D01*
G01X1002362Y240157D02*
X1004330Y242125D01*
G01X994488Y240157D02*
X996456Y242125D01*
G01X986614Y240157D02*
X988582Y242125D01*
G01X1006299Y248031D02*
X1008267Y249999D01*
G01X1002362Y244094D02*
X1004330Y246062D01*
G01X998425Y248031D02*
X1000393Y249999D01*
G01X994488Y244094D02*
X996456Y246062D01*
G01X990551Y248031D02*
X992519Y249999D01*
G01X986614Y244094D02*
X988582Y246062D01*
G01X978740Y248031D02*
X980708Y249999D01*
G01X1006299Y244094D02*
X1008267Y246062D01*
G01X998425Y244094D02*
X1000393Y246062D01*
G01X990551Y244094D02*
X992519Y246062D01*
G01X978740Y244094D02*
X980708Y246062D01*
G01X1006299Y259842D02*
X1008267Y261810D01*
G01X1002362Y255905D02*
X1004330Y257873D01*
G01X998425Y259842D02*
X1000393Y261810D01*
G01X994488Y255905D02*
X996456Y257873D01*
G01X990551Y259842D02*
X992519Y261810D01*
G01X986614Y255905D02*
X988582Y257873D01*
G01X978740Y259842D02*
X980708Y261810D01*
G01X1006299Y255905D02*
X1008267Y257873D01*
G01X1002362Y251968D02*
X1004330Y253936D01*
G01X998425Y255905D02*
X1000393Y257873D01*
G01X994488Y251968D02*
X996456Y253936D01*
G01X990551Y255905D02*
X992519Y257873D01*
G01X986614Y251968D02*
X988582Y253936D01*
G01X978740Y255905D02*
X980708Y257873D01*
G01X1018110Y141732D02*
X1020078Y139764D01*
G01X1010236Y122047D02*
X1012204Y120079D01*
G01X1014173Y118110D02*
X1016141Y116142D01*
G01X1018110Y122047D02*
X1020078Y120079D01*
G01X1018110Y133858D02*
X1020078Y131890D01*
G01X1014173Y137795D02*
X1016141Y135827D01*
G01X1014173Y141732D02*
X1016141Y139764D01*
G01X1010236Y125984D02*
X1012204Y124016D01*
G01X1014173Y122047D02*
X1016141Y120079D01*
G01X1018110Y125984D02*
Y125247D01*
X1023278Y120079D01*
G01X1014173Y133858D02*
X1016141Y131890D01*
G01X1010236Y137795D02*
X1012204Y135827D01*
G01X1014173Y145669D02*
X1016141Y143701D01*
G01X1018110Y149606D02*
X1020078Y147638D01*
G01X1014173Y153543D02*
X1016141Y151575D01*
G01X1018110Y157480D02*
X1020078Y155512D01*
G01X1014173Y161417D02*
X1016141Y159449D01*
G01X1018110Y169291D02*
X1020078Y167323D01*
G01X1014173Y173228D02*
X1016141Y171260D01*
G01X1018110Y177165D02*
X1020078Y175197D01*
G01X1010236Y145669D02*
X1012204Y143701D01*
G01X1014173Y149606D02*
X1016141Y147638D01*
G01X1010236Y153543D02*
X1012204Y151575D01*
G01X1014173Y157480D02*
X1016141Y155512D01*
G01X1010236Y161417D02*
X1012204Y159449D01*
G01X1014173Y169291D02*
X1016141Y167323D01*
G01X1010236Y173228D02*
X1012204Y171260D01*
G01X1014173Y177165D02*
X1016141Y175197D01*
G01X1014173Y181102D02*
X1016141Y179134D01*
G01X1018110Y185039D02*
X1020078Y183071D01*
G01X1014173Y188976D02*
X1016141Y190944D01*
G01X1018110Y192913D02*
X1020078Y194881D01*
G01X1014173Y196850D02*
X1016141Y198818D01*
G01X1018110Y204724D02*
X1020078Y206692D01*
G01X1014173Y208661D02*
X1016141Y210629D01*
G01X1010236Y181102D02*
X1012204Y179134D01*
G01X1014173Y185039D02*
X1016141Y183071D01*
G01X1010236Y188976D02*
X1012204Y190944D01*
G01X1014173Y192913D02*
X1016141Y194881D01*
G01X1010236Y196850D02*
X1012204Y198818D01*
G01X1014173Y204724D02*
X1016141Y206692D01*
G01X1010236Y208661D02*
X1012204Y210629D01*
G01X1010236Y240157D02*
X1012204Y242125D01*
G01X1018110Y212598D02*
X1020078Y214566D01*
G01X1014173Y216535D02*
X1016141Y218503D01*
G01X1018110Y220472D02*
X1020078Y222440D01*
G01X1014173Y224409D02*
X1016141Y226377D01*
G01X1018110Y228346D02*
X1020078Y230314D01*
G01X1014173Y232283D02*
X1016141Y234251D01*
G01X1014173Y212598D02*
X1016141Y214566D01*
G01X1010236Y216535D02*
X1012204Y218503D01*
G01X1014173Y220472D02*
X1016141Y222440D01*
G01X1010236Y224409D02*
X1012204Y226377D01*
G01X1014173Y228346D02*
X1016141Y230314D01*
G01X1010236Y232283D02*
X1012204Y234251D01*
G01X1014173Y248031D02*
X1016141Y249999D01*
G01X1010236Y244094D02*
X1012204Y246062D01*
G01X1014173Y244094D02*
X1016141Y246062D01*
G01X1014173Y259842D02*
X1016141Y261810D01*
G01X1010236Y255905D02*
X1012204Y257873D01*
G01X1014173Y255905D02*
X1016141Y257873D01*
G01X1010236Y251968D02*
X1012204Y253936D01*
G01X1040914Y834551D02*
X1042023Y833442D01*
G02X1042289Y832800I-642J-642D01*
G01Y831800D01*
G02X1041918Y830906I-1265J1D01*
G01X1041314Y830301D01*
G01X1041339Y887970D02*
Y885152D01*
X1041340Y885151D01*
G03X1042002Y883160I3325J0D01*
G02X1042314Y882407I-753J-753D01*
G01Y841431D01*
G02X1040914Y838051I-4780J0D01*
G01X1076750Y50000D02*
G03X1074682Y50873I-2109J-2110D01*
G03X1074640Y50874I-92J-2982D01*
G01X1070495D01*
G02X1063083Y53944I0J10483D01*
G03X1059400Y55470I-3683J-3682D01*
G01X1058624D01*
G03X1057507Y55008I-1J-1579D01*
G01X1057000Y54500D01*
G01X1071135Y60375D02*
G03X1072900Y59400I1765J1110D01*
G01X1075300D01*
G03X1076750Y60500I0J1506D01*
G01X1057000Y57700D02*
G03X1059285Y56684I2464J2464D01*
G01X1059731Y56661D01*
G02X1063932Y54793I-330J-6399D01*
G03X1070496Y52074I6564J6564D01*
G01X1074700D01*
G03X1075765Y52515I0J1506D01*
G01X1076750Y53500D01*
G01X1071135Y57175D02*
G02X1072900Y58200I1765J-1007D01*
G01X1075300D01*
G02X1076750Y57000I0J-1476D01*
G01X1070111Y834551D02*
X1068917Y833356D01*
G03X1068686Y832800I556J-557D01*
G01Y831852D01*
G03X1069058Y830954I1270J0D01*
G01X1069711Y830301D01*
G01X1057512Y834551D02*
X1056318Y833356D01*
G03X1056087Y832800I556J-557D01*
G01Y831949D01*
G03X1056528Y830886I1504J1D01*
G01X1057112Y830301D01*
G01X1044914Y834551D02*
X1043720Y833356D01*
G03X1043489Y832800I556J-557D01*
G01Y831799D01*
G03X1043823Y830991I1142J-1D01*
G01X1044514Y830301D01*
G01X1066111Y834551D02*
X1067220Y833442D01*
G02X1067486Y832800I-642J-642D01*
G01Y831900D01*
G02X1067045Y830835I-1506J0D01*
G01X1066511Y830301D01*
G01X1053512Y834551D02*
X1054621Y833442D01*
G02X1054887Y832800I-642J-642D01*
G01Y831910D01*
G02X1054439Y830827I-1531J-1D01*
G01X1053912Y830301D01*
G01X1069686Y887970D02*
Y885151D01*
G02X1069017Y883152I-3325J1D01*
G03X1068712Y882416I736J-736D01*
G01Y841428D01*
G03X1070111Y838051I4776J0D01*
G01X1057087Y887970D02*
Y885151D01*
G02X1056418Y883152I-3325J1D01*
G03X1056113Y882416I736J-736D01*
G01Y841428D01*
G03X1057512Y838051I4776J0D01*
G01X1044489Y887970D02*
Y885151D01*
G02X1043820Y883152I-3325J1D01*
G03X1043515Y882416I736J-736D01*
G01Y841428D01*
G03X1044914Y838051I4776J0D01*
G01X1066536Y887970D02*
Y885152D01*
X1066537Y885151D01*
G03X1067199Y883160I3325J0D01*
G02X1067511Y882407I-753J-753D01*
G01Y841431D01*
G02X1066111Y838051I-4780J0D01*
G01X1053937Y887970D02*
Y885152D01*
X1053938Y885151D01*
G03X1054600Y883160I3325J0D01*
G02X1054912Y882407I-753J-753D01*
G01Y841431D01*
G02X1053512Y838051I-4780J0D01*
G01X1089975Y14177D02*
X1091991Y16193D01*
X1153077D01*
X1156007Y19123D01*
Y19125D01*
X1164900Y28018D01*
Y45802D01*
X1167849Y48751D01*
G02X1169249Y49331I1400J-1400D01*
G01X1172773D01*
G01X1090177Y18525D02*
X1091309Y17393D01*
X1152579D01*
X1154807Y19621D01*
Y19623D01*
X1163700Y28516D01*
Y46300D01*
X1168398Y50998D01*
G03X1169820Y54431I-3433J3433D01*
G01Y54843D01*
G01X1138324Y79252D02*
G03X1135873Y80216I-1435J-52D01*
G01X1135149Y79492D01*
G03X1134904Y78903I587J-590D01*
G01Y78892D01*
G02X1133751Y76108I-3938J0D01*
G01X1133008Y75365D01*
G02X1130508Y74330I-2499J2500D01*
G01X1118041D01*
G03X1115376Y73226I0J-3769D01*
G01X1094166Y52016D01*
G02X1092073Y51150I-2092J2094D01*
G01X1083026D01*
G03X1080250Y50000I0J-3926D01*
G01X1138324Y94213D02*
Y95299D01*
X1138325Y95300D01*
Y95802D01*
G02X1138451Y96797I3980J1D01*
G02X1138741Y97573I3853J-998D01*
G03X1138976Y98145I-3871J1924D01*
G03X1139193Y99500I-4106J1352D01*
G01Y100824D01*
G03X1138315Y102944I-2998J0D01*
G03X1136196Y103822I-2120J-2120D01*
G01X1105918D01*
G03X1101094Y102750I-1J-11386D01*
G01X1099144Y101837D01*
X1097194Y100925D01*
G03X1094396Y97997I2373J-5069D01*
G01X1093929Y96869D01*
G03X1093148Y92945I9473J-3925D01*
G01Y65392D01*
G02X1091701Y61899I-4940J0D01*
G02X1085668Y59400I-6033J6033D01*
G01X1082906D01*
G02X1080250Y60500I0J3756D01*
G01X1135372Y84764D02*
G02X1135563Y81605I-1304J-1664D01*
G01X1134299Y80341D01*
G03X1133704Y78904I1438J-1437D01*
G01Y78893D01*
G02X1132902Y76957I-2738J0D01*
G01X1132159Y76214D01*
G02X1130508Y75530I-1651J1651D01*
G01X1118041D01*
G03X1114527Y74075I-1J-4969D01*
G01X1093317Y52865D01*
G02X1092073Y52350I-1244J1245D01*
G01X1083026D01*
G02X1080250Y53500I0J3926D01*
G01X1135372Y99725D02*
X1134983Y98097D01*
Y97694D01*
G03X1135213Y97139I785J0D01*
G01X1135329Y97023D01*
G03X1135761Y96844I432J432D01*
G01X1136299D01*
G03X1136864Y97078I0J799D01*
G01X1137079Y97292D01*
G03X1137666Y98108I-2208J2208D01*
G01Y98107D01*
G03X1137836Y98520I-2795J1392D01*
G03X1137992Y99499I-2966J975D01*
G01X1137993D01*
Y100824D01*
G03X1137466Y102095I-1798J-1D01*
G03X1136195Y102622I-1272J-1271D01*
G01X1105919D01*
G03X1101603Y101662I1J-10186D01*
G01X1097703Y99838D01*
G03X1095505Y97538I1864J-3982D01*
G01X1095038Y96410D01*
G03X1094348Y92944I8364J-3467D01*
G01Y65391D01*
G02X1092550Y61050I-6140J0D01*
G02X1085668Y58200I-6881J6882D01*
G01X1082247D01*
G03X1080887Y57636I1J-1924D01*
G01X1080250Y57000D01*
G01X1107906Y834551D02*
X1106712Y833356D01*
G03X1106481Y832800I556J-557D01*
G01Y831799D01*
G03X1106815Y830991I1142J-1D01*
G01X1107506Y830301D01*
G01X1095307Y834551D02*
X1094113Y833356D01*
G03X1093882Y832800I556J-557D01*
G01Y831799D01*
G03X1094216Y830991I1142J-1D01*
G01X1094907Y830301D01*
G01X1082709Y834551D02*
X1081515Y833356D01*
G03X1081284Y832800I556J-557D01*
G01Y831799D01*
G03X1081618Y830991I1142J-1D01*
G01X1082309Y830301D01*
G01X1103906Y834551D02*
X1105015Y833442D01*
G02X1105281Y832800I-642J-642D01*
G01Y831800D01*
G02X1104910Y830906I-1265J1D01*
G01X1104306Y830301D01*
G01X1091307Y834551D02*
X1092416Y833442D01*
G02X1092682Y832800I-642J-642D01*
G01Y831800D01*
G02X1092311Y830906I-1265J1D01*
G01X1091707Y830301D01*
G01X1078709Y834551D02*
X1079818Y833442D01*
G02X1080084Y832800I-642J-642D01*
G01Y831800D01*
G02X1079713Y830906I-1265J1D01*
G01X1079109Y830301D01*
G01X1107481Y887970D02*
Y885151D01*
G02X1106812Y883152I-3325J1D01*
G03X1106507Y882416I736J-736D01*
G01Y841428D01*
G03X1107906Y838051I4776J0D01*
G01X1094882Y887970D02*
Y885151D01*
G02X1094213Y883152I-3325J1D01*
G03X1093908Y882416I736J-736D01*
G01Y841428D01*
G03X1095307Y838051I4776J0D01*
G01X1082284Y887970D02*
Y885151D01*
G02X1081615Y883152I-3325J1D01*
G03X1081310Y882416I736J-736D01*
G01Y841428D01*
G03X1082709Y838051I4776J0D01*
G01X1104331Y887970D02*
Y885152D01*
X1104332Y885151D01*
G03X1104994Y883160I3325J0D01*
G02X1105306Y882407I-753J-753D01*
G01Y841431D01*
G02X1103906Y838051I-4780J0D01*
G01X1091733Y887970D02*
Y885151D01*
G03X1092395Y883160I3325J0D01*
G02X1092707Y882407I-753J-753D01*
G01Y841431D01*
G02X1091307Y838051I-4780J0D01*
G01X1079134Y887970D02*
Y885152D01*
X1079135Y885151D01*
G03X1079797Y883160I3325J0D01*
G02X1080109Y882407I-753J-753D01*
G01Y841431D01*
G02X1078709Y838051I-4780J0D01*
G01X1147183Y94213D02*
Y95802D01*
G02X1147599Y97573I3980J-1D01*
G03X1148051Y99500I-3871J1924D01*
G01Y101500D01*
G03X1147169Y103631I-3013J1D01*
G01X1135857Y114943D01*
G02X1135200Y116529I1586J1586D01*
G01Y129167D01*
G03X1134400Y131099I-2733J0D01*
G01Y131100D01*
X1133900Y131600D01*
X1133899D01*
G03X1132451Y132200I-1449J-1450D01*
G01X1131900D01*
Y132199D01*
G02X1129938Y133011I-1J2774D01*
G01X1129650Y133300D01*
G01X1144230Y99725D02*
X1143904Y98362D01*
G03X1144411Y96993I1277J-305D01*
G03X1145743Y97098I604J833D01*
G01X1145937Y97292D01*
G03X1146524Y98108I-2208J2208D01*
G03X1146851Y99500I-2795J1391D01*
G01Y101501D01*
X1146850Y101500D01*
G03X1146320Y102782I-1813J1D01*
G01X1135008Y114094D01*
G02X1134000Y116529I2435J2434D01*
G01Y129166D01*
G03X1133551Y130251I-1533J1D01*
G01Y130250D01*
X1133051Y130751D01*
G03X1132450Y131000I-601J-601D01*
G01X1131500D01*
G03X1130391Y130540I1J-1569D01*
G01X1129650Y129800D01*
G01X1122001Y133324D02*
X1122860Y132465D01*
G03X1123500Y132200I640J640D01*
G01X1124549D01*
G03X1125405Y132554I1J1210D01*
G01X1126150Y133300D01*
G01X1142000Y133750D02*
X1141516Y134235D01*
G02X1140950Y135600I1365J1366D01*
G01Y136150D01*
G02X1141481Y137432I1813J0D01*
G01X1141900Y137851D01*
G01X1126150Y129800D02*
X1125233Y130716D01*
G03X1124549Y131000I-685J-684D01*
G01X1123500D01*
G03X1122437Y130559I1J-1504D01*
G01X1122001Y130124D01*
G01X1138500Y133750D02*
X1139326Y134575D01*
G03X1139750Y135600I-1025J1024D01*
G01Y136150D01*
G03X1139290Y137262I-1572J1D01*
G01X1138700Y137851D01*
G01X1147183Y79252D02*
Y82145D01*
G02X1147191Y82265I840J4D01*
G02X1147429Y82739I831J-121D01*
G03X1148229Y84672I-1933J1932D01*
G01Y86500D01*
G02X1148958Y88260I2489J0D01*
G01X1153242Y92544D01*
G03X1154300Y95100I-2557J2555D01*
G01Y107567D01*
G03X1152792Y111208I-5150J0D01*
G01X1141457Y122543D01*
G02X1140800Y124129I1586J1586D01*
G01Y128400D01*
G02X1142000Y130250I2026J0D01*
G01X1144230Y84764D02*
Y83390D01*
G03X1144479Y82789I850J0D01*
G03X1144962Y82589I483J483D01*
G01X1145158D01*
G03X1145831Y82842I0J1021D01*
G03X1145871Y82879I-673J768D01*
G03X1145880Y82888I-717J726D01*
G01X1146580Y83588D01*
G03X1147029Y84671I-1084J1084D01*
G01Y86500D01*
G02X1148109Y89109I3689J1D01*
G01X1152393Y93393D01*
G03X1153099Y95100I-1708J1706D01*
G01X1153100Y95099D01*
Y107567D01*
G03X1151943Y110359I-3949J-1D01*
G01X1140608Y121694D01*
G02X1139600Y124129I2435J2434D01*
G01Y128400D01*
G03X1138500Y130250I-2106J0D01*
G01X1133103Y834551D02*
X1131909Y833356D01*
G03X1131678Y832800I556J-557D01*
G01Y831887D01*
G02Y831847I-2677J-20D01*
G03X1132046Y830957I1258J-1D01*
G01X1132703Y830301D01*
G01X1120504Y834551D02*
X1119310Y833356D01*
G03X1119079Y832800I556J-557D01*
G01Y831799D01*
G03X1119413Y830991I1142J-1D01*
G01X1120104Y830301D01*
G01X1141701Y834551D02*
X1142810Y833442D01*
G02X1143076Y832800I-642J-642D01*
G01Y831900D01*
G02X1142635Y830835I-1506J0D01*
G01X1142101Y830301D01*
G01X1129103Y834551D02*
X1130212Y833442D01*
G02X1130478Y832800I-642J-642D01*
G01Y831888D01*
G02X1130045Y830844I-1477J1D01*
G01X1129503Y830301D01*
G01X1116504Y834551D02*
X1117613Y833442D01*
G02X1117879Y832800I-642J-642D01*
G01Y831800D01*
G02X1117508Y830906I-1265J1D01*
G01X1116904Y830301D01*
G01X1132678Y887970D02*
Y885151D01*
G02X1132009Y883152I-3325J1D01*
G03X1131704Y882416I736J-736D01*
G01Y841428D01*
G03X1133103Y838051I4776J0D01*
G01X1120079Y887970D02*
Y885151D01*
G02X1119410Y883152I-3325J1D01*
G03X1119105Y882416I736J-736D01*
G01Y841428D01*
G03X1120504Y838051I4776J0D01*
G01X1142126Y887970D02*
Y885152D01*
X1142127Y885151D01*
G03X1142789Y883160I3325J0D01*
G02X1143101Y882407I-753J-753D01*
G01Y841431D01*
G02X1141701Y838051I-4780J0D01*
G01X1129528Y887970D02*
Y885152D01*
X1129529Y885151D01*
G03X1130191Y883160I3325J0D01*
G02X1130503Y882407I-753J-753D01*
G01Y841431D01*
G02X1129103Y838051I-4780J0D01*
G01X1116930Y887970D02*
Y885151D01*
G03X1117592Y883160I3325J0D01*
G02X1117904Y882407I-753J-753D01*
G01Y841431D01*
G02X1116504Y838051I-4780J0D01*
G01X1169820Y99725D02*
Y98351D01*
G03X1170069Y97750I850J0D01*
G03X1170552Y97550I483J483D01*
G01X1170748D01*
G03X1171461Y97840I0J1021D01*
G03X1171470Y97849I-717J726D01*
G01X1172170Y98549D01*
G03X1172619Y99633I-1084J1084D01*
G01Y102528D01*
G03X1172144Y103675I-1622J0D01*
G01X1171663Y104156D01*
G02X1171380Y104486I2004J2005D01*
G02X1170851Y106104I2210J1618D01*
G01X1170850Y113347D01*
Y128266D01*
G03X1170513Y129081I-1152J1D01*
G01X1169467Y130126D01*
G01X1173479Y130121D02*
X1172351Y128993D01*
G03X1172050Y128266I727J-727D01*
G01Y126885D01*
X1172052Y106204D01*
X1172051Y106203D01*
Y106127D01*
G03X1172518Y104999I1595J0D01*
G01X1172993Y104524D01*
G02X1173047Y104469I-1987J-2005D01*
G02X1173819Y102528I-2050J-1940D01*
G01Y99633D01*
G02X1173019Y97700I-2733J-1D01*
G03X1172773Y97106I594J-594D01*
G01Y94213D01*
G01X1181631Y79252D02*
X1181632Y79253D01*
Y82145D01*
G02X1181878Y82739I840J0D01*
G03X1182678Y84672I-1933J1932D01*
G01Y85500D01*
G03X1181620Y88056I-3615J1D01*
G01X1180363Y89313D01*
G03X1177801Y90374I-2562J-2563D01*
G01X1172137D01*
G02X1169557Y91444I2J3649D01*
G01X1160645Y100349D01*
G02X1160258Y101285I936J935D01*
G01X1160257Y101284D01*
Y129000D01*
G02X1161407Y130904I2151J0D01*
G01X1178679Y84764D02*
Y83390D01*
G03X1178928Y82789I850J0D01*
G03X1179411Y82589I483J483D01*
G01X1179607D01*
G03X1180218Y82792I0J1021D01*
G03X1180320Y82879I-610J819D01*
G03X1180329Y82888I-717J726D01*
G01X1181029Y83588D01*
G03X1181478Y84672I-1084J1084D01*
G01Y85500D01*
G03X1180771Y87207I-2414J0D01*
G01X1179514Y88464D01*
G03X1177800Y89174I-1714J-1714D01*
G01X1172137D01*
G02X1168708Y90594I0J4850D01*
G01X1159796Y99500D01*
G02X1159057Y101285I1784J1784D01*
G01Y129000D01*
G03X1157907Y130904I-2151J0D01*
G01X1161407Y134404D02*
X1160923Y134889D01*
G02X1160357Y136254I1365J1366D01*
G01Y136804D01*
G02X1160888Y138086I1813J0D01*
G01X1161307Y138505D01*
G01X1157907Y134404D02*
X1158733Y135229D01*
G03X1159157Y136254I-1025J1024D01*
G01Y136804D01*
G03X1158697Y137916I-1572J1D01*
G01X1158107Y138505D01*
G01X1158299Y834551D02*
X1157105Y833356D01*
G03X1156874Y832800I556J-557D01*
G01Y831948D01*
G03X1157314Y830886I1502J0D01*
G01X1157899Y830301D01*
G01X1145701Y834551D02*
X1144507Y833356D01*
G03X1144276Y832800I556J-557D01*
G01Y831900D01*
G03X1144682Y830920I1386J0D01*
G01X1145301Y830301D01*
G01X1176347Y834551D02*
X1177456Y833442D01*
G02X1177722Y832800I-642J-642D01*
G01Y831700D01*
G02X1177422Y830976I-1024J0D01*
G01X1176747Y830301D01*
G01X1154299Y834551D02*
X1155408Y833442D01*
G02X1155674Y832800I-642J-642D01*
G01Y831879D01*
G02X1155248Y830849I-1456J-1D01*
G01X1154699Y830301D01*
G01X1157874Y887970D02*
Y885151D01*
G02X1157205Y883152I-3325J1D01*
G03X1156900Y882416I736J-736D01*
G01Y841428D01*
G03X1158299Y838051I4776J0D01*
G01X1145276Y887970D02*
Y885151D01*
G02X1144607Y883152I-3325J1D01*
G03X1144302Y882416I736J-736D01*
G01Y841428D01*
G03X1145701Y838051I4776J0D01*
G01X1176772Y887970D02*
Y885152D01*
X1176773Y885151D01*
G03X1177435Y883160I3325J0D01*
G02X1177747Y882407I-753J-753D01*
G01Y841431D01*
G02X1176347Y838051I-4780J0D01*
G01X1154725Y887970D02*
Y885151D01*
G03X1155387Y883160I3325J0D01*
G02X1155699Y882407I-753J-753D01*
G01Y841431D01*
G02X1154299Y838051I-4780J0D01*
G01X1182161Y130377D02*
G03X1180878Y128700I454J-1677D01*
G01Y106204D01*
G03X1181208Y105196I1704J0D01*
G03X1181377Y104999I1374J1008D01*
G01X1181852Y104524D01*
G02X1181906Y104469I-1987J-2005D01*
G02X1182678Y102528I-2050J-1940D01*
G01Y99633D01*
G02X1181878Y97700I-2733J-1D01*
G03X1181632Y97106I594J-594D01*
G01X1181631Y97105D01*
Y94213D01*
G01X1190490D02*
Y97106D01*
G02X1190736Y97700I840J0D01*
G03X1191536Y99633I-1933J1932D01*
G01Y102528D01*
G03X1190764Y104469I-2822J1D01*
G03X1190710Y104524I-2041J-1950D01*
G01X1190235Y104999D01*
G02X1190066Y105196I1205J1205D01*
G02X1189736Y106204I1374J1008D01*
G01Y128800D01*
G02X1190935Y130298I1535J0D01*
G01X1190490Y79252D02*
Y82145D01*
G02X1190499Y82275I841J7D01*
G02X1190503Y82295I826J-155D01*
G02X1190736Y82739I827J-151D01*
G03X1191536Y84672I-1933J1932D01*
G01Y85400D01*
X1191535D01*
G02X1192199Y87001I2264J-1D01*
G01X1196988Y91790D01*
G03X1198300Y94958I-3169J3168D01*
G01Y128500D01*
G02X1199500Y130250I1876J0D01*
G01X1207949Y130180D02*
G03X1206797Y128200I1126J-1980D01*
G01Y98688D01*
X1206798Y98689D01*
G03X1208062Y95636I4316J-1D01*
G01X1212160Y91538D01*
G03X1215510Y90150I3351J3351D01*
G01X1222335D01*
G02X1225985Y86500I0J-3650D01*
G01Y84672D01*
G02X1225697Y83451I-2734J0D01*
G03X1225198Y82208I7340J-3668D01*
G03X1225098Y81853I7846J-2402D01*
G03X1224939Y79252I6562J-1707D01*
G01X1178679Y99725D02*
Y98351D01*
G03X1180000Y97500I935J0D01*
G02X1180320Y97840I5770J-5110D01*
G03X1180329Y97849I-717J726D01*
G01X1181029Y98549D01*
G03X1181478Y99633I-1084J1084D01*
G01Y102528D01*
G03X1181003Y103675I-1622J0D01*
G01X1180522Y104156D01*
G02X1180239Y104486I2004J2005D01*
G02X1179678Y106204I2343J1716D01*
G01Y128700D01*
G03X1178661Y130377I-1891J0D01*
G01X1187537Y99725D02*
Y98351D01*
G03X1187786Y97750I850J0D01*
G03X1188269Y97550I483J483D01*
G01X1188465D01*
G03X1189178Y97840I0J1021D01*
G03X1189187Y97849I-717J726D01*
G01X1189887Y98549D01*
G03X1190336Y99633I-1084J1084D01*
G01Y102528D01*
G03X1189861Y103675I-1622J0D01*
G01X1189380Y104156D01*
G02X1189097Y104486I2004J2005D01*
G02X1188536Y106204I2343J1716D01*
G01X1188535D01*
X1188536Y106205D01*
Y128800D01*
G03X1187435Y130298I-1570J0D01*
G01X1187537Y84764D02*
Y83390D01*
G03X1187786Y82789I850J0D01*
G03X1188269Y82589I483J483D01*
G01X1188465D01*
G03X1189178Y82879I0J1021D01*
G03X1189187Y82888I-717J726D01*
G01X1189887Y83588D01*
G03X1190336Y84672I-1084J1084D01*
G01Y85400D01*
X1190335D01*
Y85401D01*
X1190334Y85400D01*
G02X1191350Y87850I3465J-1D01*
G01X1196139Y92639D01*
G03X1197100Y94958I-2319J2320D01*
G01Y128500D01*
G03X1196000Y130250I-1942J0D01*
G01X1221986Y84764D02*
Y83889D01*
G03X1222199Y83139I1427J0D01*
G01X1222300Y82975D01*
G03X1223173Y82619I681J421D01*
G03X1224079Y83231I-377J1535D01*
G01X1224623Y83987D01*
G03X1224785Y84672I-1367J685D01*
G01Y86500D01*
G03X1222335Y88950I-2450J0D01*
G01X1215510D01*
G02X1211311Y90689I0J5939D01*
G01X1207213Y94787D01*
G02X1205597Y98689I3901J3901D01*
G01Y128200D01*
G03X1204449Y130180I-2281J0D01*
G01X1182161Y133877D02*
G02X1181111Y136412I2535J2535D01*
G01Y140777D01*
G02X1181642Y142059I1813J0D01*
G01X1182061Y142478D01*
G01X1190935Y133798D02*
X1190451Y134283D01*
G02X1189885Y135648I1365J1366D01*
G01Y136198D01*
G02X1190416Y137480I1813J0D01*
G01X1190835Y137899D01*
G01X1199500Y133750D02*
G02X1198450Y136285I2535J2535D01*
G01Y141150D01*
G02X1198981Y142432I1813J0D01*
G01X1199400Y142851D01*
G01X1207949Y133680D02*
X1207326Y134302D01*
G02X1206789Y135600I1298J1297D01*
G01Y141802D01*
X1205991Y142600D01*
Y155730D01*
X1206991Y156730D01*
G01X1178661Y133877D02*
G03X1179911Y136895I-3018J3018D01*
G01Y140777D01*
G03X1179451Y141889I-1572J1D01*
G01X1178861Y142478D01*
G01X1187435Y133798D02*
X1188261Y134623D01*
G03X1188685Y135648I-1025J1024D01*
G01Y136198D01*
G03X1188225Y137310I-1572J1D01*
G01X1187635Y137899D01*
G01X1196000Y133750D02*
G03X1197250Y136768I-3018J3018D01*
G01Y141150D01*
G03X1196790Y142262I-1572J1D01*
G01X1196200Y142851D01*
G01X1204449Y133680D02*
X1205037Y134269D01*
G03X1205589Y135600I-1331J1332D01*
G01Y141304D01*
X1204791Y142102D01*
Y155730D01*
X1203791Y156730D01*
G01X1192945Y834551D02*
X1191751Y833356D01*
G03X1191520Y832800I556J-557D01*
G01Y831820D01*
G03X1191869Y830976I1193J-1D01*
G01X1192545Y830301D01*
G01X1180347Y834551D02*
X1179153Y833356D01*
G03X1178922Y832800I556J-557D01*
G01Y831700D01*
G02Y831686I-2224J-7D01*
G03X1179177Y831072I869J1D01*
G01X1179947Y830301D01*
G01X1188945Y834551D02*
X1190054Y833442D01*
G02X1190320Y832800I-642J-642D01*
G01Y831820D01*
G02X1189935Y830892I-1313J1D01*
G01X1189345Y830301D01*
G01X1192520Y887970D02*
Y885151D01*
G02X1191851Y883152I-3325J1D01*
G03X1191546Y882416I736J-736D01*
G01Y841428D01*
G03X1192945Y838051I4776J0D01*
G01X1179922Y887970D02*
Y885151D01*
G02X1179253Y883152I-3325J1D01*
G03X1178948Y882416I736J-736D01*
G01Y841428D01*
G03X1180347Y838051I4776J0D01*
G01X1189371Y887970D02*
Y885151D01*
G03X1190033Y883160I3325J0D01*
G02X1190345Y882407I-753J-753D01*
G01Y841431D01*
G02X1188945Y838051I-4780J0D01*
G01X1212748Y130065D02*
X1213629Y129183D01*
G02X1214161Y127900I-1283J-1284D01*
G01X1214160D01*
X1214161Y127899D01*
Y106123D01*
G03X1214977Y104150I2788J-2D01*
G01X1215452Y103675D01*
G02X1215927Y102528I-1147J-1147D01*
G01Y99633D01*
G02X1215478Y98549I-1533J0D01*
G01X1214778Y97849D01*
G02X1214769Y97840I-726J717D01*
G02X1214056Y97550I-713J731D01*
G01X1213860D01*
G02X1213377Y97750I0J683D01*
G02X1213128Y98351I601J601D01*
G01Y99725D01*
G01X1216080Y94213D02*
X1216081Y94214D01*
Y97106D01*
G02X1216327Y97700I840J0D01*
G03X1217127Y99633I-1933J1932D01*
G01Y102530D01*
G03X1216301Y104524I-2820J0D01*
G01X1215826Y104999D01*
G02X1215361Y106122I1123J1123D01*
G01Y127900D01*
G02X1215908Y129222I1869J1D01*
G01X1216752Y130065D01*
G01X1233797Y94213D02*
Y97106D01*
G02X1234043Y97700I840J0D01*
G03X1234843Y99633I-1933J1932D01*
G01Y102528D01*
G03X1234071Y104469I-2822J1D01*
G03X1234017Y104524I-2041J-1950D01*
G01X1233542Y104999D01*
G02X1233373Y105196I1205J1205D01*
G02X1233043Y106204I1374J1008D01*
G01Y128300D01*
G02X1234309Y130362I2312J0D01*
G01X1233797Y79252D02*
Y82145D01*
G02X1234043Y82739I840J0D01*
G03X1234843Y84672I-1933J1932D01*
G01Y87114D01*
G02X1235500Y88700I2243J0D01*
G01X1240679Y93879D01*
G03X1241800Y96585I-2706J2706D01*
G01Y128200D01*
G02X1243000Y130250I2351J0D01*
G01X1224939Y94213D02*
Y97106D01*
G02X1225185Y97700I840J0D01*
G03X1225985Y99633I-1933J1932D01*
G01Y102528D01*
G03X1225213Y104469I-2822J1D01*
G03X1225159Y104524I-2041J-1950D01*
G01X1224684Y104999D01*
G02X1224515Y105196I1205J1205D01*
G02X1224185Y106204I1374J1008D01*
G01Y128500D01*
G02X1225448Y130359I2000J0D01*
G01X1230844Y99725D02*
Y98351D01*
G03X1232200Y97600I860J-48D01*
G03X1232485Y97840I-1258J1783D01*
G03X1232494Y97849I-717J726D01*
G01X1233194Y98549D01*
G03X1233643Y99633I-1084J1084D01*
G01Y102528D01*
G03X1233168Y103675I-1622J0D01*
G01X1232687Y104156D01*
G02X1232404Y104486I2004J2005D01*
G02X1231843Y106204I2343J1716D01*
G01X1231842D01*
X1231843Y106205D01*
Y128300D01*
G03X1230809Y130362I-2573J0D01*
G01X1230844Y84764D02*
Y83390D01*
G03X1231093Y82789I850J0D01*
G03X1231576Y82589I483J483D01*
G01X1231772D01*
G03X1232485Y82879I0J1021D01*
G03X1232494Y82888I-717J726D01*
G01X1233194Y83588D01*
G03X1233643Y84672I-1084J1084D01*
G01Y87115D01*
G02X1234651Y89549I3443J0D01*
G01X1239830Y94728D01*
G03X1240600Y96585I-1856J1858D01*
G01Y128200D01*
G03X1239500Y130250I-2460J0D01*
G01X1221986Y99725D02*
Y98351D01*
G03X1222235Y97750I850J0D01*
G03X1222718Y97550I483J483D01*
G01X1222914D01*
G03X1223627Y97840I0J1021D01*
G03X1223636Y97849I-717J726D01*
G01X1224336Y98549D01*
G03X1224785Y99633I-1084J1084D01*
G01Y102528D01*
G03X1224310Y103675I-1622J0D01*
G01X1223829Y104156D01*
G02X1223546Y104486I2004J2005D01*
G02X1222985Y106204I2343J1716D01*
G01X1222984D01*
X1222985Y106205D01*
Y128500D01*
G03X1221948Y130359I-2185J0D01*
G01X1234309Y133862D02*
G02X1233259Y136397I2535J2535D01*
G01Y140762D01*
G02X1233790Y142044I1813J0D01*
G01X1234209Y142463D01*
G01X1243000Y133750D02*
X1242516Y134235D01*
G02X1241950Y135600I1365J1366D01*
G01Y136150D01*
G02X1242481Y137432I1813J0D01*
G01X1242900Y137851D01*
G01X1225448Y133859D02*
X1224964Y134344D01*
G02X1224398Y135709I1365J1366D01*
G01Y136259D01*
G02X1224929Y137541I1813J0D01*
G01X1225348Y137960D01*
G01X1230809Y133862D02*
G03X1232059Y136880I-3018J3018D01*
G01Y140762D01*
G03X1231599Y141874I-1572J1D01*
G01X1231009Y142463D01*
G01X1239500Y133750D02*
X1240326Y134575D01*
G03X1240750Y135600I-1025J1024D01*
G01Y136150D01*
G03X1240290Y137262I-1572J1D01*
G01X1239700Y137851D01*
G01X1221948Y133859D02*
X1222774Y134684D01*
G03X1223198Y135709I-1025J1024D01*
G01Y136259D01*
G03X1222738Y137371I-1572J1D01*
G01X1222148Y137960D01*
G01X1237040Y834551D02*
X1235846Y833356D01*
G03X1235615Y832800I556J-557D01*
G01Y831844D01*
G03X1235981Y830959I1251J-1D01*
G01X1236640Y830301D01*
G01X1224441Y834551D02*
Y834549D01*
X1223248Y833356D01*
G03X1223017Y832800I556J-557D01*
G01Y831817D01*
G03X1223364Y830979I1185J0D01*
G01X1224042Y830301D01*
G01X1233040Y834551D02*
X1234149Y833442D01*
G02X1234415Y832800I-642J-642D01*
G01Y831800D01*
G02X1234044Y830906I-1265J1D01*
G01X1233440Y830301D01*
G01X1220441Y834551D02*
X1220442D01*
X1221551Y833442D01*
G02X1221817Y832800I-642J-642D01*
G01Y831817D01*
G02X1221434Y830894I-1306J1D01*
G01X1220842Y830301D01*
G01X1236615Y887970D02*
Y885151D01*
G02X1235946Y883152I-3325J1D01*
G03X1235641Y882416I736J-736D01*
G01Y841428D01*
G03X1237040Y838051I4776J0D01*
G01X1224016Y887970D02*
Y885152D01*
X1224017Y885151D01*
G02X1223348Y883152I-3325J1D01*
G03X1223043Y882416I736J-736D01*
G01Y841426D01*
G03X1224441Y838051I4773J0D01*
G01X1233465Y887970D02*
Y885152D01*
X1233466Y885151D01*
G03X1234128Y883160I3325J0D01*
G02X1234440Y882407I-753J-753D01*
G01Y841431D01*
G02X1233040Y838051I-4780J0D01*
G01X1220867Y887970D02*
Y885152D01*
X1220868Y885151D01*
G03X1221530Y883160I3325J0D01*
G02X1221842Y882407I-753J-753D01*
G01Y841431D01*
G02X1220443Y838052I-4778J-1D01*
G01X1220441Y838051D01*
G01X1253719Y129845D02*
X1252812Y128937D01*
G03X1252299Y127700I1237J-1238D01*
G01Y119051D01*
X1247062Y113814D01*
Y71123D01*
X1260227Y57958D01*
G02X1260820Y56526I-1433J-1432D01*
G01Y55444D01*
G02X1259804Y52989I-3472J-1D01*
G01X1259633Y52818D01*
G03X1259534Y52700I592J-597D01*
G03X1259428Y52486I693J-476D01*
G03X1259387Y52224I799J-259D01*
G01Y49331D01*
G01X1249679Y129845D02*
X1250586Y128937D01*
G02X1251099Y127700I-1237J-1238D01*
G01Y119549D01*
X1245861Y114311D01*
Y113317D01*
X1245862Y113316D01*
Y70625D01*
X1259378Y57109D01*
G02X1259620Y56526I-583J-584D01*
G01Y55443D01*
X1259619Y55444D01*
G02X1258955Y53838I-2272J-1D01*
G01X1258084Y52967D01*
G02X1258075Y52958I-726J717D01*
G02X1257362Y52668I-713J731D01*
G01X1257166D01*
G02X1256683Y52868I0J683D01*
G02X1256434Y53469I601J601D01*
G01X1256435Y53470D01*
Y54843D01*
G01X1265997Y130172D02*
G02X1267400Y127900I-1138J-2272D01*
G01X1267401Y127899D01*
Y120752D01*
G02X1267242Y120370I-540J0D01*
G01X1257991Y111119D01*
G03X1257482Y109889I1230J-1229D01*
G01Y105872D01*
G03X1257539Y105428I1744J-2D01*
G03X1257553Y105380I2795J789D01*
G03X1257995Y104486I2786J821D01*
G03X1258278Y104156I2287J1675D01*
G01X1258759Y103675D01*
G02X1259234Y102528I-1147J-1147D01*
G01Y99633D01*
G02X1258785Y98549I-1533J0D01*
G01X1258085Y97849D01*
G02X1258076Y97840I-726J717D01*
G02X1257363Y97550I-713J731D01*
G01X1257167D01*
G02X1256684Y97750I0J683D01*
G02X1256435Y98351I601J601D01*
G01Y99725D01*
G01X1270005Y130171D02*
G03X1268601Y127902I1132J-2269D01*
G01Y120751D01*
G02X1268091Y119521I-1740J1D01*
G01X1258840Y110270D01*
G03X1258682Y109889I380J-381D01*
G01Y105873D01*
G03X1258704Y105720I543J0D01*
G01X1258705D01*
G03X1258964Y105196I1634J482D01*
G03X1259133Y104999I1374J1008D01*
G01X1259608Y104524D01*
G02X1259662Y104469I-1987J-2005D01*
G02X1260434Y102528I-2050J-1940D01*
G01Y99633D01*
G02X1259634Y97700I-2733J-1D01*
G03X1259388Y97106I594J-594D01*
G01Y94214D01*
X1259387Y94213D01*
G01X1262044Y130169D02*
G03X1260796Y127944I1359J-2225D01*
G01Y121755D01*
G02X1259853Y119479I-3218J0D01*
G01X1252930Y112556D01*
G03X1252100Y110553I2002J-2003D01*
G01Y96576D01*
G03X1252826Y94824I2477J0D01*
G01X1256503Y91147D01*
G03X1258367Y90375I1864J1864D01*
G01X1264717D01*
G02X1269292Y85800I0J-4575D01*
G01Y84672D01*
G02X1268492Y82739I-2733J-1D01*
G03X1268246Y82145I594J-594D01*
G01Y79252D01*
G01X1277365Y130072D02*
G03X1276100Y127700I1591J-2372D01*
G01Y118559D01*
G02X1274361Y114361I-5937J0D01*
G01X1270209Y110209D01*
G03X1269292Y107996I2212J-2213D01*
G01Y99633D01*
G02X1268492Y97700I-2733J-1D01*
G03X1268246Y97106I594J-594D01*
G01Y94213D01*
G01X1286643Y129980D02*
G03X1285449Y127836I1328J-2144D01*
G01Y120244D01*
G02X1283826Y116326I-5541J0D01*
G01X1276912Y109412D01*
G03X1276350Y108056I1355J-1356D01*
G01Y106204D01*
G03X1276849Y104999I1704J0D01*
G01X1277324Y104524D01*
G02X1277378Y104469I-1987J-2005D01*
G02X1278150Y102528I-2050J-1940D01*
G01Y99633D01*
G02X1277350Y97700I-2733J-1D01*
G03X1277104Y97106I594J-594D01*
G01Y94213D01*
G01X1296117Y129877D02*
G03X1294916Y127551I1652J-2326D01*
G01Y106893D01*
G02X1293307Y103009I-5492J0D01*
G01X1278894Y88596D01*
G03X1278151Y86800I1797J-1795D01*
G01X1278150Y86801D01*
Y84672D01*
G02X1277350Y82739I-2733J-1D01*
G03X1277104Y82145I594J-594D01*
G01Y79252D01*
G01X1258544Y130169D02*
G02X1259596Y127944I-1827J-2225D01*
G01Y121755D01*
G02X1259004Y120328I-2018J1D01*
G01X1252081Y113405D01*
G03X1250900Y110553I2851J-2851D01*
G01Y96576D01*
G03X1251977Y93975I3677J-1D01*
G01X1255654Y90298D01*
G03X1258367Y89175I2712J2714D01*
G01X1264717D01*
G02X1268092Y85800I0J-3375D01*
G01Y84672D01*
G02X1267643Y83588I-1533J0D01*
G01X1266943Y82888D01*
G02X1266934Y82879I-726J717D01*
G02X1266221Y82589I-713J731D01*
G01X1266025D01*
G02X1265542Y82789I0J683D01*
G02X1265293Y83390I601J601D01*
G01Y84764D01*
G01X1273865Y130072D02*
G02X1274900Y127700I-2201J-2372D01*
G01Y118560D01*
G02X1273512Y115210I-4737J0D01*
G01X1269360Y111058D01*
G03X1268092Y107996I3061J-3061D01*
G01Y99632D01*
X1268091Y99633D01*
G02X1267642Y98549I-1532J0D01*
G03X1267606Y98512I1445J-1441D01*
G01X1266943Y97849D01*
G02X1266934Y97840I-726J717D01*
G02X1266221Y97550I-713J731D01*
G01X1266025D01*
G02X1265542Y97750I0J683D01*
G02X1265293Y98351I601J601D01*
G01Y99725D01*
G01X1283143Y129980D02*
G02X1284249Y127836I-1525J-2144D01*
G01Y120244D01*
G02X1282977Y117175I-4340J1D01*
G01X1276063Y110261D01*
G03X1275150Y108056I2204J-2204D01*
G01Y106204D01*
G03X1275711Y104486I2904J-2D01*
G03X1275994Y104156I2287J1675D01*
G01X1276475Y103675D01*
G02X1276950Y102528I-1147J-1147D01*
G01Y99633D01*
G02X1276501Y98549I-1533J0D01*
G01X1275801Y97849D01*
G02X1275792Y97840I-726J717D01*
G02X1275079Y97550I-713J731D01*
G01X1274883D01*
G02X1274400Y97750I0J683D01*
G02X1274151Y98351I601J601D01*
G01Y99725D01*
G01X1292617Y129877D02*
G02X1293716Y127551I-1912J-2326D01*
G01Y106893D01*
G02X1292458Y103858I-4292J1D01*
G01X1278044Y89445D01*
G03X1276950Y86800I2647J-2643D01*
G01Y84672D01*
G02X1276501Y83588I-1533J0D01*
G01X1275801Y82888D01*
G02X1275792Y82879I-726J717D01*
G02X1275079Y82589I-713J731D01*
G01X1274883D01*
G02X1274400Y82789I0J683D01*
G02X1274151Y83390I601J601D01*
G01Y84764D01*
G01X1262044Y133669D02*
G02X1260994Y136204I2535J2535D01*
G01Y144069D01*
G02X1261525Y145351I1813J0D01*
G01X1261944Y145770D01*
G01X1277365Y133572D02*
G02X1276315Y135422I1105J1850D01*
G01Y135972D01*
G02X1276846Y137254I1813J0D01*
G01X1277265Y137673D01*
G01X1258544Y133669D02*
G03X1259794Y136687I-3018J3018D01*
G01Y144069D01*
G03X1259334Y145181I-1572J1D01*
G01X1258744Y145770D01*
G01X1273865Y133572D02*
G03X1275115Y135422I-744J1850D01*
G01Y135972D01*
G03X1274655Y137084I-1572J1D01*
G01X1274065Y137673D01*
G01X1274835Y834551D02*
X1273641Y833356D01*
G03X1273410Y832800I556J-557D01*
G01Y831844D01*
G03X1273776Y830959I1251J-1D01*
G01X1274435Y830301D01*
G01X1262237Y834551D02*
X1261043Y833356D01*
G03X1260812Y832800I556J-557D01*
G01Y831947D01*
G03X1261251Y830887I1499J0D01*
G01X1261837Y830301D01*
G01X1249638Y834551D02*
Y834549D01*
X1248445Y833356D01*
G03X1248214Y832800I556J-557D01*
G01Y831914D01*
G03X1248630Y830910I1420J0D01*
G01X1249239Y830301D01*
G01X1270835Y834551D02*
X1271944Y833442D01*
G02X1272210Y832800I-642J-642D01*
G01Y831800D01*
G02X1271839Y830906I-1265J1D01*
G01X1271235Y830301D01*
G01X1258237Y834551D02*
X1259346Y833442D01*
G02X1259612Y832800I-642J-642D01*
G01Y831912D01*
G02X1259162Y830827I-1535J1D01*
G01X1258637Y830301D01*
G01X1245638Y834551D02*
X1245639D01*
X1246748Y833442D01*
G02X1247014Y832800I-642J-642D01*
G01Y831914D01*
G02X1246563Y830825I-1540J0D01*
G01X1246039Y830301D01*
G01X1274410Y887970D02*
Y885151D01*
G02X1273741Y883152I-3325J1D01*
G03X1273436Y882416I736J-736D01*
G01Y841428D01*
G03X1274835Y838051I4776J0D01*
G01X1261812Y887970D02*
Y885151D01*
G02X1261143Y883152I-3325J1D01*
G03X1260838Y882416I736J-736D01*
G01Y841428D01*
G03X1262237Y838051I4776J0D01*
G01X1249213Y887970D02*
Y885152D01*
X1249214Y885151D01*
G02X1248545Y883152I-3325J1D01*
G03X1248240Y882416I736J-736D01*
G01Y841426D01*
G03X1249638Y838051I4773J0D01*
G01X1271260Y887970D02*
Y885152D01*
X1271261Y885151D01*
G03X1271923Y883160I3325J0D01*
G02X1272235Y882407I-753J-753D01*
G01Y841431D01*
G02X1270835Y838051I-4780J0D01*
G01X1258662Y887970D02*
Y885152D01*
X1258663Y885151D01*
G03X1259325Y883160I3325J0D01*
G02X1259637Y882407I-753J-753D01*
G01Y841431D01*
G02X1258237Y838051I-4780J0D01*
G01X1246063Y887970D02*
Y885153D01*
X1246065Y885151D01*
G03X1246727Y883160I3325J0D01*
G02X1247039Y882407I-753J-753D01*
G01Y841431D01*
G02X1245640Y838052I-4778J-1D01*
G01X1245638Y838051D01*
G01X1286643Y133480D02*
G02X1285593Y136015I2535J2535D01*
G01Y139880D01*
G02X1286124Y141162I1813J0D01*
G01X1286543Y141581D01*
G01X1296117Y133377D02*
X1295633Y133862D01*
G02X1295067Y135227I1365J1366D01*
G01Y135777D01*
G02X1295598Y137059I1813J0D01*
G01X1296017Y137478D01*
G01X1283143Y133480D02*
G03X1284393Y136498I-3018J3018D01*
G01Y139880D01*
G03X1283933Y140992I-1572J1D01*
G01X1283343Y141581D01*
G01X1292617Y133377D02*
X1293443Y134202D01*
G03X1293867Y135227I-1025J1024D01*
G01Y135777D01*
G03X1293407Y136889I-1572J1D01*
G01X1292817Y137478D01*
G01X1312630Y834551D02*
Y834549D01*
X1311437Y833356D01*
G03X1311206Y832800I556J-557D01*
G01Y831949D01*
G03X1311647Y830886I1504J1D01*
G01X1312231Y830301D01*
G01X1287433Y834551D02*
X1286239Y833356D01*
G03X1286008Y832800I556J-557D01*
G01Y831799D01*
G02Y831748I-2465J-25D01*
G03X1286306Y831027I1019J-1D01*
G01X1287033Y830301D01*
G01X1308630Y834551D02*
X1308631D01*
X1309740Y833442D01*
G02X1310006Y832800I-642J-642D01*
G01Y831900D01*
G02X1309565Y830835I-1506J0D01*
G01X1309031Y830301D01*
G01X1283433Y834551D02*
X1284542Y833442D01*
G02X1284808Y832800I-642J-642D01*
G01Y831800D01*
G02X1284437Y830906I-1265J1D01*
G01X1283833Y830301D01*
G01X1312205Y887970D02*
Y885152D01*
X1312206Y885151D01*
G02X1311537Y883152I-3325J1D01*
G03X1311232Y882416I736J-736D01*
G01Y841426D01*
G03X1312630Y838051I4773J0D01*
G01X1287008Y887970D02*
Y885151D01*
G02X1286339Y883152I-3325J1D01*
G03X1286034Y882416I736J-736D01*
G01Y841428D01*
G03X1287433Y838051I4776J0D01*
G01X1309056Y887970D02*
Y885152D01*
X1309057Y885151D01*
G03X1309719Y883160I3325J0D01*
G02X1310031Y882407I-753J-753D01*
G01Y841431D01*
G02X1308632Y838052I-4778J-1D01*
G01X1308630Y838051D01*
G01X1283859Y887970D02*
Y885151D01*
G03X1284521Y883160I3325J0D01*
G02X1284833Y882407I-753J-753D01*
G01Y841431D01*
G02X1283433Y838051I-4780J0D01*
G01X1337827Y834551D02*
X1336633Y833356D01*
G03X1336402Y832800I556J-557D01*
G01Y832046D01*
G03X1336911Y830817I1738J0D01*
G01X1337427Y830301D01*
G01X1325229Y834551D02*
X1324035Y833356D01*
G03X1323804Y832800I556J-557D01*
G01Y831700D01*
G02Y831692I-2224J-4D01*
G03X1324063Y831067I884J0D01*
G01X1324829Y830301D01*
G01X1333827Y834551D02*
X1334936Y833442D01*
G02X1335202Y832800I-642J-642D01*
G01Y832046D01*
G02X1334658Y830731I-1859J-1D01*
G01X1334227Y830301D01*
G01X1321229Y834551D02*
X1322338Y833442D01*
G02X1322604Y832800I-642J-642D01*
G01Y831700D01*
G02X1322304Y830976I-1024J0D01*
G01X1321629Y830301D01*
G01X1337402Y887970D02*
Y885151D01*
G02X1336733Y883152I-3325J1D01*
G03X1336428Y882416I736J-736D01*
G01Y841428D01*
G03X1337827Y838051I4776J0D01*
G01X1324804Y887970D02*
Y885151D01*
G02X1324135Y883152I-3325J1D01*
G03X1323830Y882416I736J-736D01*
G01Y841428D01*
G03X1325229Y838051I4776J0D01*
G01X1334252Y887970D02*
Y885152D01*
X1334253Y885151D01*
G03X1334915Y883160I3325J0D01*
G02X1335227Y882407I-753J-753D01*
G01Y841431D01*
G02X1333827Y838051I-4780J0D01*
G01X1321654Y887970D02*
Y885152D01*
X1321655Y885151D01*
G03X1322317Y883160I3325J0D01*
G02X1322629Y882407I-753J-753D01*
G01Y841431D01*
G02X1321229Y838051I-4780J0D01*
G01X1350425Y834551D02*
X1349402Y833527D01*
G03X1349000Y832558I969J-970D01*
G01Y831800D01*
G03X1349335Y830991I1144J0D01*
G01X1350025Y830301D01*
G01X1346425Y834551D02*
X1347364Y833613D01*
G02X1347800Y832559I-1054J-1053D01*
G01Y831800D01*
G02X1347429Y830906I-1265J1D01*
G01X1346825Y830301D01*
G01X1350000Y887970D02*
Y885151D01*
G02X1349331Y883152I-3325J1D01*
G03X1349026Y882416I736J-736D01*
G01Y841428D01*
G03X1350425Y838051I4776J0D01*
G01X1346851Y887970D02*
Y885151D01*
G03X1347513Y883160I3325J0D01*
G02X1347825Y882407I-753J-753D01*
G01Y841431D01*
G02X1346425Y838051I-4780J0D01*
G54D17*
X21900Y192300D03*
X21800Y180800D03*
X23100Y216900D03*
X31500D03*
X38500Y273200D03*
X41500Y261700D03*
X43900Y299900D03*
X54600Y321600D03*
X61799Y372557D03*
X42900Y763200D03*
X67600Y327300D03*
X84700Y328200D03*
X81300D03*
X74000Y572200D03*
X84000Y570700D03*
X80500D03*
X100900Y190600D03*
X130051Y648346D03*
X133299Y574920D03*
X190520Y834501D03*
X194520D03*
X222500Y510200D03*
X226000D03*
X221000Y525700D03*
X207118Y834501D03*
X203118D03*
X219717D03*
X215717D03*
X232315D03*
X228315D03*
X239600Y146100D03*
X244300Y230200D03*
X259857Y510148D03*
X246500Y517700D03*
X241300Y635600D03*
X266906Y768598D03*
X254362Y834501D03*
X250362D03*
X266961D03*
X262961D03*
X267300Y293200D03*
X297729Y354840D03*
X279559Y834501D03*
X275559D03*
X329241Y325130D03*
X301500Y483500D03*
X313354Y834501D03*
X317354D03*
X329953D03*
X325953D03*
X367748D03*
X363748D03*
X342551D03*
X338551D03*
X351150D03*
X355150D03*
X389796D03*
X385796D03*
X398394D03*
X402394D03*
X410993D03*
X414993D03*
X423591D03*
X427591D03*
X459071Y118741D03*
X480406Y820598D03*
X505477Y291940D03*
X525409Y328741D03*
X542120Y215005D03*
X544851Y834501D03*
X548851D03*
X557449D03*
X561449D03*
X570048D03*
X604170Y330540D03*
X574048Y834501D03*
X586646D03*
X582646D03*
X599245D03*
X595245D03*
X619363Y228308D03*
X609500Y353583D03*
X611843Y834501D03*
X607843D03*
X624442D03*
X620442D03*
X637040D03*
X633040D03*
X659087D03*
X655087D03*
X671685D03*
X667685D03*
X684284D03*
X680284D03*
X696882D03*
X692882D03*
X724379D03*
X728379D03*
X736977D03*
X740977D03*
X749576D03*
X753576D03*
X762174D03*
X766174D03*
X774772D03*
X778772D03*
X787370D03*
X791370D03*
X799969D03*
X803969D03*
X812567D03*
X816567D03*
X837764D03*
X849906Y797598D03*
X841764Y834501D03*
X850362D03*
X854362D03*
X896000Y2700D03*
X900522Y13166D03*
X905500Y331200D03*
X1039675Y15287D03*
X1014451Y41506D03*
X1040914Y834501D03*
X1044914D03*
X1053512D03*
X1057512D03*
X1066111D03*
X1070111D03*
X1091307D03*
X1095307D03*
X1103906D03*
X1107906D03*
X1078709D03*
X1082709D03*
X1120504D03*
X1116504D03*
X1129103D03*
X1133103D03*
X1141701D03*
X1145701D03*
X1154299D03*
X1158299D03*
X1176347D03*
X1180347D03*
X1192945D03*
X1188945D03*
X1224441D03*
X1220441D03*
X1237040D03*
X1233040D03*
X1257500Y390200D03*
X1254000D03*
X1249638Y834501D03*
X1245638D03*
X1258237D03*
X1262237D03*
X1274835D03*
X1270835D03*
X1294628Y726067D03*
X1287433Y834501D03*
X1283433D03*
X1312630D03*
X1308630D03*
X1325229D03*
X1321229D03*
X1337827D03*
X1333827D03*
X1346425D03*
X1350425D03*
G54D35*
X25300Y739200D03*
X58300Y327500D03*
X62800Y327200D03*
X64500Y420800D03*
X32000Y473300D03*
X49000D03*
X53200Y466700D03*
X55261Y507441D03*
X51300Y709700D03*
X43300D03*
X57200Y690600D03*
X80300Y259200D03*
X95670Y340811D03*
X91600Y340700D03*
X70591Y363199D03*
X70654Y370860D03*
X80000Y403500D03*
X84274Y399141D03*
X96046Y423330D03*
X92500Y469800D03*
X96700Y469700D03*
X88000Y606900D03*
X72000Y606300D03*
X76000D03*
X66000Y598300D03*
X97500Y631800D03*
X65000Y763100D03*
X108500Y294700D03*
X128180Y311014D03*
X103998Y340850D03*
X99887Y340875D03*
X103617Y332815D03*
X100200Y384900D03*
X100076Y430730D03*
X111500Y457800D03*
X107500D03*
X106900Y732100D03*
X126000Y777300D03*
X151600Y406300D03*
X133000Y457800D03*
X137000D03*
X142000Y453300D03*
X160000Y774800D03*
X164500Y812800D03*
X196018Y196356D03*
X191018D03*
X197841Y430442D03*
X184116Y458610D03*
X192733Y458132D03*
X188150Y458505D03*
X172800Y457800D03*
X197500Y570332D03*
X191500Y598300D03*
X195500Y590800D03*
Y583300D03*
X199500Y695800D03*
X167200Y719700D03*
X199500Y751300D03*
X171700Y757700D03*
X224900Y109400D03*
X224600Y120100D03*
X207369Y147784D03*
X220969Y434972D03*
X209400Y450100D03*
X213500D03*
X225000Y518400D03*
X229000Y525800D03*
X201500Y570332D03*
X226200Y572462D03*
X204000Y733800D03*
Y789300D03*
X261200Y101900D03*
X235505Y144662D03*
X236331Y230380D03*
X258900Y293600D03*
X263000Y293400D03*
X266729Y345940D03*
X244900Y430900D03*
X262900Y430400D03*
X257500Y447538D03*
X253400Y447500D03*
X242500Y525800D03*
X253500D03*
X258000Y517800D03*
X245300Y635700D03*
X277500Y133800D03*
X272900Y293300D03*
X299639Y332701D03*
X294406Y719698D03*
X290406D03*
X286406D03*
X282406D03*
X298406D03*
X278406Y768698D03*
X274406D03*
X282478Y768731D03*
X316646Y293575D03*
X302700Y294562D03*
X320662Y293590D03*
X315300Y337300D03*
X310406Y719698D03*
X306406D03*
X302406D03*
X314500Y719800D03*
X355200Y328800D03*
X466000Y65500D03*
X457700D03*
X474400D03*
X500238Y130550D03*
X478800Y119300D03*
X477466Y182820D03*
X471681Y306512D03*
X476200Y359600D03*
X480700Y397600D03*
X499906Y771698D03*
X495906D03*
X491906Y820698D03*
X487906D03*
X495978Y820731D03*
X504248Y130550D03*
X528709Y291483D03*
X523906Y771698D03*
X507906D03*
X519906D03*
X503906D03*
X515906D03*
X511906D03*
X528100Y771600D03*
X558263Y133520D03*
X570100Y202300D03*
X541681Y291076D03*
X563531Y373380D03*
X558531Y380880D03*
X631363Y228408D03*
X623363D03*
X608090Y330660D03*
X632000Y333900D03*
X636000D03*
X617000Y375900D03*
X623000D03*
X640000Y333900D03*
X718302Y3324D03*
X736500Y24300D03*
X713375Y24502D03*
X724820Y15040D03*
X720700Y14970D03*
X728960Y15130D03*
X720840Y56440D03*
X742700Y11600D03*
X769400Y104200D03*
X838252Y14300D03*
X834252D03*
X830252D03*
X826252D03*
X822252D03*
X854400D03*
X846252D03*
X842252D03*
X873406Y748624D03*
X869406Y748698D03*
X865406D03*
X861406Y797698D03*
X857406D03*
X865478Y797731D03*
X891301Y13177D03*
X877406Y748698D03*
X893406D03*
X889406D03*
X885406D03*
X881406D03*
X897600Y748600D03*
X938000Y23300D03*
X911000Y89800D03*
X915500D03*
X920000D03*
X933500D03*
X929000D03*
X924500D03*
X938000D03*
X956000D03*
X1005176Y41562D03*
X1000683Y45750D03*
X1010676Y41562D03*
X1068809Y13342D03*
X1249679Y129895D03*
X1253719D03*
X1274500Y338800D03*
X1278500D03*
X1265500Y390300D03*
X1269500D03*
X1273500D03*
X1261500D03*
X1304000Y12800D03*
Y36300D03*
Y59800D03*
Y83300D03*
X1311000Y278800D03*
X1282500Y338800D03*
X1286500D03*
X1290500D03*
X1294500D03*
X1302500D03*
X1298500D03*
X1310128Y677167D03*
X1306128Y726167D03*
X1302128D03*
X1310200Y726200D03*
X1335100Y141970D03*
X1338128Y677167D03*
X1322128D03*
X1334128D03*
X1318128D03*
X1330128D03*
X1314128D03*
X1326128D03*
X1342300Y676800D03*
X1322400Y669600D03*
X1378134Y173509D03*
X1359124Y171420D03*
X1359011Y178984D03*
G54D119*
X259300Y635900D03*
G54D128*
X478719Y308208D03*
X486219Y312083D03*
X478719Y315958D03*
X733382Y3881D03*
Y-3869D03*
X740882Y6D03*
X873250Y22375D03*
Y14625D03*
X880750Y18500D03*
X1306970Y139185D03*
Y131435D03*
X1314470Y135310D03*
G54D44*
X54378Y237402D03*
G54D26*
X31500Y441800D03*
Y434200D03*
X31000Y423800D03*
Y416200D03*
X37300Y712200D03*
Y704600D03*
X124051Y647136D03*
Y654736D03*
X153421Y301558D03*
Y309158D03*
X161400Y301600D03*
Y309200D03*
X276300Y621600D03*
Y629200D03*
Y644100D03*
Y651700D03*
X335000Y179700D03*
Y187300D03*
X343000Y179700D03*
Y187300D03*
X589500Y356300D03*
Y348700D03*
X574000Y356300D03*
Y348700D03*
X581700Y356300D03*
Y348700D03*
X660263Y228808D03*
Y236408D03*
X704700Y278200D03*
Y285800D03*
X732600Y238700D03*
X724600D03*
X716600D03*
X708600D03*
X732600Y246300D03*
X724600D03*
X716600D03*
X708600D03*
X712300Y278200D03*
X719900D03*
X727500D03*
X735100D03*
X712300Y285800D03*
X719900D03*
X727500D03*
X735100D03*
X748237Y205992D03*
Y198392D03*
X923900Y47800D03*
Y55400D03*
X971400Y39400D03*
Y31800D03*
Y48800D03*
Y56400D03*
X979400Y39400D03*
Y31800D03*
Y48800D03*
Y56400D03*
X1177000Y228600D03*
Y221000D03*
X1168000Y228600D03*
Y221000D03*
X1177000Y267200D03*
Y274800D03*
X1168000Y267200D03*
Y274800D03*
X1213000Y228600D03*
Y221000D03*
X1204000Y228600D03*
Y221000D03*
X1195000Y228600D03*
Y221000D03*
X1186000Y228600D03*
Y221000D03*
X1212500Y267200D03*
Y274800D03*
X1195000Y267200D03*
Y274800D03*
X1204000Y267200D03*
Y274800D03*
X1186000Y267200D03*
Y274800D03*
G54D53*
X65700Y430500D03*
Y438500D03*
X47200Y439500D03*
X54800D03*
X60200Y572500D03*
Y564500D03*
X73300Y430500D03*
Y438500D03*
X67800Y572500D03*
Y564500D03*
X120700Y203500D03*
X128300D03*
X120700Y195500D03*
X128300D03*
X120700Y211500D03*
X128300D03*
X127300Y277400D03*
X119700D03*
X150600Y266100D03*
X143000D03*
X229200Y177500D03*
Y169000D03*
Y186000D03*
X231200Y509500D03*
X236800Y177500D03*
X248700Y171922D03*
X256300D03*
X236800Y169000D03*
X248700Y179722D03*
X256300D03*
X248700Y187722D03*
X256300D03*
X236800Y186000D03*
X238800Y509500D03*
X261600Y606400D03*
X254000D03*
X261600Y614400D03*
X254000D03*
X261600Y622400D03*
X254000D03*
X304639Y326201D03*
X312239D03*
X510677Y293740D03*
X518277D03*
X570063Y253608D03*
Y245608D03*
X569200Y375000D03*
X558331Y375080D03*
X550731D03*
X595063Y264108D03*
X602663D03*
X577663Y253608D03*
Y245608D03*
X576800Y375000D03*
X1346300Y240000D03*
X1338700D03*
X1359681Y240509D03*
X1367281D03*
X1359740Y248121D03*
X1367340D03*
G54D71*
X91750Y600560D03*
Y595440D03*
X85250D03*
Y598000D03*
Y600560D03*
X105896Y362064D03*
Y359504D03*
Y356944D03*
X112396D03*
Y362064D03*
X297512Y470240D03*
Y472800D03*
Y475360D03*
X291012D03*
Y470240D03*
X743250Y28640D03*
Y33760D03*
X749750D03*
Y31200D03*
Y28640D03*
G54D62*
X60300Y717400D03*
G54D164*
X1337000Y263250D03*
G54D137*
X603363Y221358D03*
G54D146*
X700939Y212618D03*
X738439D03*
G54D155*
X943111Y5908D03*
X935236D03*
X927361D03*
X919486D03*
X911616D03*
X943111Y13778D03*
X935236D03*
X927361D03*
X919486D03*
X911616D03*
X958856Y5908D03*
X950986D03*
X958856Y13778D03*
X950986D03*
G54D80*
X121504Y248031D03*
G54D174*
G01X23100Y216950D02*
Y210050D01*
X11700Y198650D01*
Y139700D01*
X31977Y119423D01*
Y116614D01*
G01Y126614D02*
X29486D01*
X13500Y142600D01*
Y197700D01*
X31500Y215700D01*
Y216950D01*
G01X23100D02*
X27050D01*
X27300Y217200D01*
G01X31500Y216950D02*
X34894Y220344D01*
Y233906D01*
X14800Y254000D01*
Y295401D01*
X20637Y301238D01*
X37138D01*
X38800Y302900D01*
G01X104808Y405542D02*
Y410691D01*
X102373Y413126D01*
X73488D01*
X67525Y407163D01*
X27261D01*
X15638Y418786D01*
Y491138D01*
X48700Y524200D01*
Y536590D01*
X64448Y552338D01*
X75338D01*
X77500Y554500D01*
G01X23720Y472640D02*
X17063Y465983D01*
Y419377D01*
X27478Y408962D01*
X33468D01*
X37500Y412994D01*
Y414000D01*
G01X29300Y539850D02*
Y536800D01*
X30550Y535550D01*
Y533500D01*
G01X25000Y527062D02*
X24800Y527262D01*
Y540900D01*
G01X31200Y712650D02*
X25200D01*
G01X25300Y739150D02*
X21099D01*
X18800Y736851D01*
Y711800D01*
X24050Y706550D01*
Y691400D01*
G01X21300Y728400D02*
X22300Y729400D01*
X25050D01*
G01X21108Y732713D02*
X21195Y732800D01*
X22300D01*
X22900Y733400D01*
X25050D01*
G01X34831Y727839D02*
X32388Y730281D01*
X29431D01*
X28550Y729400D01*
G01X34300Y732900D02*
X33656Y732256D01*
X29694D01*
X28550Y733400D01*
G01X35300Y738400D02*
X31050Y742650D01*
X25300D01*
G01D02*
X21250D01*
G01X34800Y721900D02*
X33300Y720400D01*
X28550D01*
G01X37800Y745400D02*
X36300Y746900D01*
X28550D01*
G01X29400Y738500D02*
X28750Y739150D01*
X25300D01*
G01X60673Y280483D02*
Y274527D01*
X60872Y274328D01*
G01X53100Y279500D02*
X52600Y280000D01*
Y281653D01*
X54083Y283136D01*
G01X47800Y309400D02*
X50168D01*
X50841Y308727D01*
X54083D01*
G01Y310695D02*
X51049D01*
X49944Y311800D01*
X37400D01*
X35300Y309700D01*
X32770D01*
X31598Y310872D01*
G01X54083Y306758D02*
X50794D01*
X50091Y307461D01*
X47063D01*
X44699Y309825D01*
X38219D01*
X36119Y307725D01*
X32713D01*
X31662Y306674D01*
G01D02*
Y303262D01*
G01X58700Y308600D02*
X58705Y308605D01*
Y315317D01*
G01X61800Y306900D02*
Y309933D01*
X60673Y311060D01*
Y315317D01*
G01X54083Y292979D02*
X49007D01*
X48128Y292100D01*
X46000D01*
G01X45882Y287141D02*
X49751Y291010D01*
X54083D01*
G01X43262Y330307D02*
Y326338D01*
X45050Y324550D01*
Y321400D01*
G01X64610Y315317D02*
Y318355D01*
X65200Y318945D01*
Y324800D01*
X62850Y327150D01*
X62800D01*
G01X54200Y347400D02*
Y342455D01*
X60288Y336367D01*
Y329712D01*
X62800Y327200D01*
Y327150D01*
G01X31598Y310872D02*
Y314598D01*
X31700Y314700D01*
G01X52050Y316100D02*
X54083Y314067D01*
Y312664D01*
G01X62642Y315317D02*
Y322042D01*
X62900Y322300D01*
G01X58300Y327450D02*
X58350D01*
X59922Y325878D01*
Y325278D01*
X62900Y322300D01*
G01X39866Y364307D02*
Y371366D01*
G01X53422Y357864D02*
X51213Y355655D01*
Y351665D01*
X52521Y350357D01*
G01X44866Y364307D02*
Y361141D01*
X46807Y359200D01*
X52086D01*
X53422Y357864D01*
G01X49866Y364307D02*
Y366266D01*
X56500Y372900D01*
G01X59550Y367033D02*
X59357Y367226D01*
Y373649D01*
X57900Y375106D01*
Y382546D01*
X59399Y384045D01*
X64155D01*
X64800Y383400D01*
G01X67093Y354737D02*
X64277D01*
X63500Y353960D01*
G01X61799Y372607D02*
X65164D01*
X65965Y373408D01*
G01Y362838D02*
Y360600D01*
X63398Y358033D01*
X59550D01*
G01X62838Y392392D02*
X61435Y393795D01*
X54613D01*
X49866Y389048D01*
Y384307D01*
G01X32750Y429000D02*
X33651D01*
X35709Y426942D01*
G01D02*
X36651Y426000D01*
X41900D01*
G01X49000Y469400D02*
Y473250D01*
G01D02*
X47850D01*
X45900Y471300D01*
X43060D01*
G01X47734Y465792D02*
Y466112D01*
X49000Y467378D01*
Y469400D01*
G01X32000Y476750D02*
X34075Y474675D01*
X36581D01*
X37218Y474038D01*
X45169D01*
X45531Y474400D01*
G01X32000Y476750D02*
X31700Y477050D01*
Y481100D01*
G01D02*
X32400Y481800D01*
X33900D01*
X37000Y478700D01*
X37940D01*
G01X105045Y503930D02*
X101245D01*
X100067Y502752D01*
X91511D01*
X90408Y501649D01*
X82949D01*
X78336Y497036D01*
X74942D01*
X64825Y486919D01*
Y483319D01*
X63110Y481604D01*
Y474721D01*
X63024Y474321D01*
X62204Y473500D01*
X61550D01*
X60850Y474200D01*
G01X107423Y501955D02*
X102064D01*
X100886Y500777D01*
X92330D01*
X91227Y499674D01*
X83768D01*
X79155Y495061D01*
X75761D01*
X66800Y486100D01*
Y482500D01*
X65085Y480785D01*
Y474514D01*
X64836Y473338D01*
X63023Y471525D01*
X62275D01*
X60850Y470100D01*
G01X53200Y474250D02*
X57300D01*
X57350Y474200D01*
G01X53200Y474250D02*
X51500D01*
X49000Y476750D01*
G01X49691Y479800D02*
X47332D01*
X46632Y480500D01*
X44860D01*
X43060Y478700D01*
G01X49000Y476750D02*
X49691Y477441D01*
Y479800D01*
G01X57350Y474200D02*
Y474981D01*
X60810Y478441D01*
G01X53200Y470150D02*
X57300D01*
X57350Y470100D01*
G01X32000Y473250D02*
X35990D01*
X37940Y471300D01*
G01D02*
X35900D01*
X33900Y469300D01*
G01X31562Y465195D02*
Y464838D01*
X35500Y460900D01*
X38900D01*
X40700Y462700D01*
X47800D01*
X50800Y465700D01*
Y467750D01*
X53200Y470150D01*
G01X31562Y465195D02*
Y472812D01*
X32000Y473250D01*
G01X44000Y466500D02*
X43000Y465500D01*
X40750D01*
X40250Y466000D01*
G01X40500Y471300D02*
Y469300D01*
X43300Y466500D01*
X44000D01*
G01X40500Y478700D02*
Y480750D01*
X41188Y481438D01*
X43422D01*
X44500Y482516D01*
Y484000D01*
G01X50140Y494559D02*
Y494414D01*
X49676Y493950D01*
X46900D01*
G01X52940Y496200D02*
X51218D01*
X50267Y495249D01*
Y494686D01*
X50140Y494559D01*
G01X46900Y493950D02*
X46561D01*
X43046Y497465D01*
G01X58060Y488800D02*
X60560D01*
X60983Y489223D01*
X60987D01*
G01X64000Y490750D02*
X62514D01*
X60987Y489223D01*
G01X61870Y515670D02*
Y511698D01*
X67068Y506500D01*
X70750D01*
G01X55261Y510891D02*
X59280D01*
X59587Y511198D01*
G01X61128Y519646D02*
X60023Y518541D01*
Y511634D01*
X59587Y511198D01*
G01X49691Y479800D02*
X49812Y479921D01*
G01X52940Y488800D02*
Y489810D01*
X52000Y490750D01*
X50140D01*
G01D02*
X47200D01*
X46900Y490450D01*
G01X42534Y490525D02*
X42609Y490450D01*
X46900D01*
G01X58060Y496200D02*
X59822D01*
X60900Y495122D01*
G01X63370Y498214D02*
X64000Y497584D01*
Y494250D01*
G01X60900Y495122D02*
Y495900D01*
X63370Y498370D01*
Y498214D01*
G01X44500Y484000D02*
X44000Y484500D01*
X40750D01*
G01X55500Y496200D02*
Y498500D01*
X55062Y498938D01*
X52969D01*
X52000Y499907D01*
Y501500D01*
G01D02*
X52500Y502000D01*
X55750D01*
G01X55500Y488800D02*
Y487500D01*
X52000Y484000D01*
G01D02*
X53000Y483000D01*
X55750D01*
G01X61800Y537000D02*
X62200Y536600D01*
Y531960D01*
X66890Y527270D01*
G01X34050Y533500D02*
X38371D01*
X39616Y532255D01*
G01D02*
Y528260D01*
X38418Y527062D01*
X34000D01*
G01X66494Y556916D02*
X59084D01*
X54112Y561888D01*
Y577112D01*
X59000Y582000D01*
X73750D01*
G01X66000Y598250D02*
X57121Y607129D01*
Y632419D01*
X62002Y637300D01*
X72300D01*
X77538Y632062D01*
X82000D01*
X83200Y630862D01*
Y623400D01*
X86238Y620362D01*
X92562D01*
X97500Y625300D01*
Y631750D01*
G01X67508Y608289D02*
X62611D01*
G01X70000Y624500D02*
X62400D01*
G01X78200Y646000D02*
X54000D01*
X53000Y645000D01*
G01X73717Y632517D02*
X71434Y634800D01*
X63300D01*
G01X47800Y666400D02*
X50400D01*
X71900Y687900D01*
X82075D01*
G01X51300Y713150D02*
X47300D01*
G01X48700Y718195D02*
X47300Y716795D01*
Y713150D01*
G01X63300Y697200D02*
Y703400D01*
X66100Y706200D01*
X69700D01*
G01X55350Y713000D02*
X54700Y713650D01*
Y716250D01*
X53700Y717250D01*
G01X55350Y713000D02*
X55400Y712950D01*
Y708950D01*
X55350Y708900D01*
G01X31200Y712650D02*
X34050D01*
X34500Y712200D01*
X37300D01*
G01X43300Y713150D02*
X38250D01*
X37300Y712200D01*
G01X42600Y718000D02*
Y713850D01*
X43300Y713150D01*
G01X31550Y687525D02*
Y683435D01*
X32498Y682487D01*
G01X37700Y687500D02*
X41150D01*
X43950Y690300D01*
G01X32498Y682487D02*
X33756D01*
X37700Y686431D01*
Y687500D01*
G01X57200Y686450D02*
Y690550D01*
G01X51450Y686425D02*
X57175D01*
X57200Y686450D01*
G01X61505Y689980D02*
X59885D01*
X59315Y690550D01*
X57200D01*
G01X61505Y689980D02*
X64974D01*
X65350Y690356D01*
G01X44250Y728010D02*
X39936D01*
X38424Y729522D01*
X36514D01*
X34831Y727839D01*
G01X44550Y729979D02*
X40761D01*
X39243Y731497D01*
X35703D01*
X34300Y732900D01*
G01X49379Y744650D02*
Y749221D01*
X45900Y752700D01*
X43700D01*
X40200Y756200D01*
G01X47410Y744950D02*
Y748490D01*
X45800Y750100D01*
X41300D01*
X35000Y756400D01*
G01X70700Y714000D02*
X68400Y716300D01*
Y719200D01*
X62750Y724850D01*
X61190D01*
G01X48700Y718195D02*
X53316Y722811D01*
Y725150D01*
G01X35300Y738400D02*
X37816Y735884D01*
X44550D01*
G01X56100Y755900D02*
X57253Y754747D01*
Y744650D01*
G01X50900Y756000D02*
Y754500D01*
X55284Y750116D01*
Y744650D01*
G01X53700Y717250D02*
Y720728D01*
X55284Y722312D01*
Y725150D01*
G01X42600Y718000D02*
X44700Y720100D01*
X46900D01*
X49379Y722579D01*
Y725150D01*
G01X64400Y751800D02*
X61190Y748590D01*
Y744950D01*
G01X47410Y724850D02*
X37750D01*
X34800Y721900D01*
G01X37800Y745400D02*
X41410Y741790D01*
X44250D01*
G01X45400Y756200D02*
X53316Y748284D01*
Y744650D01*
G01X59221D02*
Y751621D01*
X61300Y753700D01*
Y756200D01*
G01X39000Y763350D02*
Y757400D01*
X40200Y756200D01*
G01X35000Y763350D02*
Y756400D01*
G01X56700Y766550D02*
Y770750D01*
X56650Y770800D01*
G01D02*
Y773450D01*
X58500Y775300D01*
G01X56100Y755900D02*
X54500Y757500D01*
Y764350D01*
X56700Y766550D01*
G01X47800Y763400D02*
X45100Y766100D01*
Y778800D01*
X48300Y782000D01*
X57600D01*
X60800Y778800D01*
Y766550D01*
G01X52300Y763150D02*
X48050D01*
X47800Y763400D01*
G01X50900Y756000D02*
Y760000D01*
X52300Y761400D01*
Y763150D01*
G01X42900Y763250D02*
Y758700D01*
X45400Y756200D01*
G01X56700Y763050D02*
X60800D01*
G01X61300Y756200D02*
Y756700D01*
X56700Y761300D01*
Y763050D01*
G01X60800D02*
X61500D01*
X65000Y766550D01*
G01X108224Y158387D02*
Y144424D01*
X91189Y127389D01*
Y126614D01*
G01X104050Y135210D02*
X96919Y128079D01*
Y122344D01*
X91189Y116614D01*
G01X111050Y203300D02*
X106288Y198538D01*
Y193693D01*
X104611Y192016D01*
Y145611D01*
X95614Y136614D01*
X91189D01*
G01X97850Y272000D02*
Y266790D01*
X97480Y266420D01*
G01X70516Y280483D02*
Y273516D01*
X70000Y273000D01*
G01X68100Y265300D02*
X69100Y266300D01*
Y272100D01*
X70000Y273000D01*
G01X84295Y280483D02*
Y272205D01*
X90100Y266400D01*
G01X82327Y280483D02*
Y276473D01*
X82700Y276100D01*
Y267400D01*
X83300Y266800D01*
G01X78390Y280483D02*
Y275557D01*
X78120Y275287D01*
Y271920D01*
X75800Y269600D01*
G01X80358Y280483D02*
Y274360D01*
G01X80300Y262650D02*
X76190D01*
X76170Y262670D01*
G01X80358Y274360D02*
Y269188D01*
X76170Y265000D01*
Y262670D01*
G01X100500Y285300D02*
X98268Y287532D01*
X94776D01*
X94317Y287073D01*
X88917D01*
G01X100750Y302900D02*
Y302114D01*
X99335Y300699D01*
X97583D01*
X96798Y301484D01*
G01X88917Y298884D02*
X91983D01*
X92271Y298596D01*
X93026D01*
X94308Y299878D01*
X95192D01*
X96798Y301484D01*
G01Y297915D02*
X98083Y299200D01*
X100450D01*
X100750Y298900D01*
G01X88917Y296916D02*
X92064D01*
X92122Y296974D01*
X92991D01*
X93023Y297006D01*
X93568D01*
X94901Y298339D01*
X96374D01*
X96798Y297915D01*
G01X95700Y293900D02*
X94653Y294947D01*
X88917D01*
G01X100750Y294900D02*
X99600D01*
X96607Y291907D01*
X94793D01*
X93721Y292979D01*
X88917D01*
G01Y291010D02*
X93604D01*
X94182Y290432D01*
X100282D01*
X100750Y290900D01*
G01X88917Y283136D02*
X92937Y279116D01*
X97212D01*
X97750Y278578D01*
Y276300D01*
G01X104000Y286200D02*
X101243Y288957D01*
X93143D01*
X93058Y289042D01*
X88917D01*
G01Y304790D02*
X92098D01*
X97830Y310522D01*
Y311830D01*
X97838Y311838D01*
Y311989D01*
G01X88917Y306758D02*
X92032D01*
X95365Y310091D01*
Y315765D01*
X96500Y316900D01*
G01X88917Y308727D02*
X91793D01*
X93940Y310874D01*
Y317841D01*
X98354Y322255D01*
X98855D01*
X100650Y324050D01*
Y324100D01*
G01X96677Y285294D02*
X94913D01*
X94724Y285105D01*
X88917D01*
G01X96677Y285294D02*
Y282702D01*
X95557Y281582D01*
G01X91600Y340650D02*
Y331900D01*
X91300Y331600D01*
G01D02*
X89300Y329600D01*
Y325100D01*
X82327Y318127D01*
Y315317D01*
G01X94700Y335600D02*
X93438Y334338D01*
Y330714D01*
X90725Y328001D01*
Y324509D01*
X84295Y318079D01*
Y315317D01*
G01X95670Y340761D02*
Y336570D01*
X94700Y335600D01*
G01X96107Y324781D02*
Y322802D01*
X92502Y319197D01*
Y311602D01*
X91595Y310695D01*
X88917D01*
G01X96107Y324781D02*
X99926Y328600D01*
X100550D01*
G01X100440Y319780D02*
X99380D01*
X96500Y316900D01*
G01X99887Y340825D02*
X97234Y338172D01*
Y335110D01*
X94863Y332739D01*
Y330123D01*
X92275Y327535D01*
Y324043D01*
X86264Y318032D01*
Y315317D01*
G01X98400Y332400D02*
X96288Y330288D01*
Y328657D01*
X93700Y326069D01*
Y323200D01*
X89417Y318917D01*
Y313164D01*
X88917Y312664D01*
G01X79455Y357174D02*
X84029Y352600D01*
X95774D01*
X99887Y348487D01*
Y344325D01*
G01X93968Y378707D02*
X96393D01*
X99760Y375340D01*
X105622D01*
X106223Y375941D01*
X109407D01*
X112122Y378656D01*
G01X100200Y384850D02*
X97057Y381707D01*
X92157D01*
X83850Y373400D01*
X82005D01*
X79792Y371187D01*
G01X79741Y365075D02*
X79200Y364534D01*
Y361082D01*
X79555Y360727D01*
G01X79792Y371187D02*
Y365126D01*
X79741Y365075D01*
G01X79555Y360727D02*
X81718Y362890D01*
X82500D01*
G01D02*
X83110D01*
X85650Y360350D01*
Y360000D01*
G01X85800Y355000D02*
Y357238D01*
X85700Y357338D01*
Y359950D01*
X85650Y360000D01*
G01X89150D02*
X90093Y360943D01*
Y365200D01*
G01D02*
Y371207D01*
G01X67000Y377500D02*
Y374443D01*
X65965Y373408D01*
G01X70654Y374310D02*
X70364Y374600D01*
Y375872D01*
X68736Y377500D01*
X67000D01*
G01X70654Y374310D02*
X76930D01*
X81307Y378687D01*
X83667D01*
G01X76241Y365075D02*
X74667Y366649D01*
X70591D01*
G01X65965Y367408D02*
X69832D01*
X70591Y366649D01*
G01X65965Y367408D02*
Y362838D01*
G01X64800Y383400D02*
X66736Y381464D01*
X68365D01*
G01X84440Y392665D02*
Y395740D01*
X84700Y396000D01*
G01X90028Y399115D02*
Y394659D01*
X88034Y392665D01*
X84440D01*
G01X100200Y384850D02*
X98200Y386850D01*
Y391219D01*
X98162Y391257D01*
Y393111D01*
X98200Y393149D01*
Y402563D01*
X95148Y405615D01*
G01X84274Y402591D02*
X80859D01*
X80000Y403450D01*
G01X90028Y405615D02*
X88285D01*
X87400Y406500D01*
X84400D01*
G01D02*
X84274Y406374D01*
Y402591D01*
G01X89500Y466600D02*
Y464762D01*
X92362Y461900D01*
X93900D01*
X101312Y454488D01*
Y453793D01*
X102955Y452150D01*
X115370D01*
X116235Y451285D01*
G01X93599Y477241D02*
X92000Y475642D01*
X88784D01*
X86371Y473229D01*
Y464148D01*
X93149Y457370D01*
Y456451D01*
X100500Y449100D01*
X107700D01*
X107900Y448900D01*
G01X97099Y477241D02*
X100911D01*
X101170Y477500D01*
X103158D01*
X106258Y480600D01*
G01X93314Y466166D02*
Y465406D01*
X94720Y464000D01*
X97900D01*
X99900Y466000D01*
X102540D01*
X105563Y469023D01*
X106447D01*
X110262Y472838D01*
Y476138D01*
X116311Y482187D01*
X117687D01*
X119299Y483799D01*
X120098D01*
G01X92500Y469750D02*
Y468600D01*
X93314Y467786D01*
Y466166D01*
G01X96700Y469650D02*
Y466900D01*
X97100Y466500D01*
G01X96700Y473150D02*
X98888Y470962D01*
Y469212D01*
X99838Y468262D01*
X102886D01*
X105417Y470793D01*
Y471117D01*
X107000Y472700D01*
G01X70910Y502219D02*
X70909Y502220D01*
X67019D01*
G01X99800Y511851D02*
X99614Y512037D01*
X86720D01*
X85667Y513090D01*
X83019D01*
G01X88500Y509613D02*
X100727D01*
X102038Y510924D01*
Y511157D01*
X106176Y515295D01*
X116948D01*
G01X83894Y508831D02*
X84676Y509613D01*
X88500D01*
G01X83894Y504831D02*
X86438Y507375D01*
X89427D01*
X90240Y508188D01*
X94431D01*
X94699Y507920D01*
X101439D01*
X105119Y511600D01*
X106000D01*
G01X95750Y506000D02*
X96080Y505670D01*
X99820D01*
G01X66473Y511404D02*
X67377Y510500D01*
X70750D01*
G01X67162Y515142D02*
X66473Y514453D01*
Y511404D01*
G01X77700Y522500D02*
X73992D01*
X73787Y522705D01*
G01X84250Y542300D02*
X88727Y546777D01*
Y547047D01*
G01D02*
X91237D01*
X92084Y546200D01*
X99600D01*
X100063Y545737D01*
X108047D01*
X112794Y540990D01*
X112830D01*
X115020Y538800D01*
X118640D01*
X120098Y537342D01*
G01X98008Y548338D02*
X91962D01*
X91015Y549285D01*
X87235D01*
X84250Y546300D01*
G01Y534300D02*
X88000Y538050D01*
Y538500D01*
G01D02*
X89000D01*
X91900Y541400D01*
X96634D01*
X97270Y542036D01*
X97424D01*
X98237Y542849D01*
X100091D01*
X100866Y542074D01*
X105091D01*
X105641Y541524D01*
X107706D01*
X107830Y541400D01*
X108400D01*
X114100Y535700D01*
X118590D01*
X120098Y534192D01*
G01X116948Y537342D02*
X114500D01*
X107530Y544312D01*
X93812D01*
X93138Y543638D01*
X93100D01*
G01D02*
X93062Y543600D01*
X91400D01*
X88900Y541100D01*
X87050D01*
X84250Y538300D01*
G01X95750Y526500D02*
Y526606D01*
X100383Y531239D01*
X103313D01*
G01X67700Y518500D02*
X71278D01*
X71540Y518238D01*
G01D02*
X71870Y517908D01*
Y515620D01*
X70750Y514500D01*
G01X95750Y522500D02*
Y523413D01*
X99829Y527492D01*
G01X103100Y517400D02*
X101900D01*
X97962Y513462D01*
X87311D01*
X84161Y516612D01*
Y516615D01*
X83686Y517090D01*
X83019D01*
G01X95750Y518500D02*
X101143Y523893D01*
X103289D01*
G01X83600Y525700D02*
X85200D01*
X87011Y523889D01*
Y517794D01*
X88493Y516312D01*
X96612D01*
X101894Y521594D01*
X116948D01*
G01X83600Y525700D02*
X81751Y527549D01*
Y528499D01*
X80950Y529300D01*
G01X71170Y531831D02*
X71763Y531238D01*
X77300D01*
G01X77700Y538500D02*
X75131Y535931D01*
X71170D01*
G01X95750Y530500D02*
Y530720D01*
X99476Y534446D01*
G01X95750Y534500D02*
X99050Y537800D01*
X103300D01*
G01X95750Y538500D02*
X97861Y540611D01*
X99164D01*
G01X81523Y521151D02*
X81497Y521177D01*
Y523100D01*
X79550Y525047D01*
X72153D01*
X70390Y526810D01*
Y527270D01*
G01X120098Y518444D02*
X118442Y520100D01*
X102600D01*
X101325Y518825D01*
X101309D01*
X97371Y514887D01*
X87902D01*
X85586Y517203D01*
Y518860D01*
X83664Y520782D01*
X81892D01*
X81523Y521151D01*
G01X77372Y526885D02*
Y527872D01*
X79162Y529662D01*
Y530705D01*
X80750Y532293D01*
Y534300D01*
G01X69100Y549200D02*
X71300Y547000D01*
X74500D01*
X79200Y542300D01*
X80750D01*
G01X73700Y549300D02*
X75200D01*
X78200Y546300D01*
X80750D01*
G01Y538300D02*
X78550Y540500D01*
X72000D01*
X70000Y542500D01*
G01X80750Y554500D02*
X78938Y556312D01*
X78287D01*
X78261Y556338D01*
X74662D01*
X74000Y557000D01*
G01X116948Y543641D02*
X113893D01*
X105697Y551837D01*
X101482D01*
X101193Y552126D01*
X96108D01*
X94796Y553438D01*
X92473D01*
X92033Y552998D01*
X88271D01*
G01D02*
X86263D01*
X85350Y553911D01*
X84839D01*
X84250Y554500D01*
G01X77500D02*
X77246Y554754D01*
X73508D01*
X71346Y556916D01*
X66494D01*
G01X96537Y555253D02*
X96020Y555770D01*
X86924D01*
X85770Y556924D01*
Y556980D01*
X84250Y558500D01*
G01X96537Y555253D02*
X97197Y554593D01*
X100742D01*
X102073Y553262D01*
X105511D01*
X106436Y552336D01*
X113593Y545179D01*
X118560D01*
X120098Y543641D01*
G01X84900Y582250D02*
Y578598D01*
X84226Y577924D01*
G01X80650Y550400D02*
X77400D01*
G01X93400Y551200D02*
X92940Y550740D01*
X86640D01*
X86300Y550400D01*
X84150D01*
G01X120098Y540492D02*
X118560Y542030D01*
X117603D01*
X117591Y542042D01*
X116305D01*
X116293Y542030D01*
X114284D01*
X113561Y542753D01*
X113525D01*
X106978Y549300D01*
X102300D01*
X101201Y550399D01*
X100886D01*
X100597Y550688D01*
X95512D01*
X95000Y551200D01*
X93400D01*
G01X66000Y594250D02*
Y598250D01*
G01X91750Y595440D02*
Y592500D01*
X92000Y592250D01*
Y591200D01*
G01X73750Y586000D02*
X74269Y586519D01*
Y599470D01*
G01X73750Y586000D02*
Y582000D01*
G01X69500Y586000D02*
X73750D01*
G01X65780Y586777D02*
X67677D01*
X68738Y587838D01*
X70338D01*
X71709Y589209D01*
Y592970D01*
G01X66000Y590750D02*
X65780Y590530D01*
Y586777D01*
G01X70000Y615500D02*
Y611750D01*
X72000Y609750D01*
G01X76000Y606250D02*
X76250Y606500D01*
X80250D01*
G01X72000Y606250D02*
X76000D01*
G01X72000D02*
X69547D01*
X67508Y608289D01*
G01X83750Y606500D02*
X83562Y606688D01*
Y610519D01*
G01X85250Y600560D02*
Y605000D01*
X83750Y606500D01*
G01X83562Y610519D02*
X84331D01*
X88000Y606850D01*
G01X86933Y598000D02*
X85250D01*
G01X92000Y605500D02*
X88388Y601888D01*
Y599455D01*
X86933Y598000D01*
G01X88350Y590300D02*
X88388Y590338D01*
Y596545D01*
X86933Y598000D01*
G01X84900Y585750D02*
X88350Y589200D01*
Y590300D01*
G01X78500Y615500D02*
Y612250D01*
X76000Y609750D01*
G01X104000Y627000D02*
X99250Y631750D01*
X97500D01*
G01X86750Y646000D02*
X78200D01*
G01X89500Y628750D02*
Y622700D01*
X89600Y622600D01*
G01X90250Y642000D02*
X89500Y641250D01*
Y628750D01*
G01X90250Y646000D02*
Y642000D01*
G01X92060Y635250D02*
X97500D01*
G01X102020Y633720D02*
X100490Y635250D01*
X97500D01*
G01X64500Y615500D02*
X70000D01*
G01X78500Y624500D02*
Y627734D01*
X73717Y632517D01*
G01X84000Y615500D02*
X78500D01*
G01X85500Y706800D02*
X84300D01*
X83000Y705500D01*
Y703950D01*
X80950Y701900D01*
G01X99950Y695400D02*
X85950D01*
G01D02*
X85450Y695900D01*
Y702150D01*
G01X85500Y706800D02*
X86000Y706300D01*
Y702700D01*
X85450Y702150D01*
G01X74500Y713400D02*
X71300D01*
X70700Y714000D01*
G01X76450Y705150D02*
X70750D01*
X69700Y706200D01*
G01X80950Y705400D02*
X80700Y705150D01*
X76450D01*
G01X85000Y714900D02*
X83500D01*
X82151Y716249D01*
Y722141D01*
X81092Y723200D01*
X79250D01*
G01X86678Y720600D02*
Y715878D01*
X85700Y714900D01*
X85000D01*
G01X98450Y681900D02*
Y685525D01*
X96075Y687900D01*
G01X107000Y717800D02*
Y696700D01*
X101225Y690925D01*
X97925D01*
X96075Y689075D01*
Y687900D01*
G01X87450Y681900D02*
X83350D01*
G01X82075Y687900D02*
Y683175D01*
X83350Y681900D01*
G01X99150Y732300D02*
X97732Y730882D01*
X96118D01*
X95400Y731600D01*
G01X99150Y727800D02*
X98043Y728907D01*
X96107D01*
X95400Y728200D01*
G01X73900Y755200D02*
X67800Y749100D01*
Y746900D01*
X64350Y743450D01*
Y741790D01*
G01X68900Y730000D02*
X68700D01*
X68679Y729979D01*
X64050D01*
G01Y735884D02*
X68120D01*
X68465Y736229D01*
G01X81850Y727300D02*
X85600D01*
X85800Y727500D01*
G01X81850Y731300D02*
X85500D01*
X85800Y731000D01*
G01X73800Y749600D02*
X67112Y742912D01*
Y740641D01*
X66292Y739821D01*
X64050D01*
G01X79900Y749300D02*
Y745250D01*
X79550Y744900D01*
G01X75750Y723200D02*
Y719300D01*
G01X71000Y719200D02*
X64350Y725850D01*
Y728010D01*
G01X75750Y719300D02*
X75650Y719200D01*
X71000D01*
G01X86678Y720600D02*
X85495D01*
X84695Y721400D01*
X83922D01*
G01X89600Y727900D02*
Y725900D01*
X91800Y723700D01*
Y723150D01*
G01X86678Y722200D02*
X90850D01*
X91800Y723150D01*
G01X74600Y727550D02*
X78100D01*
X78350Y727300D01*
G01X64050Y731947D02*
X70203D01*
X74600Y727550D01*
G01Y731050D02*
X78100D01*
X78350Y731300D01*
G01X74600Y731050D02*
X71835Y733815D01*
X68139D01*
X68038Y733916D01*
X64050D01*
G01X79800Y762400D02*
Y766650D01*
X79550Y766900D01*
G01Y757900D02*
Y762150D01*
X79800Y762400D01*
G01X79550Y757900D02*
X76600D01*
X73900Y755200D01*
G01X79550Y753700D02*
Y749650D01*
X79900Y749300D01*
G01X79550Y753700D02*
X77900D01*
X73800Y749600D01*
G01X65000Y763050D02*
Y752400D01*
X64400Y751800D01*
G01X69800Y762900D02*
X74050D01*
X74300Y762650D01*
G01X65000Y763050D02*
X69650D01*
X69800Y762900D01*
G01X64900Y770900D02*
X65000Y770800D01*
Y766550D01*
G01X97248Y813797D02*
X93697D01*
X93100Y813200D01*
G01X97248Y820203D02*
X94603D01*
X93300Y818900D01*
G01X111319Y195688D02*
X110820Y195189D01*
Y156740D01*
X109970Y155890D01*
Y133630D01*
X108050Y131710D01*
G01Y135210D02*
X104050D01*
G01X111967Y199632D02*
X111319Y198984D01*
Y195688D01*
G01X105300Y207900D02*
X104100D01*
X103100Y208900D01*
Y211600D01*
G01X107050Y212200D02*
Y209150D01*
X105800Y207900D01*
X105300D01*
G01X110550Y212200D02*
X111050Y211700D01*
Y207700D01*
G01D02*
Y203300D01*
G01X119800Y234531D02*
X115369Y230100D01*
X109550D01*
G01X106050D02*
Y229879D01*
X100688Y224517D01*
G01X114733Y238996D02*
Y234079D01*
X113192Y232538D01*
X108488D01*
X106050Y230100D01*
G01X100953Y257066D02*
Y262921D01*
X104172Y266140D01*
X107340D01*
G01X101350Y272000D02*
X102550Y273200D01*
X106800D01*
X107300Y272700D01*
G01X108827Y257066D02*
Y264032D01*
X109452Y264657D01*
Y270548D01*
X107300Y272700D01*
G01X99057Y281582D02*
X102100D01*
X102499Y281183D01*
G01X120700Y282400D02*
Y283100D01*
X121350Y283750D01*
Y287500D01*
G01X108500Y294650D02*
X108250Y294900D01*
X104250D01*
G01X113915Y307600D02*
X114877Y306638D01*
Y295977D01*
X112208Y293308D01*
X109842D01*
X108500Y294650D01*
G01X117484Y307600D02*
X116352Y306468D01*
Y295276D01*
X115737Y294661D01*
X115693D01*
X112833Y291801D01*
X109651D01*
X108500Y290650D01*
G01X104250Y290900D02*
X104390Y290760D01*
X108390D01*
X108500Y290650D01*
G01X104000Y286200D02*
X105850Y284350D01*
Y283150D01*
X106500Y282500D01*
Y280650D01*
G01X100490Y315650D02*
X99650D01*
X99613Y315613D01*
Y315610D01*
X97830Y313827D01*
Y312170D01*
X97838Y312162D01*
Y311989D01*
G01X108385Y327857D02*
X107122Y326594D01*
X102281D01*
X100650Y324963D01*
Y324100D01*
G01X113000Y336000D02*
X112775Y336225D01*
X111945D01*
X105942Y330222D01*
X105622D01*
X104050Y328650D01*
Y328600D01*
G01X160303Y365303D02*
X145500Y350500D01*
X136700D01*
X121899Y335699D01*
Y331900D01*
X119704Y329705D01*
X119610D01*
X111511Y321606D01*
Y321512D01*
X105649Y315650D01*
X103990D01*
G01X103940Y319780D02*
X105172Y321012D01*
X107558D01*
G01X104150Y324100D02*
X108850D01*
X114838Y330088D01*
Y336138D01*
X122000Y343300D01*
G01X100277Y336077D02*
X103998Y339798D01*
Y340800D01*
G01D02*
X99912D01*
X99887Y340825D01*
G01X103617Y332765D02*
X98765D01*
X98400Y332400D01*
G01X105896Y362064D02*
X105835Y362125D01*
G01D02*
Y373069D01*
X107282Y374516D01*
X112307D01*
X117938Y380147D01*
Y389507D01*
X114996Y392449D01*
Y395657D01*
X108249Y402404D01*
X106148D01*
X104808Y403744D01*
Y405542D01*
G01X102000Y364700D02*
X103260D01*
X105835Y362125D01*
G01X129694Y379247D02*
Y377155D01*
X132764Y374085D01*
Y373985D01*
G01X137862Y361723D02*
X137839Y361700D01*
X135699D01*
X134146Y363253D01*
Y366513D01*
X122963Y377696D01*
G01D02*
Y392287D01*
X122950Y392300D01*
G01X117761Y372556D02*
X116361Y371156D01*
X108247D01*
G01X117761Y372556D02*
X117811Y372506D01*
X119599D01*
X119649Y372556D01*
X125309D01*
X128716Y369149D01*
Y357556D01*
X119830Y348670D01*
G01X111900Y344200D02*
X115360D01*
X119830Y348670D01*
G01X117300Y361700D02*
X115104Y359504D01*
X105896D01*
G01X109285Y352411D02*
X110322Y351374D01*
Y347616D01*
X106956Y344250D01*
X104048D01*
X103998Y344300D01*
G01X112396Y356944D02*
Y355406D01*
X110984Y353994D01*
X110868D01*
X109285Y352411D01*
G01X126450Y392300D02*
X127700D01*
X130280Y389720D01*
G01X136000Y388984D02*
X131016D01*
X130280Y389720D01*
G01X129694Y379247D02*
X134247D01*
X136000Y381000D01*
Y383079D01*
G01X112250Y388600D02*
Y385000D01*
G01D02*
Y378784D01*
X112122Y378656D01*
G01X100200Y388350D02*
Y390300D01*
X100000Y390500D01*
Y391784D01*
X100400Y392184D01*
G01D02*
X104507D01*
G01D02*
X105000Y392677D01*
Y397200D01*
X103158Y399042D01*
X102248D01*
G01X124290Y401910D02*
Y399010D01*
X132347Y390953D01*
X136000D01*
G01X125718Y383302D02*
Y383343D01*
X126175Y383800D01*
X130367D01*
X131614Y385047D01*
X136000D01*
G01X125600Y386700D02*
X127230D01*
X127546Y387016D01*
X136000D01*
G01X107358Y409942D02*
Y409916D01*
X109023D01*
X109597Y410490D01*
X121760D01*
X127400Y404850D01*
G01D02*
X127410Y404840D01*
Y399590D01*
X130000Y397000D01*
G01X136000Y392921D02*
Y394600D01*
X133600Y397000D01*
X130000D01*
G01X135250Y440240D02*
X132899D01*
X131355Y438696D01*
Y437004D01*
G01X137000Y436700D02*
X131659D01*
X131355Y437004D01*
G01X150632Y450105D02*
X150602Y450075D01*
Y448025D01*
X151676Y446951D01*
Y441106D01*
X138249Y427679D01*
Y425800D01*
X131304Y418855D01*
G01X131004Y422710D02*
X134768Y426474D01*
Y429438D01*
G01X127633Y441705D02*
Y446663D01*
X129520Y448550D01*
Y448660D01*
G01X130633Y444763D02*
X134670Y448800D01*
X137500D01*
X141950Y453250D01*
X142000D01*
G01X112184Y441150D02*
Y437194D01*
X112978Y436400D01*
X116300D01*
G01X120252Y440302D02*
Y436452D01*
X120200Y436400D01*
G01X116300D02*
X120200D01*
G01X122406Y447830D02*
X120252Y445676D01*
Y443802D01*
G01X116235Y451285D02*
X120000D01*
G01X101200Y470400D02*
X102000D01*
X103277Y471677D01*
Y472561D01*
X116116Y485400D01*
X118550D01*
X120098Y486948D01*
G01X116948Y480649D02*
X111949Y475650D01*
Y473049D01*
X107048Y468148D01*
X106703D01*
X105966Y467411D01*
Y467410D01*
X103056Y464500D01*
X100800D01*
X100000Y463700D01*
Y462700D01*
G01X103500Y461250D02*
X101450D01*
X100000Y462700D01*
G01X115673Y464911D02*
Y468773D01*
X117212Y470312D01*
Y475588D01*
X121636Y480012D01*
Y481213D01*
X122610Y482187D01*
X123810D01*
X124959Y483336D01*
Y485510D01*
X126397Y486948D01*
G01X115673Y464911D02*
X115500Y464738D01*
Y461250D01*
G01X106983Y465035D02*
X107000Y465018D01*
Y461750D01*
X107500Y461250D01*
G01X123247Y483799D02*
X122273D01*
X120661Y482187D01*
X119461D01*
X118486Y481212D01*
Y480012D01*
X117585Y479111D01*
X117444D01*
X113166Y474833D01*
Y472595D01*
X107000Y466429D01*
Y465052D01*
X106983Y465035D01*
G01X111421Y467542D02*
X111427D01*
Y467538D01*
X111400Y467511D01*
Y461350D01*
X111500Y461250D01*
G01X111421Y467542D02*
X115306Y471427D01*
Y475594D01*
X120098Y480386D01*
Y480649D01*
G01X126397Y483799D02*
Y482682D01*
X124959Y481244D01*
Y478359D01*
X122700Y476100D01*
G01X123247Y480649D02*
Y478947D01*
X122700Y478400D01*
G01X126397Y480649D02*
Y477249D01*
X122948Y473800D01*
X122600D01*
G01X129547Y483799D02*
Y482682D01*
X128000Y481135D01*
Y476652D01*
X122848Y471500D01*
X122600D01*
G01X133000Y461250D02*
X130326D01*
X129076Y462500D01*
G01D02*
Y464230D01*
X135846Y471000D01*
Y480649D01*
G01X129547D02*
Y475087D01*
X121937Y467477D01*
Y467277D01*
X120680Y466020D01*
G01X120500Y461000D02*
X123362Y463862D01*
Y466886D01*
X131258Y474782D01*
Y481244D01*
X132696Y482682D01*
Y483799D01*
G01X125500Y466000D02*
X132696Y473196D01*
Y480649D01*
G01X135846Y483799D02*
Y482682D01*
X134408Y481244D01*
Y472892D01*
X127638Y466122D01*
Y464227D01*
X126838Y463427D01*
Y457662D01*
X128500Y456000D01*
G01X102032Y475274D02*
X103974D01*
X115648Y486948D01*
X116948D01*
G01X107000Y472700D02*
Y474114D01*
X116685Y483799D01*
X116948D01*
G01X123696Y454452D02*
X122406Y453162D01*
Y447830D01*
G01X123247Y490098D02*
X121673Y491672D01*
G01X126397Y508996D02*
X128109Y507284D01*
X130142D01*
X130985Y506441D01*
Y504300D01*
G01X120098Y508996D02*
X119804D01*
X118230Y510570D01*
X114553D01*
X107913Y503930D01*
X105045D01*
G01D02*
Y505292D01*
G01X116948Y508996D02*
X116947Y508997D01*
X115774D01*
X108732Y501955D01*
X107423D01*
G01D02*
Y500672D01*
G01X126397Y505846D02*
X124822Y504271D01*
G01X129547Y505846D02*
X127973Y504272D01*
G01X123247Y499547D02*
X121673Y497973D01*
G01X123247Y496397D02*
Y496396D01*
X121673Y494822D01*
G01X120098Y505846D02*
Y505836D01*
X118500Y504238D01*
G01X116948Y505846D02*
X115373Y504271D01*
G01X123247Y486948D02*
X121709Y488486D01*
X114144D01*
X106258Y480600D01*
G01X99800Y511851D02*
X103111Y515162D01*
X104062D01*
X105633Y516733D01*
X117543D01*
X118981Y515295D01*
X120098D01*
G01X129547Y512145D02*
X127973Y510571D01*
G01X126397Y512145D02*
X124823Y510571D01*
G01X123247Y512145D02*
X121673Y510571D01*
G01X106000Y511600D02*
X107983Y513583D01*
X118660D01*
X120098Y512145D01*
G01X99820Y505670D02*
X101220D01*
X104050Y508500D01*
X106620D01*
X110265Y512145D01*
X116948D01*
G01X129547Y508996D02*
X131121Y510570D01*
G01X126397Y496397D02*
X127971Y494823D01*
G01X132696Y493248D02*
X131122Y491674D01*
G01X129547Y490098D02*
X127973Y488524D01*
G01X132696Y490098D02*
X131122Y488524D01*
G01X132696Y486948D02*
X131122Y485374D01*
G01X123247Y505846D02*
X121673Y504272D01*
G01X126397Y502696D02*
X124823Y501122D01*
G01X123247Y502696D02*
X121673Y501122D01*
G01X129547Y499547D02*
X127973Y497973D01*
G01X126397Y490098D02*
X124822Y488523D01*
G01X102000Y497700D02*
X102734Y498434D01*
X108640D01*
X113837Y503631D01*
X113835Y503634D01*
Y504908D01*
X116211Y507284D01*
X120419D01*
X122131Y508996D01*
X123247D01*
G01X129547Y493248D02*
X127973Y491674D01*
G01X124823Y497973D02*
X126397Y499547D01*
G01X123247Y493248D02*
X123249D01*
X124823Y491674D01*
G01X129547Y486948D02*
X127973Y485374D01*
G01X126397Y493248D02*
X124823Y494822D01*
G01X129547Y496397D02*
X131121Y494823D01*
G01X129547Y502696D02*
X127973Y501122D01*
G01X129547Y531043D02*
X127973Y529469D01*
G01X126397Y524744D02*
X124823Y523170D01*
G01X98008Y548338D02*
X99478D01*
X100654Y547162D01*
X107860D01*
X113157Y541865D01*
X113193D01*
X114566Y540492D01*
X116948D01*
G01X126397Y531043D02*
X124823Y532617D01*
G01X132696Y537342D02*
Y536400D01*
X132196Y535900D01*
X131400D01*
X130985Y536315D01*
Y538639D01*
X131400Y539054D01*
X134132D01*
X134270Y538916D01*
G01X132696Y540492D02*
Y541312D01*
X130985Y543022D01*
Y544236D01*
X129868Y545353D01*
X128836D01*
X127900Y546289D01*
Y547321D01*
X125111Y550110D01*
X124847D01*
G01X132696Y543641D02*
Y544032D01*
X131000Y545728D01*
Y549861D01*
X130100Y550761D01*
Y554424D01*
X129600Y554924D01*
X122547D01*
G01X123247Y543641D02*
X121673Y545215D01*
G01X123247Y524744D02*
X121673Y523170D01*
G01X103313Y531239D02*
X104052Y530500D01*
X111000D01*
X115200Y526300D01*
X118542D01*
X120098Y524744D01*
G01X129547Y527893D02*
X131121Y529467D01*
G01X129547Y518444D02*
X131121Y520018D01*
G01X126397Y518444D02*
X127971Y520018D01*
G01X129547Y515295D02*
X131121Y513721D01*
G01X116948Y524744D02*
X114300D01*
X111468Y527576D01*
X99913D01*
X99829Y527492D01*
G01D02*
Y527520D01*
G01X116948Y518444D02*
X104144D01*
X103100Y517400D01*
G01X123247Y518444D02*
X121673Y516870D01*
Y513721D01*
G01X129547Y521594D02*
X131121Y523168D01*
G01X126397Y521594D02*
X124822Y520019D01*
G01X123247Y521594D02*
X121673Y520020D01*
G01X103289Y523893D02*
X112707D01*
X113500Y523100D01*
X118592D01*
X120098Y521594D01*
G01X126397Y515295D02*
X127971Y513721D01*
G01X123247Y515295D02*
X124821Y513721D01*
G01X116948Y527893D02*
X115374Y529467D01*
G01X120098Y527893D02*
X118524Y529467D01*
G01X123247Y527893D02*
X121673Y529467D01*
G01X99476Y534446D02*
X99522Y534400D01*
X110243D01*
X113600Y531043D01*
X116948D01*
G01X103300Y537800D02*
X108400D01*
X113600Y532600D01*
X118541D01*
X120098Y531043D01*
G01X126397Y527893D02*
X124823Y529467D01*
G01X99164Y540611D02*
X99202Y540649D01*
X107343D01*
X113800Y534192D01*
X116948D01*
G01X123247Y531043D02*
X121673Y532617D01*
G01X123247Y534192D02*
X121673Y535766D01*
G01X129547Y524744D02*
X127973Y523170D01*
G01X123247Y537342D02*
X121673Y538916D01*
G01X98008Y548438D02*
Y548338D01*
G01X126801Y574386D02*
X128814D01*
X131138Y572062D01*
X151200D01*
X151700Y571562D01*
Y568311D01*
X151200Y567811D01*
X148289D01*
X139178Y558700D01*
Y550010D01*
X142145Y547043D01*
Y546791D01*
G01X135846Y543641D02*
Y543643D01*
X134219Y545270D01*
Y547281D01*
X134134Y547366D01*
Y547386D01*
X132900Y548620D01*
Y551638D01*
X132299Y552239D01*
Y561901D01*
X134000Y563602D01*
Y564437D01*
X133500Y564937D01*
X129791D01*
X129350Y564496D01*
Y563073D01*
X125915Y559638D01*
X124900D01*
G01X132696Y546791D02*
X131900Y547587D01*
Y550600D01*
X131100Y551400D01*
Y559100D01*
X130600Y559600D01*
X128200D01*
X127700Y559100D01*
Y557200D01*
X126962Y556462D01*
X124900D01*
G01X138995Y546791D02*
X138319Y547467D01*
Y548020D01*
X136575Y549764D01*
Y560129D01*
X143400Y566954D01*
Y568612D01*
X142800Y569212D01*
X126112D01*
X124900Y568000D01*
Y565990D01*
G01X138995Y543641D02*
X137869D01*
X137369Y544141D01*
Y547369D01*
X135150Y549588D01*
Y559538D01*
X135149Y559539D01*
Y560719D01*
X140900Y566470D01*
Y567287D01*
X140400Y567787D01*
X127000D01*
X126500Y567287D01*
Y564414D01*
X124900Y562814D01*
G01X129547Y546791D02*
X129225Y547113D01*
Y549050D01*
X128750Y549525D01*
X127400D01*
X126900Y550025D01*
Y550925D01*
X127400Y551425D01*
X128750D01*
X129225Y551900D01*
Y552775D01*
X128714Y553286D01*
X124900D01*
G01X135846Y546791D02*
Y547293D01*
X133775Y549364D01*
Y552001D01*
X133724Y552052D01*
Y561310D01*
X137100Y564686D01*
Y565862D01*
X136600Y566362D01*
X129200D01*
X127925Y565087D01*
Y563664D01*
X125537Y561276D01*
X122547D01*
G01X142145Y543641D02*
X140700Y545086D01*
Y547188D01*
X138000Y549888D01*
Y559538D01*
X147698Y569236D01*
Y570139D01*
X147200Y570637D01*
X124337D01*
X122547Y568847D01*
Y567628D01*
G01X128258Y583511D02*
Y595234D01*
X129795Y596771D01*
G01X126646Y612519D02*
X125072Y610945D01*
G01X123496Y599921D02*
X123000Y600417D01*
Y602425D01*
X123500Y602925D01*
X124570D01*
X125070Y602425D01*
Y598347D01*
G01X132945Y599921D02*
X134500Y601476D01*
Y605800D01*
X135000Y606300D01*
X139000D01*
X139500Y605800D01*
Y604200D01*
X139900Y603800D01*
X141200D01*
X141800Y604400D01*
Y608100D01*
X141400Y608500D01*
X131870D01*
X131370Y608000D01*
Y601496D01*
G01X120347Y599921D02*
X118773Y601495D01*
G01X126646Y599921D02*
X126837Y600112D01*
Y603463D01*
X126500Y603800D01*
X121400D01*
X120900Y604300D01*
Y606200D01*
X120300Y606800D01*
X117500D01*
X116800Y607500D01*
Y608400D01*
X117400Y609000D01*
X126146D01*
X126646Y608500D01*
Y606400D01*
G01X117197Y612519D02*
Y610900D01*
X116697Y610400D01*
X114700D01*
X114200Y610900D01*
Y613594D01*
X114700Y614094D01*
X115622D01*
G01X117197Y599921D02*
X115024D01*
X112100Y596997D01*
Y594500D01*
X111600Y594000D01*
X110200D01*
X109700Y594500D01*
Y598100D01*
X113900Y602300D01*
X114818D01*
X115622Y601496D01*
G01X123496Y612519D02*
X121922Y610945D01*
G01X123496Y596771D02*
Y597888D01*
X121785Y599599D01*
Y601815D01*
X120566Y603034D01*
X118800D01*
X118300Y603534D01*
Y604172D01*
X118773Y604645D01*
G01X120347Y596771D02*
Y595700D01*
X120847Y595200D01*
X121600D01*
X122058Y595658D01*
Y597887D01*
X121600Y598345D01*
X118773D01*
G01X117197Y596771D02*
Y595655D01*
X115435Y593893D01*
Y587100D01*
X114935Y586600D01*
X113900D01*
X113400Y587100D01*
Y596122D01*
X115623Y598345D01*
G01X120347Y612519D02*
X118773Y610945D01*
G01X126646Y596771D02*
X125208Y595333D01*
Y593159D01*
X122559Y590510D01*
X121385D01*
X120384Y589509D01*
Y588235D01*
X121109Y587509D01*
Y586100D01*
X120609Y585600D01*
X118800D01*
X118300Y586100D01*
Y589275D01*
X118773Y589748D01*
G01X129795Y612519D02*
X129831Y612483D01*
Y610308D01*
X129900Y610239D01*
Y602092D01*
X129408Y601600D01*
X128713D01*
X128221Y602092D01*
Y610945D01*
G01X117197Y615669D02*
X109930Y622936D01*
X108064D01*
X104000Y627000D01*
G01X126646Y615669D02*
X128220Y614095D01*
G01X123496Y615669D02*
X125070Y614095D01*
G01X120347Y615669D02*
Y615641D01*
X118805Y614099D01*
G01X129795Y615669D02*
X131369Y614095D01*
G01X119650Y707800D02*
Y714300D01*
G01D02*
Y716750D01*
X118060Y718340D01*
Y721650D01*
G01X98450Y681900D02*
X102450D01*
G01X111400Y732300D02*
X113085Y730615D01*
X118876D01*
X120620Y732359D01*
Y737950D01*
G01X101800Y737200D02*
X102700Y736300D01*
Y732350D01*
X102650Y732300D01*
G01D02*
X102900Y732050D01*
X106900D01*
G01X111400Y732300D02*
X107150D01*
X106900Y732050D01*
G01X120620Y721650D02*
Y726940D01*
X118920Y728640D01*
X112266D01*
X112253Y728653D01*
X111400Y727800D01*
G01X102650D02*
X102900Y728050D01*
X106900D01*
G01D02*
X107150Y727800D01*
X111400D01*
G01X102100Y723300D02*
X102650Y723850D01*
Y727800D01*
G01X132400Y732300D02*
X131003Y730903D01*
X124771D01*
X123180Y732494D01*
Y737950D01*
G01Y721650D02*
Y727304D01*
X124804Y728928D01*
X131272D01*
X132400Y727800D01*
G01X125740Y737950D02*
Y741300D01*
X124350Y742690D01*
Y744850D01*
X124800Y745300D01*
G01D02*
X128850D01*
X128950Y745200D01*
G01X126000Y780750D02*
Y784900D01*
X125900Y785000D01*
G01X118200Y782300D02*
X120900Y785000D01*
X125900D01*
G01X114750Y756000D02*
X111300D01*
G01X122700Y761300D02*
Y756300D01*
G01X126000Y777250D02*
X128500Y774750D01*
Y768500D01*
G01X122700Y761300D02*
Y762700D01*
X128500Y768500D01*
G01X122700Y756300D02*
Y753700D01*
X121100Y752100D01*
X120500D01*
G01X118250Y756000D02*
Y753850D01*
X120000Y752100D01*
X120500D01*
G01X162500Y222000D02*
X160000Y219500D01*
X156740D01*
G01X162900Y237540D02*
X156740Y231380D01*
Y228500D01*
G01X166890Y237540D02*
X162900D01*
G01X134800Y329600D02*
X136100Y328300D01*
X138279D01*
X141607Y331628D01*
X146754D01*
X150421Y327961D01*
Y327936D01*
X159935D01*
G01X145168Y317749D02*
X145767D01*
X149564Y321546D01*
Y322277D01*
G01X145168Y317749D02*
X145039Y317878D01*
Y321826D01*
X145563Y322350D01*
G01X149564Y322277D02*
X151540Y324253D01*
X161791D01*
X163850Y326312D01*
Y329077D01*
X161116Y331811D01*
X152435D01*
G01X142063Y322350D02*
X138059D01*
X137768Y322641D01*
G01X144667Y329390D02*
X142077Y326800D01*
X138684D01*
X137768Y325884D01*
Y322641D01*
G01X146000Y370750D02*
X145965Y370785D01*
Y374500D01*
G01D02*
Y380050D01*
G01X160850Y379200D02*
Y375200D01*
G01D02*
Y371945D01*
X161303Y371492D01*
Y371436D01*
X161311Y371428D01*
G01X136264Y373985D02*
X138905Y371344D01*
Y368565D01*
G01X141216Y361163D02*
Y366254D01*
X138905Y368565D01*
G01X148900Y363200D02*
Y366165D01*
X147815Y367250D01*
X146000D01*
G01X145027Y361163D02*
X146863D01*
X148900Y363200D01*
G01X150000Y388984D02*
X158655D01*
X163900Y383739D01*
Y368900D01*
X160303Y365303D01*
G01X156573Y371799D02*
X152175D01*
X151760Y372214D01*
G01X150000Y383079D02*
Y373974D01*
X151760Y372214D01*
G01X150000Y392921D02*
X156021D01*
X157065Y393965D01*
Y395331D01*
G01D02*
X157100Y395366D01*
Y396600D01*
X154050Y399650D01*
Y402200D01*
G01X160204Y384199D02*
X157387Y387016D01*
X150000D01*
G01X157350Y379200D02*
Y380249D01*
X160204Y383103D01*
Y384199D01*
G01X155700Y409750D02*
X151600D01*
G01X136500Y417400D02*
X147652D01*
X151600Y413452D01*
Y409750D01*
G01X133812Y414712D02*
Y410605D01*
X134571Y409846D01*
G01X150000Y390953D02*
X160547D01*
X161800Y389700D01*
G01D02*
X164937D01*
X166321Y388316D01*
G01X155657Y384291D02*
X154901Y385047D01*
X150000D01*
G01X134571Y406346D02*
X132778Y404553D01*
Y401706D01*
G01X140047Y395950D02*
Y398223D01*
X139360Y398910D01*
X134984D01*
X132778Y401116D01*
Y401706D01*
G01X135250Y443740D02*
Y444643D01*
X137344Y446737D01*
G01X134768Y429438D02*
Y431029D01*
X143976Y440237D01*
Y455526D01*
X146200Y457750D01*
G01X133812Y414712D02*
X136500Y417400D01*
G01X143248Y420306D02*
X142870Y420684D01*
Y424630D01*
X143073Y424833D01*
G01X152978Y435602D02*
Y434738D01*
X143073Y424833D01*
G01X162577Y447721D02*
X163440Y448584D01*
Y453020D01*
G01X161043Y480649D02*
Y476817D01*
X166515Y471345D01*
Y469453D01*
X170192Y465776D01*
G01X169399Y470740D02*
X162754Y477385D01*
Y482361D01*
X164192Y483799D01*
G01X142145Y480649D02*
Y479555D01*
X143547Y478153D01*
Y477976D01*
G01X146431Y453528D02*
X147209D01*
X150632Y450105D01*
G01X151594Y480649D02*
Y468944D01*
X152100Y468438D01*
Y463150D01*
X150200Y461250D01*
Y458567D01*
X150174Y458541D01*
G01X150632Y453605D02*
X150174Y454063D01*
Y458541D01*
G01X148444Y480649D02*
Y472300D01*
X149700Y471044D01*
Y467076D01*
X149461Y466837D01*
G01D02*
X149437D01*
X146200Y463600D01*
Y461250D01*
G01X175000Y466000D02*
Y468500D01*
X164192Y479308D01*
Y480649D01*
G01X133000Y461250D02*
X137000D01*
G01X134090Y465780D02*
Y466000D01*
X137557Y469467D01*
Y481244D01*
X138995Y482682D01*
Y483799D01*
G01X138930Y465660D02*
X138995Y465725D01*
Y480649D01*
G01X141500Y461400D02*
Y467524D01*
X140707Y468317D01*
Y476551D01*
X140457Y476801D01*
Y479399D01*
X140707Y479649D01*
Y482361D01*
X142145Y483799D01*
G01X164222Y457919D02*
X161360Y455057D01*
Y450610D01*
X159829Y449079D01*
X159239D01*
G01X154743Y480649D02*
Y471557D01*
X156638Y469662D01*
Y463038D01*
X154700Y461100D01*
G01X154500Y466000D02*
Y469400D01*
X153305Y470595D01*
Y482361D01*
X154743Y483799D01*
G01X158790Y458450D02*
X158063Y459177D01*
Y470537D01*
X156455Y472145D01*
Y482361D01*
X157893Y483799D01*
G01X160300Y465900D02*
Y470400D01*
X157893Y472807D01*
Y480649D01*
G01X164268Y462983D02*
X161119Y459834D01*
Y457019D01*
X159820Y455720D01*
Y453247D01*
X159082Y452509D01*
G01X144520Y466070D02*
X144300Y465850D01*
Y459000D01*
X142050Y456750D01*
X142000D01*
G01X144520Y466070D02*
X145400Y466950D01*
Y478493D01*
X143845Y480048D01*
Y482349D01*
X145295Y483799D01*
G01X168320Y455278D02*
Y462990D01*
X162790Y468520D01*
Y470930D01*
X159605Y474115D01*
Y482361D01*
X161043Y483799D01*
G01X142145Y493248D02*
X140571Y491674D01*
G01X142145Y490098D02*
X140570Y488523D01*
G01X164192Y486948D02*
X162618Y485374D01*
G01X151594Y493248D02*
X150020Y491674D01*
G01X157893Y486948D02*
X156319Y485374D01*
G01X145295Y493248D02*
X143721Y491674D01*
G01X145295Y490098D02*
X143721Y488524D01*
G01X145295Y486948D02*
X143721Y485374D01*
G01X154743Y493248D02*
Y493247D01*
X153170Y491674D01*
G01X151594Y486948D02*
X150020Y485374D01*
G01X151594Y483799D02*
X150020Y482225D01*
G01X148444Y486948D02*
X146870Y485374D01*
G01X148444Y490098D02*
X146870Y488524D01*
G01X164192Y490098D02*
X162618Y488524D01*
G01X164192Y493248D02*
X162618Y491674D01*
G01X135846Y493248D02*
X134272Y491674D01*
G01X135846Y490098D02*
X134272Y488524D01*
G01X135846Y486948D02*
X134272Y485374D01*
G01X138995Y493248D02*
X137421Y491674D01*
G01X138995Y486948D02*
X137421Y485374D01*
G01X142145Y486948D02*
X140571Y485374D01*
G01X157893Y490098D02*
X156318Y488523D01*
G01X157893Y493248D02*
X156319Y491674D01*
G01X154743Y486948D02*
X153169Y485374D01*
G01X154743Y490098D02*
X153169Y488524D01*
G01X161043Y493248D02*
X159469Y491674D01*
G01X161043Y490098D02*
X159469Y488524D01*
G01X161043Y486948D02*
X159469Y485374D01*
G01X151594Y490098D02*
X150020Y488524D01*
G01X138995Y490098D02*
X137421Y488524D01*
G01X164192Y540492D02*
X165766Y542066D01*
G01X145295Y534192D02*
X143721Y532618D01*
G01X138995Y537342D02*
X137421Y535768D01*
G01X138995Y540492D02*
X137421Y542066D01*
G01X138995Y534192D02*
X137421Y532618D01*
G01X135846Y540492D02*
X134272Y542066D01*
G01X135846Y537342D02*
X134272Y535768D01*
G01X142145Y537342D02*
X140570Y535767D01*
G01X142145Y540492D02*
X140571Y538918D01*
X137421D01*
G01X148444Y540492D02*
Y540543D01*
X147000Y541987D01*
Y547287D01*
X143251Y551036D01*
X142951D01*
G01X145295Y543641D02*
X143619Y545317D01*
Y547371D01*
X142761Y548229D01*
X142274D01*
X140276Y550227D01*
Y557439D01*
X149137Y566300D01*
X161280D01*
G01X154743Y537342D02*
Y536000D01*
X155113Y535630D01*
X156085D01*
X156455Y536000D01*
Y538699D01*
X156100Y539054D01*
X153343D01*
X153188Y538899D01*
G01X161043Y534192D02*
X162617Y535766D01*
G01X148444Y537342D02*
Y537379D01*
X146869Y538954D01*
G01X148444Y534192D02*
X147000Y535636D01*
X146964D01*
X146858Y535742D01*
G01X157893Y543641D02*
Y542400D01*
X157393Y541900D01*
X156800D01*
X156300Y542400D01*
Y544853D01*
X156800Y545353D01*
X158488D01*
X159537Y546402D01*
Y548256D01*
G01X157893Y540492D02*
X159449Y542048D01*
G01X157893Y537342D02*
X159449Y538898D01*
G01X157893Y534192D02*
X159443Y532642D01*
X159456D01*
G01X161043Y540492D02*
X162617Y542066D01*
G01X161043Y537342D02*
X162617Y538916D01*
G01X151594Y543641D02*
X153100Y545147D01*
Y549038D01*
X149975Y552163D01*
Y557125D01*
X149126Y557974D01*
X146814D01*
X145913Y557073D01*
Y551399D01*
X145514Y551000D01*
X144949D01*
X144550Y551399D01*
Y556100D01*
X144050Y556600D01*
X143451D01*
X142951Y556100D01*
Y555636D01*
G01X151594Y540492D02*
X151556D01*
X149981Y538917D01*
G01X151594Y537342D02*
X153131Y535805D01*
Y535768D01*
X153132Y535767D01*
G01X151594Y534192D02*
Y533100D01*
X151094Y532600D01*
X150485D01*
X149985Y533100D01*
Y535771D01*
G01X154743Y540492D02*
X153251Y541984D01*
Y542021D01*
X153194Y542078D01*
G01X153187Y532636D02*
X154743Y534192D01*
G01X142145D02*
X140571Y532618D01*
G01X145295Y537342D02*
Y537376D01*
X143718Y538953D01*
G01X145295Y540492D02*
X145264D01*
X143686Y542070D01*
G01X135846Y534192D02*
X134272Y532618D01*
G01X164192Y534192D02*
X162618Y532618D01*
G01X164192Y537342D02*
X165766Y538916D01*
G01X174500Y561500D02*
Y553397D01*
X171082Y549979D01*
X168497D01*
X165904Y547386D01*
Y545353D01*
X164192Y543641D01*
G01Y546791D02*
Y546912D01*
X172362Y555082D01*
Y581862D01*
X175500Y585000D01*
X177187D01*
G01X145295Y546791D02*
Y546933D01*
X143124Y549104D01*
X142637D01*
X141226Y550516D01*
Y556373D01*
X148853Y564000D01*
X161280D01*
G01X151594Y546791D02*
Y549006D01*
X149100Y551500D01*
Y554787D01*
X147451Y556436D01*
G01X142394Y596771D02*
X140956Y595333D01*
Y591675D01*
X140481Y591200D01*
X138975D01*
X138500Y590725D01*
Y589775D01*
X138975Y589300D01*
X140481D01*
X140956Y588825D01*
Y587875D01*
X140481Y587400D01*
X138975D01*
X138500Y586925D01*
Y585975D01*
X138975Y585500D01*
X140481D01*
X140956Y585025D01*
Y584075D01*
X140481Y583600D01*
X138975D01*
X138500Y583125D01*
Y582175D01*
X138975Y581700D01*
X140481D01*
X140956Y581225D01*
Y579800D01*
X141456Y579300D01*
X143468D01*
X143968Y579800D01*
Y588898D01*
G01X157893Y546791D02*
Y549607D01*
X156200Y551300D01*
Y555700D01*
X152800Y559100D01*
X149200D01*
X148700Y559600D01*
Y561800D01*
X149200Y562300D01*
X154525D01*
X155000Y561825D01*
Y560100D01*
X155500Y559600D01*
X156400D01*
X156900Y560100D01*
Y562000D01*
X157400Y562500D01*
X158800D01*
X159300Y562000D01*
Y551856D01*
X159800Y551356D01*
X160700D01*
G01X131500Y584000D02*
Y581542D01*
X132583Y580458D01*
X136757D01*
X136769Y580470D01*
X138769Y578470D01*
G01X136095Y612519D02*
X137669Y610945D01*
G01X136095Y593622D02*
X136800D01*
X137300Y593122D01*
Y583316D01*
X136784Y582800D01*
X135021D01*
X134521Y583300D01*
Y595196D01*
G01X151843Y599921D02*
Y605000D01*
X152343Y605500D01*
X153200D01*
X153554Y605146D01*
Y598800D01*
X153101Y598347D01*
X150269D01*
G01X154992Y612519D02*
Y612521D01*
X156566Y614095D01*
G01X142394Y599921D02*
X143968Y601495D01*
G01X142394Y612519D02*
Y612533D01*
X140821Y614106D01*
G01X164441Y599921D02*
X164479Y599883D01*
X166652D01*
X167936Y598600D01*
X174500D01*
X175000Y599100D01*
Y606300D01*
X174500Y606800D01*
X172900D01*
X172400Y606300D01*
Y602555D01*
X171895Y602050D01*
X166570D01*
X166016Y601496D01*
G01X158142Y612519D02*
X158104Y612481D01*
Y608396D01*
X159600Y606900D01*
X166400D01*
X166900Y607400D01*
Y608300D01*
X166400Y608800D01*
X160900D01*
X159716Y609984D01*
Y610945D01*
G01X158142Y596771D02*
X159716Y595197D01*
G01X164441Y612519D02*
X165142Y613220D01*
X170200D01*
X170600Y613620D01*
Y615000D01*
X171200Y615600D01*
X172900D01*
X173300Y615200D01*
Y610400D01*
X172800Y609900D01*
X166516D01*
X166016Y610400D01*
Y610944D01*
G01X148693Y596771D02*
Y597907D01*
X148240Y598360D01*
X147115D01*
G01X148693Y599921D02*
Y602094D01*
X147754Y603033D01*
X144067D01*
X143300Y603800D01*
Y604800D01*
X143800Y605300D01*
X150268D01*
X150968Y604600D01*
Y602196D01*
X150268Y601496D01*
G01X151843Y612519D02*
Y611743D01*
X151806Y611706D01*
Y610000D01*
X151099Y609293D01*
X146893D01*
X146300Y608700D01*
Y606975D01*
X146800Y606475D01*
X156600D01*
X157100Y606975D01*
Y608900D01*
X156600Y609400D01*
X153900D01*
X153417Y609883D01*
Y610945D01*
G01X154992Y599921D02*
Y605100D01*
X155492Y605600D01*
X156700D01*
X157200Y605100D01*
Y603500D01*
X157700Y603000D01*
X159216D01*
X159716Y603500D01*
Y604645D01*
G01X161291Y596771D02*
X162865Y598345D01*
X166015D01*
G01X139244Y612519D02*
X140818Y610945D01*
G01X132945Y612519D02*
X134520Y610944D01*
G01X132945Y596771D02*
Y595702D01*
X131507Y594264D01*
Y590935D01*
X132907Y589535D01*
Y586000D01*
X131500Y584593D01*
Y584000D01*
G01X132945Y615669D02*
X134519Y614095D01*
G01X158142Y615669D02*
X159716Y614095D01*
G01X164441Y615669D02*
Y616900D01*
X164941Y617400D01*
X168500D01*
X169000Y616900D01*
Y614595D01*
X168500Y614095D01*
X162867D01*
G01X148693Y615669D02*
Y615648D01*
X147141Y614096D01*
G01X145543Y615669D02*
X147100Y617226D01*
X150251D01*
G01X136095Y618818D02*
X134603Y617326D01*
X134581D01*
X134521Y617266D01*
G01X140650Y732300D02*
X142003Y730947D01*
X143747D01*
X144400Y731600D01*
G01X140650Y727800D02*
X141822Y728972D01*
X143628D01*
X144400Y728200D01*
G01X167200Y723150D02*
X165692D01*
X163225Y720683D01*
G01X167200Y727900D02*
X168129Y728829D01*
Y734971D01*
X165980Y737120D01*
X161050D01*
G01X137150Y732300D02*
X132400D01*
G01X139642Y736317D02*
X137150Y733825D01*
Y732300D01*
G01Y727800D02*
X132400D01*
G01X139480Y724027D02*
X137150Y726357D01*
Y727800D01*
G01X167200Y748900D02*
X168349Y747751D01*
Y741601D01*
X166428Y739680D01*
X161050D01*
G01X153700Y740650D02*
X149649D01*
X149241Y740242D01*
G01X153700Y740650D02*
X155290Y742240D01*
X161050D01*
G01X164500Y774750D02*
X163148Y773398D01*
Y771652D01*
X163800Y771000D01*
G01X164500Y778250D02*
Y783000D01*
G01Y778250D02*
X166275D01*
X169029Y775496D01*
G01X160000Y774750D02*
X161173Y773577D01*
Y771773D01*
X160400Y771000D01*
G01X160000Y778250D02*
Y783000D01*
G01Y778250D02*
X158593D01*
X156126Y775783D01*
G01X163600Y757500D02*
X163750Y757650D01*
X167200D01*
G01X164500Y783000D02*
X163119Y784381D01*
Y790119D01*
X165220Y792220D01*
X170150D01*
G01X153850D02*
X159097D01*
X161144Y790173D01*
Y784144D01*
X160000Y783000D01*
G01X164500Y816250D02*
X163124Y817626D01*
Y819324D01*
X163800Y820000D01*
G01X170150Y794780D02*
X165952D01*
X163019Y797713D01*
Y802519D01*
X164500Y804000D01*
G01Y812750D02*
X164550Y812800D01*
X168100D01*
G01X164500Y812750D02*
X164250Y812500D01*
Y808500D01*
G01D02*
X164500Y808250D01*
Y804000D01*
G01X160000Y816250D02*
X161149Y817399D01*
Y819251D01*
X160400Y820000D01*
G01X153850Y794780D02*
X158234D01*
X161044Y797592D01*
Y802956D01*
X160000Y804000D01*
G01Y812750D02*
X159950Y812800D01*
X156400D01*
G01X160000Y812750D02*
X160250Y812500D01*
Y808500D01*
G01D02*
X160000Y808250D01*
Y804000D01*
G01X146500Y795750D02*
X142716D01*
X142492Y795526D01*
G01X146500Y795750D02*
X148090Y797340D01*
X153850D01*
G01X156300Y887970D02*
Y882676D01*
X155661Y882037D01*
Y830685D01*
X162912Y823434D01*
Y820888D01*
X163800Y820000D01*
G01X153150Y887970D02*
Y882677D01*
X153686Y882141D01*
Y829866D01*
X160937Y822615D01*
Y820537D01*
X160400Y820000D01*
G01X162599Y887970D02*
Y882677D01*
X163218Y882058D01*
Y827826D01*
X179722Y811322D01*
Y780788D01*
X168062Y769128D01*
Y765362D01*
X167600Y764900D01*
G01X191018Y199806D02*
X186418D01*
G01X191018Y209858D02*
Y199806D01*
G01X183400Y221600D02*
X186418Y218582D01*
Y199806D01*
G01X196018Y209858D02*
Y204200D01*
G01D02*
Y199806D01*
G01X171094Y237961D02*
X170673Y237540D01*
X166890D01*
G01X196018Y241354D02*
Y249032D01*
X193950Y251100D01*
G01X194065Y289501D02*
X193900Y289336D01*
Y274372D01*
G01X190565Y289501D02*
X189170Y288106D01*
Y281503D01*
X190362Y280311D01*
Y272907D01*
X194324Y268945D01*
X220695D01*
X226300Y263340D01*
Y244555D01*
X220930Y239185D01*
Y225364D01*
X222930Y223364D01*
X226929D01*
X231399Y218894D01*
X283993D01*
X294499Y229400D01*
X359712D01*
X361675Y231363D01*
Y257976D01*
X369499Y265800D01*
X381700D01*
G01X171094Y243961D02*
Y247494D01*
X171100Y247500D01*
G01X167700Y296882D02*
X168895Y295687D01*
X174293D01*
X198793Y320187D01*
Y385493D01*
X231937Y418637D01*
Y429663D01*
X227004Y434596D01*
Y441360D01*
X223300Y445064D01*
Y458900D01*
X226800Y462400D01*
Y468905D01*
X225603Y470102D01*
X225595Y475495D01*
X226637Y476537D01*
X227700D01*
G01X167700Y292517D02*
X168895Y293712D01*
X175112D01*
X200768Y319368D01*
Y384674D01*
X233913Y417819D01*
Y419455D01*
X233912Y419456D01*
Y430482D01*
X228979Y435415D01*
Y442179D01*
X225275Y445883D01*
Y458081D01*
X228775Y461581D01*
Y469724D01*
X227700Y470799D01*
Y472200D01*
G01X182604Y446672D02*
Y442854D01*
G01X197841Y430392D02*
X200785D01*
X202652Y432259D01*
G01X184116Y458560D02*
X182521Y456965D01*
Y450815D01*
X182589Y450747D01*
G01D02*
Y446687D01*
X182604Y446672D01*
G01X185200Y466000D02*
X178996Y472204D01*
X176903D01*
X169053Y480054D01*
Y482361D01*
X170491Y483799D01*
G01X185200Y466000D02*
Y463144D01*
X184116Y462060D01*
G01X192733Y458082D02*
X192023D01*
X188150Y461955D01*
G01X196239Y462262D02*
Y461588D01*
X192733Y458082D01*
G01X179940Y480649D02*
X181514Y479075D01*
G01X184216Y482624D02*
X188590D01*
X196300Y474914D01*
Y473356D01*
X197426Y472230D01*
G01D02*
X212437Y457219D01*
Y454613D01*
X213500Y453550D01*
G01X197426Y472230D02*
X198274Y473078D01*
G01X183090Y480649D02*
X187771D01*
X194325Y474095D01*
Y472537D01*
X200402Y466460D01*
G01X209750Y465000D02*
X208542Y466208D01*
X206471D01*
X201024Y471655D01*
Y476179D01*
X198180Y479023D01*
G01D02*
X197228Y478071D01*
G01X198180Y479023D02*
X187392Y489811D01*
X187060D01*
X186359Y490512D01*
X183504D01*
X183090Y490098D01*
G01X173641Y480649D02*
X178690Y475600D01*
X185600D01*
X189275Y471925D01*
Y470882D01*
G01X192733Y461582D02*
X189275Y465040D01*
Y470882D01*
G01X172800Y457750D02*
X179328D01*
X179599Y457479D01*
G01X172800Y461250D02*
Y467339D01*
X169399Y470740D01*
G01X177377Y461749D02*
X177138Y461988D01*
Y467624D01*
X165904Y478858D01*
Y482361D01*
X167342Y483799D01*
G01X180000Y466000D02*
X178702Y467298D01*
Y468298D01*
X167342Y479658D01*
Y480649D01*
G01X192173Y466075D02*
Y472727D01*
X187800Y477100D01*
X180340D01*
X176791Y480649D01*
G01X200217Y517593D02*
X189393D01*
X183945Y512145D01*
X183090D01*
G01X179940D02*
X181395Y513600D01*
X183684D01*
X190151Y520067D01*
X198567D01*
X199442Y520942D01*
Y521127D01*
X200753Y522438D01*
X200938D01*
X201100Y522600D01*
X204200D01*
G01X176791Y512145D02*
X178365Y510571D01*
G01X173641Y512145D02*
X175215Y510571D01*
G01X170491Y512145D02*
X172065Y510571D01*
G01X202700Y495400D02*
X199728Y492428D01*
X198709D01*
X197126Y490845D01*
G01D02*
X196198D01*
X187496Y499547D01*
X183090D01*
G01X170491Y502696D02*
X172065Y501122D01*
G01X173641Y493248D02*
X175215Y491674D01*
G01X173641Y499547D02*
X175215Y497973D01*
G01X170491Y493248D02*
X172065Y491674D01*
G01X173641Y486948D02*
X175215Y485374D01*
G01X176791Y483799D02*
X175217Y482225D01*
G01X173641Y502696D02*
X175215Y501122D01*
G01X176791Y502696D02*
X178365Y501122D01*
G01X183090Y483799D02*
X184663Y485372D01*
X184664D01*
G01X170491Y496397D02*
X172065Y494823D01*
G01X176791Y493248D02*
X178365Y491674D01*
G01X179940Y490098D02*
X181514Y488524D01*
G01X183090Y486948D02*
X184664Y488522D01*
G01X173641Y496397D02*
X175215Y494823D01*
G01X202999Y474804D02*
Y476998D01*
X188424Y491573D01*
X188420D01*
G01X181771D02*
X181615D01*
X179940Y493248D01*
G01X170491Y499547D02*
X172065Y497973D01*
G01X176791Y496397D02*
X178365Y494823D01*
G01X170491Y486948D02*
X172065Y485374D01*
G01X173641Y483799D02*
X172067Y482225D01*
G01X220253Y498347D02*
X218438Y500162D01*
X208395D01*
X204423Y504134D01*
X181378D01*
X179940Y502696D01*
G01Y496397D02*
X181378Y497835D01*
X186971D01*
X196199Y488607D01*
X198946D01*
X200917Y490578D01*
G01X199829Y485947D02*
X198629Y487147D01*
X196048D01*
X186798Y496397D01*
X183090D01*
G01X176791Y499547D02*
X178365Y497973D01*
G01X198279Y496230D02*
X194755D01*
X190000Y500985D01*
X181378D01*
X179940Y499547D01*
G01X198279Y496230D02*
X199583D01*
X202613Y499260D01*
X203365D01*
X203500Y499125D01*
G01X204700Y479804D02*
X202696D01*
X196778Y485722D01*
X196001D01*
X188475Y493248D01*
X183090D01*
G01X170491Y505846D02*
X172065Y504272D01*
G01X173641Y505846D02*
X175216Y504271D01*
G01X170491Y508996D02*
X172065Y507422D01*
G01X176791Y505846D02*
X178365Y504272D01*
G01X167342Y490098D02*
X165768Y488524D01*
G01X167342Y493248D02*
X165768Y491674D01*
G01X170491Y490098D02*
X172065Y488524D01*
G01X198803Y501591D02*
X195420D01*
X194315Y502696D01*
X183090D01*
G01X173641Y490098D02*
X175216Y488523D01*
G01X176791Y486948D02*
X178365Y485374D01*
G01X176791Y490098D02*
X178365Y488524D01*
G01X179940Y486948D02*
X181514Y485374D01*
G01X170491Y515295D02*
X172065Y513721D01*
G01X173641Y515295D02*
X175215Y513721D01*
G01X176791Y540492D02*
X177765D01*
X179303Y538954D01*
X185613D01*
X196251Y549592D01*
X196886D01*
X197763Y550469D01*
X199879D01*
X199924Y550424D01*
X200000D01*
G01X176791Y543641D02*
X177765D01*
X179377Y545253D01*
X180577D01*
X181552Y546228D01*
Y547428D01*
X183124Y549000D01*
X183902D01*
X192976Y558074D01*
X193062D01*
X194772Y559784D01*
Y559870D01*
X195482Y560580D01*
Y562264D01*
X196782Y563564D01*
G01X170491Y537342D02*
X172065Y535768D01*
G01X175360Y580890D02*
X173787Y579317D01*
Y570237D01*
X178425Y565599D01*
Y554846D01*
X171808Y548229D01*
X169896D01*
X168780Y547113D01*
Y545079D01*
X167342Y543641D01*
G01X183090Y531043D02*
X184231D01*
X191688Y538500D01*
X203300D01*
G01X170491Y527893D02*
X172065Y526319D01*
G01X176791Y531043D02*
X178365Y529469D01*
G01X196882Y542190D02*
X192902D01*
X184904Y534192D01*
X183090D01*
G01X196882Y542190D02*
X204390D01*
X206700Y544500D01*
G01X173641Y531043D02*
X175215Y529469D01*
G01X179940Y534192D02*
X181632Y532500D01*
X184450D01*
X191875Y539925D01*
X201925D01*
X202338Y540338D01*
X204862D01*
X206700Y538500D01*
G01X183090Y537342D02*
X185578D01*
X195999Y547763D01*
X201438D01*
X202539Y546662D01*
X204162D01*
X206000Y548500D01*
X206700D01*
G01X170491Y531043D02*
X172065Y529469D01*
G01X173641Y524744D02*
X175215Y523170D01*
G01X176791Y524744D02*
X178365Y523170D01*
G01X198000Y523000D02*
X183717D01*
X183685Y523032D01*
X181652D01*
X179940Y524744D01*
G01X183090D02*
X183982D01*
X186600Y527362D01*
X202782D01*
X203314Y527894D01*
G01X173641Y537342D02*
X175216Y535767D01*
G01X202300Y559763D02*
X198697D01*
X197622Y558688D01*
Y558602D01*
X196590Y557570D01*
X196504D01*
X184113Y545179D01*
X182453D01*
X180915Y543641D01*
X179940D01*
G01X173641Y527893D02*
X175215Y526319D01*
G01X203000Y534500D02*
X200425Y537075D01*
X191501D01*
X183926Y529500D01*
X181483D01*
X179940Y531043D01*
G01X198000Y529500D02*
X187500D01*
X184455Y526455D01*
X181378D01*
X179940Y527893D01*
G01X198000Y534500D02*
X190164D01*
X183557Y527893D01*
X183090D01*
G01X179940Y537342D02*
X181378Y535904D01*
X185378D01*
X195812Y546338D01*
X200847D01*
X202685Y544500D01*
X203300D01*
G01X183090Y540492D02*
X185474D01*
X197644Y552662D01*
X204862D01*
X206700Y554500D01*
G01X173641Y534192D02*
X175215Y532618D01*
G01X179940Y540492D02*
X180915D01*
X182526Y542103D01*
X185069D01*
X197466Y554500D01*
X203271D01*
X203447Y554676D01*
Y554684D01*
X203304D01*
G01X176791Y537342D02*
X178365Y535768D01*
G01X205700Y559763D02*
Y558917D01*
X204283Y557500D01*
X198536D01*
X197181Y556145D01*
X197095D01*
X185254Y544304D01*
X183753D01*
X183090Y543641D01*
G01X170491Y534192D02*
X172065Y532618D01*
G01X185500Y567700D02*
X186340Y566860D01*
Y564056D01*
X185500Y563216D01*
Y557947D01*
X175916Y548363D01*
Y548337D01*
X175079Y547500D01*
Y546196D01*
X173962Y545079D01*
X173046D01*
X171608Y543641D01*
X170491D01*
G01X176791Y515295D02*
X178365Y513721D01*
G01X173641Y540492D02*
X175215Y538918D01*
G01X167342Y534192D02*
X168916Y535766D01*
G01X170491Y540492D02*
X172065Y538918D01*
G01X173641Y543641D02*
X174616D01*
X176228Y545253D01*
X177428D01*
X178402Y546227D01*
Y547446D01*
X191922Y560966D01*
Y564138D01*
X194839Y567055D01*
Y577651D01*
X193610Y578880D01*
G01X167342Y540492D02*
X168916Y542066D01*
G01X167342Y537342D02*
X168916Y538916D01*
G01X176791Y534192D02*
X178365Y532618D01*
G01X201500Y570282D02*
Y568300D01*
X198082Y564882D01*
Y564864D01*
X196782Y563564D01*
G01X197334Y567232D02*
X193347Y563245D01*
Y560375D01*
X191046Y558074D01*
X190960D01*
X179940Y547054D01*
Y546791D01*
G01X197500Y570282D02*
Y567490D01*
X197334Y567324D01*
Y567232D01*
G01X202610Y563580D02*
X201256Y562226D01*
X199144D01*
X196197Y559279D01*
Y559193D01*
X195078Y558074D01*
X194992D01*
X183709Y546791D01*
X183090D01*
G01X176791D02*
Y548000D01*
X186925Y558134D01*
Y562625D01*
X189500Y565200D01*
Y567700D01*
G01D02*
Y570750D01*
G01X185500Y567700D02*
Y570750D01*
G01X178500Y576376D02*
X181275Y573601D01*
Y555134D01*
X173641Y547500D01*
Y546791D01*
G01X176500Y571500D02*
X179850Y568150D01*
Y555033D01*
X171608Y546791D01*
X170491D01*
G01X174500Y566500D02*
X177000Y564000D01*
Y554659D01*
X171445Y549104D01*
X169533D01*
X167905Y547476D01*
Y547354D01*
X167342Y546791D01*
G01X177187Y585000D02*
X181000D01*
G01X177187D02*
Y586239D01*
G01X175360Y580890D02*
X176810Y582340D01*
X180160D01*
X181000Y581500D01*
G01X195500Y586750D02*
X200250D01*
X202720Y589220D01*
X204910D01*
G01X191500Y586750D02*
X195500D01*
G01X191500D02*
X189750D01*
X187750Y584750D01*
G01X195500Y594250D02*
X198250D01*
X200720Y591780D01*
X204910D01*
G01X191500Y594250D02*
X195500D01*
G01X191500D02*
X189250D01*
X187500Y596000D01*
G01X195500Y598250D02*
X191500D01*
G01X195500D02*
X196000Y597750D01*
X199750D01*
X202100Y600100D01*
X204100D01*
G01X199500Y699250D02*
X198073D01*
X195788Y696965D01*
G01X199500Y704000D02*
X200742Y705242D01*
Y710758D01*
X198280Y713220D01*
X193350D01*
G01X171700Y719650D02*
X170293Y718243D01*
Y716607D01*
X171000Y715900D01*
G01X171700Y723150D02*
Y727900D01*
G01Y723150D02*
X173152D01*
X175505Y720797D01*
G01X171700Y727900D02*
X170104Y729496D01*
Y734804D01*
X172420Y737120D01*
X177350D01*
G01X167200Y719650D02*
X168318Y718532D01*
Y716618D01*
X167600Y715900D01*
G01X167200Y723150D02*
Y727900D01*
G01X199500Y733750D02*
X196250D01*
X195900Y733400D01*
G01X199500Y725000D02*
X200714Y723786D01*
Y718714D01*
X197780Y715780D01*
X193350D01*
G01X171700Y748900D02*
Y753150D01*
X171450Y753400D01*
G01X171700Y748900D02*
X170324Y747524D01*
Y741539D01*
X172183Y739680D01*
X177350D01*
G01X167200Y748900D02*
Y753150D01*
X167450Y753400D01*
G01X186000Y716750D02*
X182093D01*
X181873Y716530D01*
G01X186000Y716750D02*
X187590Y718340D01*
X193350D01*
G01X184700Y736150D02*
X183110Y734560D01*
X177350D01*
G01X189913Y736842D02*
X189221Y736150D01*
X184700D01*
G01X199500Y754750D02*
X197978D01*
X195489Y752261D01*
G01X199500Y759500D02*
X200648Y760648D01*
Y766352D01*
X198280Y768720D01*
X193350D01*
G01Y771280D02*
X199000D01*
X200742Y773022D01*
Y779257D01*
X199500Y780500D01*
G01X171000Y764900D02*
X170200Y764100D01*
Y762650D01*
X171700Y761150D01*
G01X165748Y887970D02*
Y882677D01*
X165193Y882122D01*
Y828645D01*
X181697Y812141D01*
Y779969D01*
X170037Y768309D01*
Y765863D01*
X171000Y764900D01*
G01X171700Y757650D02*
X175150D01*
X175300Y757500D01*
G01X171700Y757650D02*
X171450Y757400D01*
Y753400D01*
G01X167600Y764900D02*
X168225Y764275D01*
Y762175D01*
X167200Y761150D01*
G01Y757650D02*
X167450Y757400D01*
Y753400D01*
G01X186000Y772250D02*
X187590Y773840D01*
X193350D01*
G01X186000Y772250D02*
X185508Y771758D01*
X182092D01*
G01X175197Y887970D02*
Y882677D01*
X174616Y882096D01*
Y873543D01*
X170900Y869827D01*
Y829517D01*
X202150Y798267D01*
Y797650D01*
X203300Y796500D01*
G01X172048Y887970D02*
Y882677D01*
X172641Y882084D01*
Y874362D01*
X168925Y870646D01*
Y828698D01*
X200175Y797448D01*
Y796775D01*
X199900Y796500D01*
G01X199500Y789250D02*
X195950D01*
X195900Y789200D01*
G01X203300Y741000D02*
X202655Y741645D01*
Y742806D01*
X203536Y743687D01*
X214819D01*
X224317Y753185D01*
Y781552D01*
X175993Y829876D01*
Y866693D01*
X176900Y867600D01*
G01X199900Y741000D02*
X200680Y741780D01*
Y743625D01*
X202717Y745662D01*
X214000D01*
X222342Y754004D01*
Y780733D01*
X174018Y829057D01*
Y867082D01*
X173500Y867600D01*
G01X177500Y791250D02*
X177894Y791644D01*
Y800059D01*
X177092Y800861D01*
G01X177500Y791250D02*
X175910Y789660D01*
X170150D01*
G01X225900Y105350D02*
X224698D01*
X222354Y103006D01*
G01X222356Y133438D02*
Y128757D01*
X218756Y125157D01*
X217538D01*
X216461Y124080D01*
Y111992D01*
X221080Y107373D01*
X227070D01*
X227738Y106705D01*
Y104836D01*
X228985Y103589D01*
X235713D01*
G01Y98589D02*
X227659D01*
X227606Y98642D01*
G01X225900Y101850D02*
Y101561D01*
X223641Y99302D01*
G01X235713Y93589D02*
X228163D01*
G01X235713Y88589D02*
X228163D01*
G01X213607Y130425D02*
X219175D01*
X220300Y129300D01*
G01X206107Y134300D02*
X203740Y136667D01*
Y144334D01*
G01X235713Y108589D02*
X228818D01*
X227695Y109712D01*
Y118564D01*
X230508Y121377D01*
Y125315D01*
X228708Y127115D01*
G01X224600Y120050D02*
Y116880D01*
X224576Y116678D01*
G01X224900Y109350D02*
X221702D01*
X221418Y109634D01*
G01X207699Y143587D02*
Y147404D01*
X207369Y147734D01*
G01D02*
X205744D01*
X203740Y145730D01*
Y144334D01*
G01X211199Y143587D02*
Y147121D01*
X211919Y147841D01*
X214145D01*
G01X218979Y145011D02*
X216495Y147841D01*
X214145D01*
G01X201018Y209858D02*
Y200568D01*
X200300Y199850D01*
G01X206200Y247500D02*
X206018Y247318D01*
Y241354D01*
G01X201018D02*
Y245668D01*
X206350Y251000D01*
G01X204010Y289306D02*
Y274482D01*
X203900Y274372D01*
G01X206350Y251000D02*
X208150Y252800D01*
X209200D01*
G01X258500Y391200D02*
Y382002D01*
X225008Y348510D01*
X218892D01*
X214900Y344518D01*
Y312000D01*
X200510Y297610D01*
Y291194D01*
X200560Y291144D01*
Y289356D01*
X200510Y289306D01*
G01X236231Y283559D02*
X230559D01*
X230400Y283400D01*
G01X222200Y300500D02*
X232700Y290000D01*
X240700D01*
X241231Y289469D01*
Y283559D01*
G01X209988Y425645D02*
X210162Y425819D01*
Y429362D01*
X211313Y430513D01*
Y438026D01*
X212000Y438713D01*
G01X205601Y426212D02*
X205611Y426202D01*
Y425213D01*
X206086Y424738D01*
X209081D01*
X209988Y425645D01*
G01X207938Y431285D02*
X205601Y428948D01*
Y426212D01*
G01X215338Y436405D02*
Y438762D01*
X213288Y440812D01*
Y441945D01*
G01D02*
X217453D01*
X217500Y441992D01*
G01X235750Y419500D02*
Y431850D01*
X230738Y436862D01*
Y449662D01*
X228700Y451700D01*
Y456800D01*
X231812Y459912D01*
Y480388D01*
X230500Y481700D01*
Y494300D01*
X229500Y495300D01*
X227412D01*
G01X217998Y424771D02*
X224559Y431332D01*
Y441722D01*
X223050Y443231D01*
Y443298D01*
X221986Y444362D01*
X220294D01*
X219744Y443812D01*
X218279D01*
X218261Y443830D01*
X216739D01*
X216721Y443812D01*
X215288D01*
X213450Y445650D01*
Y446000D01*
G01X217998Y424771D02*
X214362D01*
X213488Y425645D01*
G01D02*
Y427409D01*
X215338Y429259D01*
Y431285D01*
G01X209450Y446000D02*
Y442283D01*
X209788Y441945D01*
G01X207938Y436405D02*
Y439638D01*
X209788Y441488D01*
Y441945D01*
G01X207938Y436405D02*
X204313D01*
X202270Y438448D01*
G01X202652Y432259D02*
X204238Y433845D01*
X207938D01*
G01X215338D02*
X217882D01*
X218959Y434922D01*
X220969D01*
G01D02*
Y431372D01*
G01X213250Y469000D02*
X215653D01*
X216404Y469751D01*
G01D02*
X217155Y469000D01*
X219750D01*
G01Y465000D02*
X217994D01*
X216282Y463288D01*
G01X213250Y465000D02*
X214570D01*
X216282Y463288D01*
G01X200402Y466460D02*
X210462Y456400D01*
Y454612D01*
X209400Y453550D01*
G01X200402Y466460D02*
X199510Y465568D01*
G01X209750Y469000D02*
X208933Y468183D01*
X207290D01*
X202999Y472474D01*
Y474804D01*
G01D02*
X204198D01*
G01X209750Y478000D02*
Y473750D01*
X210000Y473500D01*
G01X209750Y482000D02*
Y478000D01*
G01X213500Y450050D02*
Y446050D01*
X213450Y446000D01*
G01X209400Y450050D02*
X209450Y450000D01*
Y446000D01*
G01X228900Y446800D02*
X226700Y449000D01*
Y456816D01*
X230387Y460503D01*
Y478813D01*
X225800Y483400D01*
Y488201D01*
X227400Y489801D01*
Y491200D01*
G01X221750Y486600D02*
Y487750D01*
X219700Y489800D01*
G01X202700Y495400D02*
X204000Y494100D01*
X204001D01*
X206076Y492025D01*
X212205D01*
X212318Y491912D01*
X215211D01*
X215988Y491135D01*
Y488862D01*
X218250Y486600D01*
G01X223912Y495300D02*
X223300D01*
X220253Y498347D01*
G01D02*
X221152Y499246D01*
G01X204500Y490000D02*
X203500D01*
X202922Y490578D01*
X200917D01*
G01X209750Y490000D02*
X204500D01*
G01X203550Y484522D02*
X205028Y486000D01*
X209750D01*
G01X199829Y485947D02*
X201254Y484522D01*
X203550D01*
G01X203500Y499125D02*
Y499200D01*
G01Y499125D02*
X204799Y497826D01*
Y496600D01*
X205561Y495838D01*
X208412D01*
X209850Y494400D01*
G01X209750Y482000D02*
X207959D01*
X207026Y482933D01*
Y483956D01*
G01X204700Y479804D02*
Y481630D01*
X207026Y483956D01*
G01X198803Y501591D02*
X205728D01*
X208032Y499287D01*
X216954D01*
X222124Y494117D01*
Y492976D01*
X223900Y491200D01*
G01X200217Y517593D02*
X200395D01*
X202589Y519787D01*
X205787D01*
X207500Y521500D01*
X209750D01*
G01X221000Y521750D02*
X219164Y523586D01*
X217163D01*
G01X225000Y521850D02*
X224900Y521750D01*
X221000D01*
G01X225000Y521850D02*
X229000D01*
G01X217163Y523586D02*
X215336D01*
X213250Y521500D01*
G01X221000Y525750D02*
X220427Y526323D01*
X214073D01*
X213250Y525500D01*
G01X225000Y525750D02*
X229000D01*
G01X225000D02*
X221000D01*
G01X229000D02*
X232787D01*
X233101Y526064D01*
G01X204200Y522600D02*
X205100D01*
X208000Y525500D01*
X209750D01*
G01X203300Y538500D02*
X207300Y534500D01*
X209750D01*
G01X206700Y544500D02*
X208700Y542500D01*
X209750D01*
G01X206700Y538500D02*
X209750D01*
G01X203314Y527894D02*
X205420Y530000D01*
X208000D01*
G01X200000Y550424D02*
X201376D01*
X203300Y548500D01*
G01D02*
X203750D01*
X209750Y554500D01*
G01X202610Y563580D02*
X205500Y566470D01*
Y570750D01*
G01X206700Y548500D02*
X207750D01*
X209750Y550500D01*
G01X205500Y574250D02*
X207338Y572412D01*
Y564662D01*
X208500Y563500D01*
G01X202300Y559763D02*
X202763D01*
X204601Y561601D01*
X206461D01*
X206700Y561362D01*
X209385D01*
X211062Y563039D01*
Y569188D01*
X209750Y570500D01*
G01X226122Y563994D02*
X229605D01*
X230856Y565245D01*
Y566468D01*
G01D02*
X229304Y568020D01*
X226120D01*
G01X226200Y572412D02*
Y570600D01*
X226120Y570520D01*
Y568020D01*
G01X222500Y573220D02*
X223308Y572412D01*
X226200D01*
G01X222622Y563994D02*
X217140D01*
X216241Y563095D01*
G01X204100Y600100D02*
X204910Y599290D01*
Y594340D01*
G01X223500Y601500D02*
Y596673D01*
X224828Y595345D01*
Y592108D01*
X224500Y591780D01*
X221090D01*
G01X230250Y590000D02*
X229111Y588861D01*
X224839D01*
X224480Y589220D01*
X221090D01*
G01X230250Y593750D02*
Y590000D01*
G01Y586000D02*
X229364Y586886D01*
X224886D01*
X224660Y586660D01*
X221090D01*
G01X230250Y582400D02*
Y586000D01*
G01X204000Y695750D02*
X202661Y694411D01*
Y692639D01*
X203300Y692000D01*
G01X204000Y699250D02*
Y704000D01*
G01Y699250D02*
X205435D01*
X207977Y696708D01*
G01X204000Y704000D02*
X202717Y705283D01*
Y711217D01*
X204720Y713220D01*
X209650D01*
G01X199500Y695750D02*
X200686Y694564D01*
Y692786D01*
X199900Y692000D01*
G01X199500Y699250D02*
Y704000D01*
G01X217000Y712250D02*
X221200D01*
G01X217000D02*
X215410Y710660D01*
X209650D01*
G01X204000Y751250D02*
X202599Y749849D01*
Y748201D01*
X203300Y747500D01*
G01X199500Y751250D02*
X200624Y750126D01*
Y748224D01*
X199900Y747500D01*
G01X204000Y737250D02*
X202514Y738736D01*
Y740214D01*
X203300Y741000D01*
G01X204000Y733750D02*
X207350D01*
X207600Y733500D01*
G01X204000Y733750D02*
X203750Y733500D01*
Y729500D01*
G01D02*
X204000Y729250D01*
Y725000D01*
G01D02*
X202689Y723689D01*
Y718810D01*
X205719Y715780D01*
X209650D01*
G01X199500Y737250D02*
X200539Y738289D01*
Y740361D01*
X199900Y741000D01*
G01X199500Y733750D02*
X199750Y733500D01*
Y729500D01*
G01D02*
X199500Y729250D01*
Y725000D01*
G01X204000Y754750D02*
Y759500D01*
G01Y754750D02*
X205493D01*
X207931Y752312D01*
G01X204000Y759500D02*
X202623Y760877D01*
Y766623D01*
X204720Y768720D01*
X209650D01*
G01X199500Y754750D02*
Y759500D01*
G01X204000Y780500D02*
X202717Y779217D01*
Y773038D01*
X204475Y771280D01*
X209650D01*
G01X203750Y785000D02*
X204000Y784750D01*
Y780500D01*
G01X199750Y785000D02*
X199500Y784750D01*
Y780500D01*
G01X217000Y767750D02*
X218078Y768828D01*
Y771405D01*
X218080Y771407D01*
G01X217000Y767750D02*
X215410Y766160D01*
X209650D01*
G01X204000Y792750D02*
X202687Y794063D01*
Y795887D01*
X203300Y796500D01*
G01X204000Y789250D02*
X207550D01*
X207600Y789200D01*
G01X204000Y789250D02*
X203750Y789000D01*
Y785000D01*
G01X199500Y792750D02*
X200712Y793962D01*
Y795688D01*
X199900Y796500D01*
G01X199500Y789250D02*
X199750Y789000D01*
Y785000D01*
G01X261200Y105350D02*
X264817D01*
G01X250181Y93589D02*
X258100D01*
G01X261200Y101850D02*
X258354D01*
X257912Y101408D01*
G01X250181Y98589D02*
X256793D01*
X258029Y97353D01*
G01X250181Y88589D02*
X257961D01*
X260562Y85988D01*
G01X264443Y109587D02*
X262346Y107490D01*
X259118D01*
X255217Y103589D01*
X250181D01*
G01X236250Y139500D02*
X236000D01*
X233500Y137000D01*
G01X250478Y124804D02*
Y129381D01*
X248992Y130867D01*
G01X235713Y118589D02*
Y121213D01*
X239304Y124804D01*
X250478D01*
G01X258068Y110180D02*
X256477Y108589D01*
X250181D01*
G01X259331Y118580D02*
X259194D01*
X259185Y118589D01*
X250181D01*
G01X253978Y124804D02*
X254410D01*
X257422Y121792D01*
G01X236331Y233830D02*
X240380D01*
X240400Y233850D01*
G01X236231Y245001D02*
Y233930D01*
X236331Y233830D01*
G01X266231Y245001D02*
Y239669D01*
X266500Y239400D01*
G01X266231Y245001D02*
Y245705D01*
G01D02*
Y250100D01*
X268431Y252300D01*
X271870D01*
X289170Y235000D01*
X327199D01*
X332834Y240635D01*
Y244932D01*
G01X316646Y297025D02*
X313046D01*
X301679Y308392D01*
Y309360D01*
X297601Y313438D01*
X267137D01*
X258900Y305201D01*
Y297050D01*
G01D02*
X245950D01*
X245400Y296500D01*
G01X261231Y283559D02*
Y288331D01*
X263000Y290100D01*
Y293350D01*
G01D02*
X262800Y293550D01*
X258900D01*
G01X264979Y334140D02*
Y338640D01*
G01X293229Y328640D02*
X284960D01*
X282300Y331300D01*
X266600D01*
X264979Y332921D01*
Y334140D01*
G01X273229Y338640D02*
X264979D01*
G01X261479Y334140D02*
Y330208D01*
X263068Y328619D01*
G01D02*
X265235Y326452D01*
X286752D01*
X287102Y326802D01*
X287200D01*
G01X251850Y339700D02*
X252250Y340100D01*
Y343500D01*
G01D02*
Y344150D01*
X249800Y346600D01*
Y348840D01*
G01X257200Y353960D02*
X262760D01*
X266190Y357390D01*
X266729D01*
G01X274702Y365240D02*
X263493D01*
X257200Y358947D01*
Y353960D01*
G01Y351400D02*
X261219D01*
X262604Y350015D01*
G01D02*
X266729Y345890D01*
G01X249800Y348840D02*
X244760D01*
X244400Y349200D01*
Y350925D01*
X244875Y351400D01*
X249800D01*
G01X255850Y422500D02*
X254950Y421600D01*
X251700D01*
G01X250200Y428040D02*
X247901Y425741D01*
Y422389D01*
G01D02*
X248690Y421600D01*
X251700D01*
G01X256650Y438600D02*
X257600Y437650D01*
Y433160D01*
G01X251700Y425200D02*
X254575Y428075D01*
Y436675D01*
X256500Y438600D01*
X256650D01*
G01X238400Y416200D02*
X237700Y416900D01*
Y436800D01*
X235500Y439000D01*
G01X257500Y447488D02*
Y443350D01*
X257450Y443300D01*
G01X259350Y422500D02*
X257600Y424250D01*
Y428040D01*
G01X264100Y425400D02*
X261200Y422500D01*
X259350D01*
G01X257600Y428040D02*
X266412D01*
X268994Y430622D01*
Y435701D01*
X263807Y440888D01*
X259861D01*
X257450Y443300D01*
G01X253400Y447450D02*
X253450Y447400D01*
Y443300D01*
G01X253150Y438600D02*
Y443000D01*
X253450Y443300D01*
G01X250200Y433160D02*
X252660D01*
X253150Y433650D01*
Y438600D01*
G01X249342Y439064D02*
Y434018D01*
X250200Y433160D01*
G01Y430600D02*
X245150D01*
X244900Y430850D01*
G01D02*
Y429400D01*
X241800Y426300D01*
G01X262900Y430350D02*
X262650Y430600D01*
X257600D01*
G01X262900Y430350D02*
X265557D01*
X266756Y431549D01*
G01X260600Y476550D02*
X261750D01*
X263700Y474600D01*
G01D02*
Y475783D01*
X266540Y478623D01*
Y480000D01*
G01X235500Y459000D02*
X236500D01*
X242575Y465075D01*
Y492575D01*
X246800Y496800D01*
G01X257500Y450988D02*
X256400Y452088D01*
Y455586D01*
X257493Y456679D01*
G01X257500Y450988D02*
X261349D01*
G01X253400Y450950D02*
X254425Y451975D01*
Y455556D01*
X253302Y456679D01*
G01X253400Y450950D02*
X249311D01*
G01X242800Y495486D02*
X241150Y493836D01*
Y473650D01*
X236500Y469000D01*
X235500D01*
G01Y449000D02*
X237800D01*
X244000Y455200D01*
Y491900D01*
X245500Y493400D01*
X246500D01*
G01X240450Y499400D02*
X240400D01*
Y497227D01*
X239725Y496552D01*
Y482225D01*
X236500Y479000D01*
X235500D01*
G01X246300Y478600D02*
X247015Y479315D01*
X248291D01*
X252106Y475500D01*
X253979D01*
X256079Y473400D01*
X257000D01*
G01X266540Y472600D02*
X261050D01*
X260600Y473050D01*
G01D02*
X260250Y473400D01*
X257000D01*
G01X246300Y482000D02*
X247010Y481290D01*
X249110D01*
X252925Y477475D01*
X254798D01*
X256492Y479169D01*
X260068D01*
X263300Y482401D01*
Y486300D01*
X268040Y491040D01*
X274407D01*
X278088Y487359D01*
Y482012D01*
X278100Y482000D01*
G01X269100Y472600D02*
Y470800D01*
X267800Y469500D01*
X266523D01*
X265800Y468777D01*
Y467660D01*
G01D02*
X266160Y467300D01*
X269350D01*
G01X256300Y494500D02*
X257785Y493015D01*
X275226D01*
X280100Y488141D01*
Y487001D01*
X281639Y485462D01*
X284537D01*
X288019Y488944D01*
Y509063D01*
X279340Y517742D01*
X270854D01*
X269000Y515888D01*
Y513560D01*
G01X244100Y499900D02*
X244521Y499479D01*
X247678D01*
X250806Y496351D01*
X261652D01*
X262480Y497179D01*
Y498534D01*
X265284Y501338D01*
X266027D01*
X266049Y501360D01*
X269000D01*
G01X233290Y493277D02*
X235500Y491067D01*
Y489000D01*
G01X236737Y493170D02*
Y494306D01*
X235500Y495543D01*
Y499000D01*
G01X269100Y480000D02*
Y481283D01*
X265800Y484583D01*
Y485000D01*
G01D02*
X266600Y485800D01*
X269350D01*
G01X258000Y517750D02*
X253500D01*
G01X242500D02*
X246500D01*
G01X249601Y514174D02*
X247099D01*
X246500Y514773D01*
Y517750D01*
G01X249601Y514174D02*
X252345D01*
X253500Y515329D01*
Y517750D01*
G01X242500Y529250D02*
X246500D01*
G01X257500D02*
X253500D01*
G01D02*
Y529500D01*
X250587Y532413D01*
X249674D01*
G01D02*
X248213D01*
X246500Y530700D01*
Y529250D01*
G01X237779Y528680D02*
X238931D01*
X241861Y525750D01*
X242500D01*
G01X239139Y525077D02*
X238023D01*
X236800Y526300D01*
Y527701D01*
X237779Y528680D01*
G01X235291Y521326D02*
Y522208D01*
X236130Y523047D01*
X241648D01*
X242500Y522195D01*
Y521250D01*
G01X239321Y521081D02*
X238684Y520444D01*
X236173D01*
X235291Y521326D01*
G01X233750Y590000D02*
X234720Y589030D01*
X247372D01*
X248427Y587975D01*
X253304D01*
X253946Y588617D01*
Y590054D01*
X253500Y590500D01*
G01X233750Y586000D02*
X234805Y587055D01*
X246553D01*
X247608Y586000D01*
X254123D01*
X255921Y587798D01*
Y589008D01*
X257413Y590500D01*
G01X263488Y588165D02*
X268165D01*
X269000Y589000D01*
G01X263488Y593165D02*
X269335D01*
G01X263488Y583165D02*
X261335D01*
X259000Y585500D01*
X257000D01*
G01D02*
X255770Y584270D01*
Y581381D01*
G01X274550Y634900D02*
X273550Y635900D01*
X265400D01*
G01X260800Y651900D02*
X256900D01*
X256600Y652200D01*
G01X295079Y772100D02*
Y781826D01*
X289805Y787100D01*
X260168D01*
X252749Y779681D01*
Y712456D01*
X272780Y692425D01*
X384120D01*
X439595Y747900D01*
X597700D01*
X629500Y779700D01*
X645000D01*
X645800Y780500D01*
G01X258100Y726100D02*
X257500Y725500D01*
Y713982D01*
X274408Y697074D01*
X343426D01*
X344200Y696300D01*
G01X645800Y776900D02*
X629900D01*
X599200Y746200D01*
X440300D01*
X385100Y691000D01*
X271800D01*
X251324Y711476D01*
Y780272D01*
X259852Y788800D01*
X290510D01*
X296500Y782810D01*
Y782421D01*
X296504Y782417D01*
Y773903D01*
X298052Y772355D01*
X299148D01*
G01X645800Y783900D02*
X645600Y783700D01*
X630400D01*
X596300Y749600D01*
X438890D01*
X383140Y693850D01*
X273760D01*
X254175Y713435D01*
Y779091D01*
X260484Y785400D01*
X289100D01*
X292700Y781800D01*
Y777200D01*
X291000Y775500D01*
Y772150D01*
G01X278406Y772148D02*
X277443Y773111D01*
Y777965D01*
X274911Y780497D01*
X262290D01*
X258025Y776232D01*
Y732137D01*
X260643Y729519D01*
Y713192D01*
X275287Y698548D01*
X384213D01*
X460554Y774889D01*
Y812354D01*
X461300Y813100D01*
G01X274406Y772148D02*
X275468Y773210D01*
Y777146D01*
X274092Y778522D01*
X263109D01*
X260000Y775413D01*
Y732956D01*
X262618Y730338D01*
Y714011D01*
X276106Y700523D01*
X383394D01*
X458579Y775708D01*
Y812421D01*
X457900Y813100D01*
G01X277826Y735298D02*
X275351D01*
X270865Y730812D01*
X269239D01*
X262600Y737451D01*
X262628Y737479D01*
Y744470D01*
G01X241000Y721500D02*
X243000Y723500D01*
Y737500D01*
G01X241339Y887970D02*
Y881861D01*
X241700Y881500D01*
Y880955D01*
X243027Y879628D01*
Y874823D01*
X241700Y873496D01*
Y738800D01*
X243000Y737500D01*
G01X286500Y779750D02*
X283350Y782900D01*
X260000D01*
X255600Y778500D01*
Y728600D01*
X258100Y726100D01*
G01X238189Y887970D02*
Y882450D01*
X241602Y879037D01*
Y875606D01*
X240275Y874279D01*
Y731000D01*
G01X241000Y725500D02*
X240275Y726225D01*
Y731000D01*
G01X241000Y718000D02*
X241500D01*
X246000Y722500D01*
Y745500D01*
G01X244488Y887970D02*
Y758300D01*
X246000Y756788D01*
Y745500D01*
G01X277500Y137250D02*
X274751D01*
X272900Y139101D01*
Y142600D01*
X271374Y144126D01*
X269143D01*
G01X277500Y137250D02*
Y139915D01*
X278909Y141324D01*
G01D02*
X280176D01*
X281500Y140000D01*
Y137250D01*
G01X541400Y368580D02*
Y348200D01*
X545062Y344538D01*
Y306503D01*
X556312Y295253D01*
Y288981D01*
X554641Y287310D01*
Y212088D01*
X546180Y203627D01*
X524227D01*
X517355Y196755D01*
X505942D01*
X502216Y200481D01*
Y202550D01*
X500461Y204305D01*
X498386D01*
X486097Y216594D01*
X452642D01*
X446186Y210138D01*
X387939D01*
X372200Y194399D01*
Y164893D01*
X346569Y139262D01*
X284758D01*
X284440Y139580D01*
G01D02*
X280620Y143400D01*
X279850D01*
X277750Y145500D01*
G01X269143Y146094D02*
X273518D01*
X273950Y145662D01*
X277588D01*
X277750Y145500D01*
G01X281100Y205050D02*
X290350D01*
X292500Y207200D01*
G01X271231Y245001D02*
Y237031D01*
G01X337834Y244932D02*
Y240134D01*
X330000Y232300D01*
X287699D01*
X282968Y237031D01*
X271231D01*
G01Y245705D02*
Y245001D01*
G01X272900Y293250D02*
X272800Y293150D01*
Y290300D01*
X271231Y288731D01*
Y283559D01*
G01X302700Y298012D02*
X299950D01*
X299600Y297662D01*
G01X304639Y326201D02*
X300299D01*
X299296Y327204D01*
G01D02*
X297860Y328640D01*
X293229D01*
G01X273229Y343640D02*
Y345671D01*
X272000Y346900D01*
X269219D01*
X266729Y349390D01*
G01X293229Y338640D02*
X283360D01*
X278360Y343640D01*
X273229D01*
G01X300300Y340501D02*
X298500D01*
X296639Y338640D01*
X293229D01*
G01X308300Y332550D02*
X306538D01*
X304451Y330463D01*
X297537D01*
X296700Y331300D01*
X288800D01*
X286460Y333640D01*
X273229D01*
G01X293229D02*
X297128D01*
X299639Y336151D01*
G01X304100Y336350D02*
X299838D01*
X299639Y336151D01*
G01X266729Y353890D02*
Y349390D01*
G01X288270Y365240D02*
X274702D01*
G01X272979Y354640D02*
X270229Y357390D01*
X266729D01*
G01X273783Y476100D02*
X275333Y474550D01*
X278100D01*
G01X271660Y472600D02*
Y473977D01*
X273783Y476100D01*
G01X284200Y474550D02*
X286290D01*
X287100Y475360D01*
X291012D01*
G01X291002Y483650D02*
Y478110D01*
X291012Y478100D01*
Y475360D01*
G01X284200Y474550D02*
Y477100D01*
X283400Y477900D01*
G01X278100Y478050D02*
X273610D01*
X271660Y480000D01*
G01X278100Y482000D02*
Y478050D01*
G01X296940Y458370D02*
Y465560D01*
X300082Y468702D01*
X300217D01*
X301270Y469755D01*
Y472100D01*
X300570Y472800D01*
X297512D01*
G01X302140Y444160D02*
Y452460D01*
X296940Y457660D01*
Y458370D01*
G01X293562Y490150D02*
Y495062D01*
X296000Y497500D01*
G01X290838Y501600D02*
X293200D01*
X296000Y498800D01*
Y497500D01*
G01X276400Y508440D02*
X273662D01*
X272452Y507230D01*
Y502074D01*
X271738Y501360D01*
X269000D01*
G01X282400Y487300D02*
Y488635D01*
X280300Y490735D01*
Y493050D01*
X282450Y495200D01*
G01D02*
X282500Y495250D01*
G01X276400Y496240D02*
X281410D01*
X282450Y495200D01*
G01X294238Y578165D02*
X290000D01*
G01D02*
X283488D01*
G01X294238Y583165D02*
X289835D01*
G01D02*
X283488D01*
G01X294238Y588665D02*
X290335D01*
X289835Y588165D01*
G01D02*
X283488D01*
G01X274550Y638900D02*
Y634900D01*
G01Y638900D02*
X273950Y639500D01*
X271500D01*
G01X303266Y825234D02*
X335850Y792650D01*
Y731318D01*
X331800Y727268D01*
Y711264D01*
X323397Y702861D01*
X296475D01*
X296000Y703336D01*
Y718054D01*
X294406Y719648D01*
G01X298406D02*
Y706000D01*
G01X290338Y715800D02*
Y712438D01*
X290200Y712300D01*
G01D02*
X288500Y714000D01*
Y717742D01*
X290406Y719648D01*
G01X274406Y723148D02*
X274008Y722750D01*
X268084D01*
X266980Y723854D01*
G01X280386Y735298D02*
Y732793D01*
X279003Y731410D01*
X273479D01*
X266980Y724911D01*
Y723854D01*
G01X278406Y723148D02*
Y724089D01*
X275609Y726886D01*
G01X282946Y735298D02*
Y732792D01*
X280149Y729995D01*
X279604D01*
X279594Y729985D01*
X278708D01*
X275609Y726886D01*
G01X286406Y723148D02*
X287278Y724020D01*
Y729031D01*
G01X288066Y735298D02*
Y729819D01*
X287278Y729031D01*
G01X286406Y719648D02*
Y716531D01*
G01X298306Y735298D02*
Y732538D01*
X301310Y729534D01*
Y726403D01*
G01X294406Y723148D02*
Y724445D01*
X296132Y726171D01*
G01X293186Y735298D02*
Y732614D01*
X296132Y729668D01*
Y726171D01*
G01X294406Y719648D02*
X292568Y721486D01*
Y724485D01*
X290720Y726333D01*
G01X285506Y735298D02*
Y729739D01*
X285124Y729357D01*
Y726450D01*
G01D02*
X285333Y726241D01*
G01X280498Y726806D02*
X284768D01*
X285124Y726450D01*
G01X282406Y723148D02*
X280498Y725056D01*
Y726806D01*
G01X282406Y719648D02*
Y716598D01*
G01X298406Y723148D02*
Y728382D01*
X298620Y728596D01*
G01X295746Y735298D02*
Y732499D01*
X298620Y729625D01*
Y728596D01*
G01X290626Y735298D02*
Y731900D01*
X292831Y729695D01*
Y729494D01*
G01X290406Y723148D02*
X288882Y724672D01*
Y727094D01*
X290478Y728690D01*
X292027D01*
X292831Y729494D01*
G01X278406Y768648D02*
Y765594D01*
X279500Y764500D01*
G01X282946Y757498D02*
Y760054D01*
X282000Y761000D01*
Y762000D01*
X279500Y764500D01*
G01X274406Y768648D02*
Y763500D01*
G01X280386Y757498D02*
Y760614D01*
X279000Y762000D01*
X275906D01*
X274406Y763500D01*
G01X282478Y768681D02*
X283500Y767659D01*
Y765631D01*
G01X285506Y757498D02*
Y760794D01*
X283500Y762800D01*
Y765631D01*
G01X295079Y768600D02*
Y766958D01*
X293692Y765571D01*
G01X293186Y757498D02*
Y765065D01*
X293692Y765571D01*
G01X298306Y757498D02*
Y761006D01*
X302700Y765400D01*
G01X273700Y752000D02*
X281500D01*
G01X287115Y765584D02*
X286500Y766199D01*
Y768750D01*
G01X288066Y757498D02*
Y760800D01*
X287278Y761588D01*
Y765421D01*
X287115Y765584D01*
G01X288066Y757498D02*
Y752566D01*
X287500Y752000D01*
X281500D01*
G01X286500Y768750D02*
X286750D01*
X288338Y770338D01*
Y774412D01*
X286500Y776250D01*
G01X295746Y757498D02*
Y762246D01*
X296500Y763000D01*
G01X299184Y765691D02*
X296500Y763007D01*
Y763000D01*
G01X299148Y768855D02*
Y765727D01*
X299184Y765691D01*
G01X290626Y757498D02*
Y763446D01*
X290400Y763672D01*
G01X291000Y768650D02*
Y764272D01*
X290400Y763672D01*
G01X285433Y887970D02*
Y883023D01*
X283745Y881335D01*
Y873939D01*
X292000Y865684D01*
Y826500D01*
X296872Y821628D01*
G01X320000Y718200D02*
Y720300D01*
X331838Y732138D01*
Y786662D01*
X296872Y821628D01*
G01X323600Y717800D02*
X329000Y723200D01*
Y726484D01*
X333263Y730747D01*
Y790737D01*
X295592Y828408D01*
G01X288583Y887970D02*
Y884093D01*
X285170Y880680D01*
Y874530D01*
X294000Y865700D01*
Y830000D01*
X295592Y828408D01*
G01X314750Y221900D02*
Y209450D01*
X312500Y207200D01*
G01X306900Y251000D02*
Y270600D01*
X307834Y271534D01*
Y282786D01*
G01X332834Y245636D02*
Y244932D01*
G01X302834Y245636D02*
Y250366D01*
X302400Y250800D01*
Y251500D01*
X302500Y251600D01*
G01X306800Y290500D02*
X307359D01*
X307834Y290025D01*
Y283490D01*
G01X306800Y290500D02*
Y291318D01*
X309032Y293550D01*
G01X307834Y282786D02*
Y283490D01*
G01X302700Y294512D02*
X302834Y294378D01*
Y283490D01*
G01X320662Y293540D02*
X327834Y286368D01*
Y283490D01*
G01X316646Y293525D02*
X320647D01*
X320662Y293540D01*
G01X328800Y315900D02*
X323700Y321000D01*
Y343100D01*
X314485Y352315D01*
G01X329894Y334794D02*
Y333301D01*
X333310Y329885D01*
X336141D01*
G01X334850Y335500D02*
X330600D01*
X329894Y334794D01*
G01X304839Y340501D02*
X300300D01*
G01X336141Y323975D02*
X331375D01*
X329000Y321600D01*
Y320600D01*
G01D02*
Y320100D01*
X330200Y318900D01*
X333050D01*
G01X312430Y333540D02*
X311440Y332550D01*
X308300D01*
G01X315300Y337250D02*
Y336410D01*
X312430Y333540D01*
G01X304100Y336350D02*
Y336301D01*
G01X308300Y336050D02*
X308000Y336350D01*
X304100D01*
G01X314485Y352315D02*
X308310Y358490D01*
X301929D01*
G01X315650Y542500D02*
Y538300D01*
G01X315750Y534500D02*
Y538200D01*
X315650Y538300D01*
G01X315750Y534500D02*
X313450Y532200D01*
X310000D01*
X306900Y529100D01*
G01X302406Y719648D02*
Y716448D01*
X302438Y716416D01*
Y714810D01*
X302406Y714778D01*
Y706031D01*
G01X306406D02*
X306500Y706125D01*
Y712400D01*
G01D02*
X306406Y712494D01*
Y719648D01*
G01X302406Y723148D02*
Y724833D01*
X301310Y725929D01*
Y726403D01*
G01X304000Y779950D02*
X304950Y779000D01*
X326000D01*
X330000Y775000D01*
Y762931D01*
X325500Y758431D01*
Y729500D01*
X326000Y729000D01*
G01X310406Y723148D02*
Y723858D01*
X313049Y726501D01*
X314436D01*
X315132Y727197D01*
G01X303426Y735298D02*
Y732946D01*
X308491Y727881D01*
X314448D01*
X315132Y727197D01*
G01X314500Y723250D02*
X314398Y723148D01*
X310406D01*
G01Y719648D02*
X308568Y721486D01*
Y724741D01*
X307278Y726031D01*
Y726198D01*
G01X306406Y723148D02*
X304500Y725054D01*
Y728614D01*
X304416Y728698D01*
G01X300866Y735298D02*
Y732248D01*
X304416Y728698D01*
G01X311200Y765500D02*
Y760704D01*
X310622Y760126D01*
G01X303426Y757498D02*
Y760408D01*
X304590Y761572D01*
X309176D01*
X310622Y760126D01*
G01X311406Y768648D02*
Y765706D01*
X311200Y765500D01*
G01X311406Y772148D02*
Y775198D01*
G01X302700Y765400D02*
X303300Y766000D01*
Y768550D01*
G01D02*
X305488Y770738D01*
Y774962D01*
X304000Y776450D01*
G01X315406Y768648D02*
Y765598D01*
G01X305986Y757498D02*
X307762D01*
X309083Y756177D01*
X311431D01*
X315406Y760152D01*
Y765598D01*
G01Y772148D02*
Y775200D01*
G01X307406Y768648D02*
Y764406D01*
X307000Y764000D01*
G01X300866Y757498D02*
Y760967D01*
X303449Y763550D01*
X306550D01*
X307000Y764000D01*
G01X307406Y772148D02*
Y775198D01*
G01X307481Y887970D02*
Y872280D01*
X304662Y869461D01*
Y828638D01*
X337275Y796025D01*
Y727525D01*
X360000Y704800D01*
Y704000D01*
G01X304331Y887970D02*
Y884109D01*
X305280Y883160D01*
Y872130D01*
X302074Y868924D01*
Y826426D01*
X303266Y825234D01*
G01X466905Y122378D02*
X465643Y123636D01*
Y124666D01*
X462634Y127675D01*
X419475D01*
X412800Y121000D01*
X352300D01*
X350200Y123100D01*
Y128906D01*
X350675Y129381D01*
X351419D01*
X352600Y128200D01*
G01X462868Y122374D02*
X463668Y123174D01*
Y123847D01*
X461815Y125700D01*
X420294D01*
X413619Y119025D01*
X351481D01*
X348225Y122281D01*
Y129725D01*
X349856Y131356D01*
X351419D01*
X352600Y132537D01*
G01X455800Y102950D02*
X436350D01*
X422300Y117000D01*
X349999D01*
X345800Y121199D01*
Y134100D01*
X374293Y162593D01*
Y193893D01*
X383600Y203200D01*
G01X338650Y222000D02*
Y218750D01*
X335150Y215250D01*
Y208250D01*
X336200Y207200D01*
G01X410900Y217100D02*
X365300D01*
X355400Y207200D01*
X346200D01*
G01X337834Y245636D02*
Y244932D01*
G01X339149Y315170D02*
X336550Y312571D01*
Y301865D01*
X339598Y298817D01*
Y295002D01*
X345800Y288800D01*
Y256590D01*
X345820Y256570D01*
G01X344836Y314844D02*
X348182Y311498D01*
Y291396D01*
X349970Y289608D01*
Y256720D01*
G01X337834Y283490D02*
Y282786D01*
G01X337410Y292410D02*
X337834Y291986D01*
Y283490D01*
G01X362500Y341700D02*
X340000D01*
X338350Y340050D01*
Y335500D01*
G01X507959Y202172D02*
Y208365D01*
X505369Y210955D01*
X498244D01*
X488654Y220545D01*
X461261D01*
X364800Y317006D01*
Y339400D01*
X362500Y341700D01*
G01X515659Y202072D02*
X513468Y199881D01*
X505610D01*
X505222Y200269D01*
Y206367D01*
X502609Y208980D01*
X496723D01*
X487133Y218570D01*
X460442D01*
X362825Y316187D01*
Y336000D01*
G01D02*
X359375Y339450D01*
X345280D01*
X343950Y338120D01*
Y335600D01*
G01X347450D02*
X350925D01*
X351605Y334920D01*
G01D02*
Y332412D01*
X349078Y329885D01*
X345341D01*
G01X348050Y318500D02*
X352600D01*
X353000Y318900D01*
Y320300D01*
G01D02*
Y322000D01*
X351025Y323975D01*
X345341D01*
G01Y325945D02*
X351500D01*
X352245Y325200D01*
X354500D01*
G01D02*
X354725D01*
X355200Y325675D01*
Y328750D01*
G01X336550Y318900D02*
Y317769D01*
X339149Y315170D01*
G01X344550Y318500D02*
Y315130D01*
X344836Y314844D01*
G01X376772Y887970D02*
Y881388D01*
X374375Y878991D01*
Y808987D01*
X351475Y786087D01*
Y724425D01*
X367000Y708900D01*
Y704000D01*
G01X379922Y887970D02*
Y882522D01*
X375800Y878400D01*
Y808396D01*
X352900Y785496D01*
Y727200D01*
X370500Y709600D01*
Y705500D01*
G01X348900Y730900D02*
X350050Y729750D01*
Y718650D01*
X363500Y705200D01*
Y704000D01*
G01X373622Y887970D02*
Y880254D01*
X372950Y879582D01*
Y809578D01*
X350050Y786678D01*
Y732050D01*
X348900Y730900D01*
G01X368900Y315700D02*
X371415Y313185D01*
X431525D01*
X470970Y352630D01*
X492030D01*
X534500Y395100D01*
G01X461900Y68950D02*
X457700D01*
G01X461900Y73800D02*
Y68950D01*
G01X461440Y84600D02*
Y74260D01*
X461900Y73800D01*
G01X466000Y68950D02*
X470200D01*
G01X464000Y84600D02*
Y80000D01*
X470200Y73800D01*
G01X466560Y84600D02*
Y80440D01*
X470500Y76500D01*
X475700D01*
X478400Y73800D01*
G01X469120Y84600D02*
Y89705D01*
X463375Y95450D01*
X455800D01*
G01D02*
Y91100D01*
X455300Y90600D01*
G01X466560Y106800D02*
Y110482D01*
X470047Y113969D01*
G01X464000Y106800D02*
Y113371D01*
X464692Y114063D01*
G01X455800Y102950D02*
Y98950D01*
G01X474362Y130750D02*
X466188D01*
X465270Y129832D01*
G01X481800Y131719D02*
X479472Y134047D01*
X466838D01*
X464518Y136367D01*
Y142250D01*
X461009Y145759D01*
X460785D01*
G01X470047Y113969D02*
Y115736D01*
X466905Y118878D01*
G01X464692Y114063D02*
Y117050D01*
X462868Y118874D01*
G01X469910Y143008D02*
X468348D01*
X465219Y146137D01*
Y152700D01*
X464660Y153259D01*
G01X455328Y159738D02*
X458181D01*
X464660Y153259D01*
G01X465485Y200680D02*
Y209103D01*
X463599Y210989D01*
G01X477466Y182770D02*
X467575D01*
X465485Y180680D01*
G01X458029Y380305D02*
X458034Y380300D01*
X462450D01*
X462700Y380550D01*
G01D02*
X464290Y382140D01*
X470050D01*
G01X488838Y140700D02*
Y121372D01*
X502425Y107785D01*
Y47425D01*
X497488Y42488D01*
Y31496D01*
G01X497530Y144850D02*
X493500Y140820D01*
Y119980D01*
X505500Y107980D01*
Y25500D01*
X497488Y17488D01*
Y7874D01*
G01X491488Y31496D02*
X487226D01*
X486750Y31020D01*
G01X486720Y26720D02*
Y30990D01*
X486750Y31020D01*
G01X486710Y13180D02*
Y9106D01*
X486979Y8837D01*
G01D02*
X487942Y7874D01*
X491488D01*
G01X481800Y131719D02*
X483787Y129732D01*
Y123601D01*
X501000Y106388D01*
Y58630D01*
X497488Y55118D01*
G01X486764Y78077D02*
X486734Y78047D01*
Y73396D01*
X486750Y73380D01*
G01Y49880D02*
Y54570D01*
X486760Y54580D01*
G01X491488Y55118D02*
X487298D01*
X486760Y54580D01*
G01X470200Y68950D02*
Y73800D01*
G01X478400Y68950D02*
Y73800D01*
G01Y68950D02*
X474400D01*
G01X474362Y130750D02*
X474622D01*
X497488Y107884D01*
Y78740D01*
G01X491488D02*
X487427D01*
X486764Y78077D01*
G01X475089Y114652D02*
X474551D01*
X469120Y109221D01*
Y106800D01*
G01X495403Y151642D02*
X488838Y145077D01*
Y140700D01*
G01X480881Y140064D02*
Y142480D01*
X482800Y144399D01*
Y161900D01*
X480910Y163790D01*
Y164099D01*
G01X469145Y137332D02*
X469913Y136564D01*
X475567D01*
G01D02*
X480881D01*
G01X478800Y119250D02*
Y116899D01*
X476553Y114652D01*
X475089D01*
G01X490850Y166000D02*
X488550Y168300D01*
Y180673D01*
X488462Y180761D01*
G01X497530Y144850D02*
X504430Y151750D01*
X509295D01*
X509403Y151642D01*
G01X480800Y160700D02*
Y150398D01*
X473410Y143008D01*
G01X498903Y168642D02*
X498900Y168645D01*
Y171800D01*
G01X499278Y159142D02*
Y164767D01*
X498903Y165142D01*
G01X498400Y201950D02*
X489651D01*
X488462Y200761D01*
G01X480759Y334041D02*
X477237D01*
X477037Y333841D01*
G01X480759Y339041D02*
X478929D01*
X473764Y333876D01*
X473637D01*
G01X493909Y334041D02*
X488109D01*
G01D02*
Y332641D01*
G01Y334041D02*
X484259D01*
G01Y339041D02*
X488009D01*
G01D02*
Y340441D01*
G01Y339041D02*
X493909D01*
G01X480700Y359550D02*
X479297Y358147D01*
Y356503D01*
X480000Y355800D01*
G01X480700Y367800D02*
Y363050D01*
G01D02*
X482216D01*
X484695Y360571D01*
G01X480700Y367800D02*
X479444Y369056D01*
Y375044D01*
X481420Y377020D01*
X486350D01*
G01X476200Y359550D02*
X477322Y358428D01*
Y356522D01*
X476600Y355800D01*
G01X476200Y367800D02*
Y363050D01*
G01D02*
X474525D01*
X471852Y360377D01*
G01X476200Y367800D02*
X477469Y369069D01*
Y374531D01*
X474980Y377020D01*
X470050D01*
G01X493700Y376050D02*
Y378662D01*
X494908Y379870D01*
G01X486350Y374460D02*
X492110D01*
X493700Y376050D01*
G01X480700Y388800D02*
X479463Y387563D01*
Y382537D01*
X482420Y379580D01*
X486350D01*
G01X480700Y397550D02*
X484300D01*
G01X480700D02*
X480450Y397300D01*
Y393300D01*
G01X480700Y388800D02*
Y393050D01*
X480450Y393300D01*
G01X476200Y388800D02*
X477488Y387511D01*
Y382588D01*
X474480Y379580D01*
X470050D01*
G01X476200Y397550D02*
X472600D01*
G01X476200D02*
X476450Y397300D01*
Y393300D01*
G01X476200Y388800D02*
Y393050D01*
X476450Y393300D01*
G01X480700Y401050D02*
X479426Y402324D01*
Y404664D01*
X480368Y405606D01*
G01X476200Y401050D02*
X477451Y402301D01*
Y404686D01*
X476531Y405606D01*
G01X493886Y787298D02*
Y785094D01*
X492234Y783442D01*
X488778D01*
X487003Y781667D01*
X485786D01*
X484830Y780711D01*
G01X482925Y777422D02*
X484017Y778514D01*
Y779898D01*
X484830Y780711D01*
G01X487906Y775148D02*
X485199D01*
X482925Y777422D01*
G01X491906Y775148D02*
X490061Y776993D01*
Y779588D01*
X489522Y780127D01*
G01X496446Y787298D02*
Y785030D01*
X493125Y781709D01*
X490726D01*
X489522Y780505D01*
Y780127D01*
G01X499906Y775148D02*
Y780159D01*
X500778Y781031D01*
G01X501566Y787298D02*
Y781819D01*
X500778Y781031D01*
G01X499906Y771648D02*
Y768531D01*
G01X497910Y778824D02*
X497834Y778900D01*
X493495D01*
X493408Y778813D01*
G01X495906Y775148D02*
X493408Y777646D01*
Y778813D01*
G01X499006Y787298D02*
Y781888D01*
X497910Y780792D01*
Y778824D01*
G01X495906Y771648D02*
Y768598D01*
G01X503906Y775148D02*
Y774941D01*
X502068Y773103D01*
Y765681D01*
X502044Y765657D01*
Y765135D01*
G01X503906Y775148D02*
X502440Y776614D01*
Y780192D01*
X504126Y781878D01*
Y787298D01*
G01X864800Y707700D02*
X865512Y708412D01*
Y711003D01*
X864255Y712260D01*
X793211D01*
X714022Y791449D01*
X631566D01*
X593029Y752912D01*
X489855D01*
X471451Y771316D01*
Y826330D01*
X478258Y833137D01*
X489059D01*
X491303Y830893D01*
Y828006D01*
X491906Y827403D01*
G01X868200Y707700D02*
X867487Y708413D01*
Y711822D01*
X865074Y714235D01*
X794030D01*
X714841Y793424D01*
X630747D01*
X592210Y754887D01*
X490674D01*
X473426Y772135D01*
Y825511D01*
X479077Y831162D01*
X488240D01*
X489328Y830074D01*
Y828825D01*
X487906Y827403D01*
G01X496446Y809498D02*
Y811757D01*
X495703Y812500D01*
Y813445D01*
X494008Y815140D01*
Y816101D01*
X493255Y816854D01*
G01X488255Y816894D02*
X488785Y816364D01*
X490580D01*
X492328Y814616D01*
X493011D01*
X494628Y812999D01*
Y812500D01*
X493886Y811758D01*
Y809498D01*
G01X491326Y787298D02*
X487944D01*
X485254Y789988D01*
X482239D01*
X480445Y788194D01*
Y784920D01*
X480100Y784575D01*
G01X499006Y809498D02*
Y813444D01*
X498990Y813460D01*
Y815510D01*
X497000Y817500D01*
G01X501566Y809498D02*
Y812900D01*
X500415Y814051D01*
Y817532D01*
G01X494582Y804000D02*
X492082Y801500D01*
X487000D01*
G01X501566Y809498D02*
Y804566D01*
X501000Y804000D01*
X494582D01*
G01X491906Y820648D02*
Y818203D01*
X493255Y816854D01*
G01X487906Y820648D02*
Y817243D01*
X488255Y816894D01*
G01X495978Y820681D02*
Y818522D01*
X497000Y817500D01*
G01X504406Y820648D02*
X500102D01*
X500100Y820650D01*
G01D02*
Y818209D01*
X500415Y817894D01*
Y817532D01*
G01X504406Y824148D02*
Y824394D01*
X500700Y828100D01*
G01X508500Y824150D02*
X506400Y826250D01*
X506056D01*
X500807Y831499D01*
G01X491906Y824148D02*
Y827403D01*
G01X487906Y824148D02*
Y827403D01*
G01X713332Y1831D02*
X707833D01*
X688000Y21664D01*
X536809D01*
X520578Y37895D01*
Y66230D01*
X524151Y69803D01*
G01X526550Y157715D02*
Y158315D01*
X530050Y161815D01*
G01Y157715D02*
Y152587D01*
X529176Y151713D01*
G01X534962Y159035D02*
X533118Y157191D01*
Y155318D01*
X532560Y154760D01*
Y152046D01*
G01X526550Y161815D02*
Y165815D01*
G01X530152Y175634D02*
Y170571D01*
X526550Y166969D01*
Y165815D01*
G01X535960Y151999D02*
Y152360D01*
X538500Y154900D01*
G01X507700Y171550D02*
X507222Y171072D01*
X505275D01*
X503975Y172372D01*
G01X507700Y168050D02*
Y164720D01*
X513278Y159142D01*
G01X505050Y186500D02*
Y184700D01*
X507300Y182450D01*
G01X522278Y175634D02*
X516911D01*
X510095Y182450D01*
X507300D01*
G01Y178950D02*
Y175500D01*
G01X511742Y215594D02*
X512306D01*
X515935Y211965D01*
Y208950D01*
X511459Y204474D01*
Y202172D01*
G01X519159Y202072D02*
Y211519D01*
X521742Y214102D01*
Y215594D01*
G01X517599Y236987D02*
Y239795D01*
X519526Y241722D01*
Y248913D01*
G01X539798Y228856D02*
X538857Y227915D01*
X537003D01*
X535200Y226112D01*
X518546D01*
X514861Y229797D01*
Y236056D01*
X515792Y236987D01*
X517599D01*
G01X539934Y232660D02*
X539389Y232115D01*
X538391D01*
X534363Y228087D01*
X528173D01*
X527131Y229129D01*
Y233430D01*
G01X540035Y236294D02*
X539755Y236014D01*
X537801D01*
X535295Y233508D01*
G01X522899Y236987D02*
X527074D01*
X527131Y236930D01*
G01X524526Y248913D02*
Y243922D01*
X522899Y242295D01*
Y236987D01*
G01X529526Y248913D02*
Y238680D01*
X531232Y236974D01*
G01X535295Y237008D02*
X531266D01*
X531232Y236974D01*
G01X528709Y291433D02*
Y288548D01*
X529881Y287376D01*
G01X536953Y291310D02*
X533164D01*
X532921Y291067D01*
G01X529526Y280409D02*
Y282621D01*
X532581Y285676D01*
Y290727D01*
X532921Y291067D01*
G01X534526Y280409D02*
Y282024D01*
X536607Y284105D01*
X540120D01*
X541681Y285666D01*
Y291026D01*
G01X534526Y280409D02*
Y278511D01*
G01X524177Y294690D02*
X528466D01*
X528709Y294933D01*
G01X524526Y280409D02*
Y285258D01*
X521439Y288345D01*
Y292325D01*
X523042Y293928D01*
X523415D01*
X524177Y294690D01*
G01X515906Y775148D02*
Y778570D01*
X515278Y779198D01*
G01X511806Y787298D02*
Y784538D01*
X515278Y781066D01*
Y779198D01*
G01X515906Y771648D02*
X519257Y768297D01*
X519748D01*
G01X507906Y775148D02*
Y778021D01*
X507729Y778198D01*
G01X506686Y787298D02*
Y780623D01*
X507729Y779580D01*
Y778198D01*
G01X504278Y779198D02*
X505891Y777585D01*
Y777316D01*
X506068Y777139D01*
Y773486D01*
X507906Y771648D01*
G01D02*
Y768531D01*
G01X516926Y787298D02*
Y784946D01*
X521714Y780158D01*
X523825D01*
X526222Y782555D01*
X528179D01*
G01X523906Y775148D02*
X528002D01*
X528100Y775050D01*
G01D02*
Y778835D01*
X528179Y778914D01*
Y782555D01*
G01X523906Y771648D02*
X522068Y773486D01*
Y776503D01*
X524094Y778529D01*
X524795D01*
G01X509246Y787298D02*
Y781700D01*
G01X511484Y778515D02*
X510822Y779177D01*
Y779863D01*
X509246Y781439D01*
Y781700D01*
G01X511906Y775148D02*
Y778093D01*
X511484Y778515D01*
G01X511906Y771648D02*
X513962Y769592D01*
Y767497D01*
X515650Y765809D01*
Y764500D01*
G01X503906Y771648D02*
Y768598D01*
G01X519906Y775148D02*
Y778799D01*
X519458Y779247D01*
G01X514366Y787298D02*
Y784788D01*
X519458Y779696D01*
Y779247D01*
G01X519906Y771648D02*
X521600Y769954D01*
Y766594D01*
X519906Y764900D01*
G01X516926Y809498D02*
Y812526D01*
X517900Y813500D01*
X520700D01*
X521425Y814225D01*
X521708D01*
X523019Y815536D01*
Y815819D01*
X524700Y817500D01*
G01X506686Y809498D02*
Y813000D01*
X507200Y813514D01*
Y817413D01*
X507044Y817569D01*
G01X511806Y809498D02*
Y812597D01*
X516610Y817401D01*
X516943D01*
G01X519486Y809498D02*
X520398D01*
X528100Y817200D01*
X528106D01*
X528504Y817598D01*
X528906D01*
G01X512716Y817577D02*
Y817580D01*
X512669Y817533D01*
X512390D01*
X509855Y814998D01*
G01X509246Y809498D02*
Y814389D01*
X509855Y814998D01*
G01X514366Y809498D02*
Y812967D01*
X516389Y814990D01*
X519308D01*
X520781Y816463D01*
G01X524906Y820648D02*
X523948D01*
X521982Y818682D01*
Y817664D01*
X520781Y816463D01*
G01X504126Y809498D02*
Y812879D01*
X503763Y813242D01*
Y815664D01*
X503745Y815682D01*
G01X508500Y820650D02*
X507549D01*
X506306Y819407D01*
X506283D01*
X503745Y816869D01*
Y815682D01*
G01X528906Y820648D02*
X527848D01*
X526744Y819544D01*
Y819293D01*
X526311Y818860D01*
X526060D01*
X524700Y817500D01*
G01X535827Y887970D02*
Y882543D01*
X534075Y880791D01*
Y871000D01*
X536500Y868575D01*
Y831500D01*
X534543Y829543D01*
G01X528906Y824148D02*
X529148D01*
X534543Y829543D01*
G01X512579Y820600D02*
X512300D01*
X510100Y818400D01*
X508031D01*
X507200Y817569D01*
X507044D01*
G01X512579Y824100D02*
X511900D01*
X508579Y827421D01*
G01X520906Y820648D02*
X520190D01*
X516943Y817401D01*
G01X520906Y824148D02*
X519200Y825854D01*
Y832100D01*
X523300Y836200D01*
X527500D01*
G01X532906Y820648D02*
X531956D01*
X528906Y817598D01*
G01X532906Y824148D02*
X535948D01*
X540200Y828400D01*
Y837200D01*
G01X512716Y817577D02*
Y817550D01*
G01X516679Y820600D02*
X515772D01*
X513984Y818812D01*
X513951D01*
X512716Y817577D01*
G01X516679Y824100D02*
X516079D01*
X512679Y827500D01*
G01X532678Y887970D02*
Y881410D01*
X532650Y881382D01*
Y839446D01*
X532217Y839013D01*
G01D02*
X530811Y837607D01*
Y836811D01*
X523700Y829700D01*
G01D02*
Y825354D01*
X524906Y824148D01*
G01X538977Y887970D02*
Y883677D01*
X535540Y880240D01*
Y871551D01*
X540200Y866891D01*
Y837200D01*
G01X718302Y6774D02*
X716305Y4777D01*
X706903D01*
X687984Y23696D01*
X617191D01*
X606643Y34244D01*
Y42015D01*
X588858Y59800D01*
X571809D01*
X567458Y64151D01*
Y69803D01*
G01X554250Y137597D02*
X557532D01*
X558220Y136909D01*
G01X549100Y126900D02*
X548900Y127100D01*
Y131720D01*
X550730Y133550D01*
G01X570754Y147365D02*
X567831Y144442D01*
Y144423D01*
X566531Y143123D01*
G01X538375Y163463D02*
X539378D01*
X542490Y160351D01*
G01X538375Y163463D02*
Y159122D01*
X538462Y159035D01*
G01X571400Y164750D02*
X568215Y167935D01*
X564483D01*
G01X561648Y175634D02*
Y170770D01*
X564483Y167935D01*
G01X567200Y164750D02*
X563100D01*
G01X553774Y175634D02*
Y171089D01*
X555282Y169581D01*
X558572D01*
X563100Y165053D01*
Y164750D01*
G01X561600Y154800D02*
Y155100D01*
X563100Y156600D01*
Y161250D01*
G01D02*
X558600Y165750D01*
Y166770D01*
X558121Y167249D01*
G01X538026Y175634D02*
Y169412D01*
X542490Y164948D01*
Y163851D01*
G01X550400Y165050D02*
X554500D01*
G01D02*
X555550D01*
X556638Y163962D01*
Y160062D01*
X558100Y158600D01*
G01X545900Y175634D02*
Y172800D01*
X550200Y168500D01*
Y165250D01*
X550400Y165050D01*
G01X538500Y154900D02*
X541037D01*
X545337Y159200D01*
X552150D01*
X554500Y161550D01*
G01X569522Y175634D02*
X573727D01*
X575600Y173761D01*
Y164650D01*
G01X569522Y192366D02*
Y201672D01*
X570100Y202250D01*
G01X536953Y294810D02*
X538881Y292882D01*
Y287276D01*
X539481Y286676D01*
G01X549449Y291069D02*
X544993Y286613D01*
Y281352D01*
G01X549449Y291069D02*
X554074D01*
G01X541681Y291026D02*
X545906D01*
X545949Y291069D01*
G01D02*
Y291783D01*
X549751Y295585D01*
X551926D01*
G01X541400Y368580D02*
X548531D01*
G01X560531Y364180D02*
Y368731D01*
X561300Y369500D01*
G01D02*
Y370100D01*
X563531Y372331D01*
Y373330D01*
G01X544000Y761000D02*
X545875Y759125D01*
X581625D01*
X628148Y805648D01*
G01X547395Y761198D02*
X547418Y761175D01*
X575075D01*
X614444Y800544D01*
G01X540500Y761000D02*
X543800Y757700D01*
X589100D01*
X638470Y807070D01*
G01X573151Y211067D02*
Y205301D01*
X570100Y202250D01*
G01X598808Y205137D02*
X592934D01*
X591571Y206500D01*
G01D02*
X589713Y208358D01*
Y211308D01*
G01X593213D02*
X594521Y210000D01*
X596253D01*
G01X576100Y234500D02*
Y232300D01*
X578157Y230243D01*
X578219D01*
X579854Y228608D01*
X581313D01*
G01X589713Y215308D02*
Y211308D01*
G01X602808Y213937D02*
X608699D01*
X615598Y207038D01*
X620743D01*
X623313Y209608D01*
G01X718343Y10856D02*
X711188D01*
X709000Y8668D01*
X705610D01*
X689157Y25121D01*
X617782D01*
X608068Y34835D01*
Y63197D01*
X610766Y65895D01*
Y69803D01*
G01X635482Y207733D02*
X637229Y209480D01*
X644849D01*
X645200Y209831D01*
Y217232D01*
X640633Y221799D01*
X635272D01*
X632449Y224622D01*
G01X623363Y231858D02*
X619363D01*
G01X627363D02*
X623363D01*
G01X627363D02*
X631363D01*
G01D02*
X634613D01*
X637063Y229408D01*
G01X612406Y232984D02*
X615687D01*
X616813Y231858D01*
X619363D01*
G01X622113Y238108D02*
X619113Y235108D01*
X617061D01*
X616970Y235017D01*
G01X612406Y234952D02*
X616807D01*
X616872Y235017D01*
X616970D01*
G01X631363Y228358D02*
Y225708D01*
X632449Y224622D01*
G01X624101Y330010D02*
X624790Y329321D01*
Y319608D01*
X631898Y312500D01*
X680838D01*
X698638Y330300D01*
X844021D01*
X875421Y298900D01*
X891937D01*
X894438Y301401D01*
Y305206D01*
X894397Y305247D01*
X895000Y305850D01*
G01X624000Y333850D02*
X624843Y333007D01*
Y330752D01*
X624101Y330010D01*
G01X891000Y305850D02*
X892420Y304430D01*
Y304429D01*
X892463Y304387D01*
Y302220D01*
X891118Y300875D01*
X876240D01*
X844840Y332275D01*
X697819D01*
X680019Y314475D01*
X632717D01*
X626765Y320427D01*
Y329165D01*
X627500Y329900D01*
G01X628000Y333850D02*
X626818Y332668D01*
Y330582D01*
X627500Y329900D01*
G01X628079Y346807D02*
Y344178D01*
X627277Y343376D01*
X625179D01*
X624000Y342197D01*
Y337350D01*
G01D02*
X622550Y335900D01*
X620200D01*
G01X630047Y346807D02*
Y343288D01*
X628597Y341838D01*
X627007D01*
X626260Y341091D01*
G01X628000Y337350D02*
X626260Y339090D01*
Y341091D01*
G01X608090Y338070D02*
Y334110D01*
G01X604950Y344200D02*
X608090Y341060D01*
Y338070D01*
G01X632000Y333850D02*
Y329100D01*
G01D02*
Y324350D01*
G01X632016Y346807D02*
Y343800D01*
X632750Y343066D01*
Y341033D01*
G01D02*
Y338100D01*
X632000Y337350D01*
G01Y375850D02*
Y372642D01*
X632600Y372042D01*
G01D02*
X632016Y371458D01*
Y366393D01*
G01X623000Y375850D02*
Y371016D01*
X624516Y369500D01*
X627000D01*
X628079Y368421D01*
Y366393D01*
G01X623000Y386850D02*
Y385595D01*
X620812Y383407D01*
Y378038D01*
X623000Y375850D01*
G01X623207Y353647D02*
X617748D01*
X612901Y348800D01*
X609050D01*
X608450Y348200D01*
G01X604950Y344200D02*
Y348200D01*
G01X617000Y375850D02*
X619387Y378237D01*
Y385113D01*
X617650Y386850D01*
X617000D01*
G01X626110Y366593D02*
X625407D01*
X617000Y375000D01*
Y375850D01*
G01X627500Y379350D02*
X632000D01*
G01X627500Y383850D02*
Y379350D01*
G01X632000Y384100D02*
Y379350D01*
G01X623000Y386850D02*
Y387000D01*
X626900Y390900D01*
G01X617000Y386850D02*
X616850Y387000D01*
X613400D01*
G01X646063Y887970D02*
Y877363D01*
X644575Y875875D01*
Y862509D01*
X645813Y861271D01*
Y823313D01*
X628148Y805648D01*
G01X642914Y887970D02*
Y880481D01*
X644388Y879007D01*
Y876993D01*
X643150Y875755D01*
Y861918D01*
X644388Y860680D01*
Y830488D01*
X614444Y800544D01*
G01X713375Y27952D02*
X710812D01*
X709829Y26969D01*
X648797D01*
X641050Y34716D01*
Y56780D01*
X654073Y69803D01*
G01X647000Y143000D02*
X654500D01*
G01X659881Y197442D02*
Y196419D01*
X682000Y174300D01*
G01X663756Y204942D02*
Y208506D01*
X667250Y212000D01*
G01X663750D02*
X660700D01*
G01X671000Y215000D02*
X670250D01*
X667250Y212000D01*
G01X655750Y340100D02*
Y344600D01*
G01X659750Y340100D02*
X655750D01*
G01X642993Y349710D02*
Y348370D01*
X645724Y345639D01*
Y341417D01*
X646191Y340950D01*
X647621D01*
G01D02*
X649083D01*
X649518Y341385D01*
Y343076D01*
X651042Y344600D01*
X652250D01*
G01X660100D02*
X655750D01*
G01X659750Y376600D02*
Y374555D01*
X660500Y373805D01*
Y372100D01*
G01X655750Y376600D02*
X659750D01*
G01X655750D02*
Y372100D01*
G01X652250D02*
X648600D01*
X648500Y372000D01*
G01D02*
X642993Y366493D01*
Y363490D01*
G01X638470Y807070D02*
X645900Y814500D01*
G01D02*
X647238Y815838D01*
Y861862D01*
X646000Y863100D01*
Y875500D01*
X649213Y878713D01*
Y887970D01*
G01X727709Y68898D02*
X745500Y86689D01*
Y106916D01*
X747640Y109056D01*
Y113479D01*
X747637Y113482D01*
Y116518D01*
X747640Y116521D01*
Y117960D01*
X674100Y191500D01*
G01X747394Y68898D02*
Y106794D01*
X749065Y108465D01*
Y114070D01*
X749062Y114073D01*
Y115927D01*
X749065Y115930D01*
Y122336D01*
X688200Y183201D01*
Y191200D01*
G01X682000Y174300D02*
X731643Y124657D01*
X737598D01*
X745328Y116927D01*
Y108760D01*
X744000Y107432D01*
Y94179D01*
X722131Y72310D01*
X711436D01*
X708024Y68898D01*
G01X755750Y118800D02*
X752900Y121650D01*
Y122900D01*
X694300Y181500D01*
X693600D01*
X693300Y181200D01*
G01X673881Y197442D02*
Y191719D01*
X674100Y191500D01*
G01X687881Y197442D02*
Y191519D01*
X688200Y191200D01*
G01X677756Y204942D02*
Y208506D01*
X681250Y212000D01*
G01X687900Y208100D02*
Y210950D01*
X689150Y212200D01*
G01X691756Y204942D02*
X692650Y205836D01*
Y212200D01*
G01X697494Y186256D02*
X698675Y185075D01*
X701719D01*
X735319Y151475D01*
X803619D01*
X820694Y134400D01*
Y130312D01*
G01X812089Y140211D02*
X802800Y149500D01*
X734500D01*
X700900Y183100D01*
X698675D01*
X697494Y181919D01*
G01X677750Y212000D02*
X674500D01*
G01X685000Y215000D02*
X684250D01*
X681250Y212000D01*
G01X702756Y887970D02*
Y882272D01*
X701068Y880584D01*
Y874732D01*
X706100Y869700D01*
Y862400D01*
X704619Y860919D01*
Y826697D01*
X712495Y818821D01*
Y816195D01*
G01X705906Y887970D02*
Y883406D01*
X702493Y879993D01*
Y875607D01*
X707558Y870542D01*
Y861842D01*
X706163Y860447D01*
Y827337D01*
X714900Y818600D01*
G01X759850Y35100D02*
Y33182D01*
X761638Y31394D01*
Y23422D01*
X757626Y19410D01*
Y13600D01*
X751729Y7703D01*
Y-5461D01*
X747540Y-9650D01*
X730730D01*
X728395Y-7315D01*
G01X740882Y6D02*
X740822Y66D01*
X727479D01*
X723763Y-3650D01*
G01X717763D02*
X714105D01*
X713461Y-3006D01*
G01X733050Y14000D02*
X732654D01*
X728461Y9807D01*
Y4246D01*
X729132Y3575D01*
G01X733382Y3881D02*
X732837Y4426D01*
Y9562D01*
G01X728960Y15080D02*
X726382Y12502D01*
Y2799D01*
X725963Y2380D01*
G01D02*
X723775Y192D01*
X714971D01*
X713332Y1831D01*
G01X723740Y9594D02*
X721122D01*
X718302Y6774D01*
G01X743250Y33760D02*
X740767Y36243D01*
X736654D01*
X736317Y35906D01*
G01D02*
Y32078D01*
X736513Y31882D01*
G01X762250Y40625D02*
X752043D01*
X749562Y38144D01*
X734887D01*
X733013Y36270D01*
Y31882D01*
G01D02*
Y31237D01*
X736500Y27750D01*
G01X729000Y24800D02*
Y24007D01*
X728960Y23967D01*
Y18580D01*
G01X725314Y24751D02*
Y21505D01*
X724820Y21011D01*
Y18490D01*
G01X721890Y24887D02*
X721649Y24646D01*
Y19369D01*
X720700Y18420D01*
G01X724409Y28613D02*
X722560Y26764D01*
X720570D01*
X718758Y24952D01*
Y22249D01*
X719008Y21999D01*
G01X736550Y14000D02*
Y13275D01*
X732837Y9562D01*
G01X724820Y14990D02*
Y10674D01*
X723740Y9594D01*
G01X720755Y14964D02*
Y13268D01*
X718343Y10856D01*
G01X713375Y27952D02*
X717037D01*
X717325Y28240D01*
G01X720909Y28613D02*
X717698D01*
X717325Y28240D01*
G01X716860Y51796D02*
Y44769D01*
X722594Y39035D01*
X731650D01*
X736234Y43619D01*
Y45309D01*
X747900Y56975D01*
X758118D01*
X767450Y66307D01*
Y68465D01*
G01X738220Y68350D02*
X736990Y69580D01*
X734391D01*
X733709Y68898D01*
G01X734880Y63910D02*
Y64450D01*
X738220Y67790D01*
Y68350D01*
G01X714250Y64000D02*
X718500Y68250D01*
Y68500D01*
G01D02*
X718102Y68898D01*
X714024D01*
G01X720840Y59890D02*
X716860Y55910D01*
Y55860D01*
G01X724890Y59880D02*
X724880Y59890D01*
X720840D01*
G01X732900Y44900D02*
Y48385D01*
X742367Y57852D01*
G01X730021Y42235D02*
Y41829D01*
X730450Y41400D01*
X731999D01*
X734738Y44139D01*
Y45829D01*
X747309Y58400D01*
X756625D01*
X763147Y64922D01*
Y65169D01*
G01X783300Y1100D02*
Y4100D01*
X778275Y9125D01*
X770134D01*
X764698Y3689D01*
Y0D01*
G01X746329Y-7789D02*
X750082Y-4036D01*
Y8072D01*
X756200Y14190D01*
Y20000D01*
X759850Y23650D01*
Y26200D01*
G01X775460Y0D02*
Y3095D01*
X771715Y6840D01*
G01X756350Y35100D02*
X756808Y34642D01*
Y31161D01*
X756565Y30918D01*
G01X749750Y31200D02*
X753750D01*
X754405Y30545D01*
X756192D01*
X756565Y30918D01*
G01X762250Y40625D02*
X763400Y39475D01*
Y35200D01*
G01X756350Y26200D02*
X755046D01*
X752606Y28640D01*
X749750D01*
G01X752300Y16200D02*
X747650Y11550D01*
X742700D01*
G01X764150Y26200D02*
Y24350D01*
X772300Y16200D01*
G01X756050Y53800D02*
Y45800D01*
X754750Y44500D01*
G01D02*
X751125D01*
X747250Y40625D01*
G01X756050Y53800D02*
X760084D01*
G01X758000Y68500D02*
X757602Y68898D01*
X753394D01*
G01X757250Y64000D02*
X758000Y64750D01*
Y68500D01*
G01X742367Y57852D02*
X744815Y60300D01*
X756509D01*
X760238Y64029D01*
Y69427D01*
X753512Y76153D01*
Y81056D01*
X756756Y84300D01*
X760300D01*
X761350Y85350D01*
Y86500D01*
G01X761200Y75900D02*
Y73960D01*
X763147Y72013D01*
Y65169D01*
G01X773638Y82700D02*
X771200D01*
X767300Y78800D01*
Y74150D01*
X767450Y74000D01*
G01D02*
Y68465D01*
G01X741600Y41000D02*
X741500Y41100D01*
X741000D01*
X739750Y42350D01*
Y44500D01*
G01X773638Y90380D02*
X765230D01*
X761350Y86500D01*
G01Y82300D02*
X762600D01*
X766000Y85700D01*
G01X761350Y82300D02*
Y80950D01*
X759600Y79200D01*
G01X766000Y85700D02*
X768120Y87820D01*
X773638D01*
G01Y85260D02*
X771160D01*
X761800Y75900D01*
X761200D01*
G01X765300Y104150D02*
X769400D01*
G01X773617Y104731D02*
X769981D01*
X769400Y104150D01*
G01X761350Y102900D02*
Y98800D01*
G01D02*
X765900D01*
X766683Y99583D01*
G01X773638Y95500D02*
X770766D01*
X766683Y99583D01*
G01X761350Y94700D02*
Y90600D01*
G01Y94700D02*
X765700D01*
X766000Y94400D01*
G01X773638Y92940D02*
X767460D01*
X766000Y94400D01*
G01X768950Y129400D02*
Y133500D01*
G01X776538Y126900D02*
X771450D01*
X768950Y129400D01*
G01Y133500D02*
Y138850D01*
X768700Y139100D01*
G01X768950Y125300D02*
Y121200D01*
G01X776538Y124340D02*
X769910D01*
X768950Y125300D01*
G01Y121200D02*
Y118750D01*
X767600Y117400D01*
G01X751300Y115000D02*
X752500Y116200D01*
X757900D01*
X759250Y117550D01*
Y118800D01*
G01X776538Y121780D02*
X773880D01*
X771800Y119700D01*
Y116800D01*
X770162Y115162D01*
X762888D01*
X759250Y118800D01*
G01X815200Y7500D02*
X815100Y7400D01*
X807963D01*
X803264Y2701D01*
Y0D01*
G01X813214Y38497D02*
X801060Y26343D01*
G01X797560D02*
Y18360D01*
X795300Y16100D01*
G01X785300D02*
Y18900D01*
X791800Y25400D01*
Y25850D01*
G01X815500Y20550D02*
X809750D01*
X805300Y16100D01*
G01X778350Y74000D02*
X784490Y80140D01*
X795838D01*
G01X774392Y69785D02*
Y67104D01*
X775381Y66115D01*
G01X778350Y74000D02*
X776217Y71867D01*
Y71610D01*
X774392Y69785D01*
G01X779752Y70067D02*
X781158Y71473D01*
X781523D01*
X784150Y74100D01*
G01D02*
X786850Y76800D01*
X799100D01*
X800775Y78475D01*
Y80901D01*
X798976Y82700D01*
X795838D01*
G01X778800Y66388D02*
Y69115D01*
X779752Y70067D01*
G01X798350Y74200D02*
X798516D01*
X802200Y77884D01*
Y82800D01*
X799740Y85260D01*
X795838D01*
G01X798350Y74200D02*
X795550Y71400D01*
X786807D01*
X782551Y67144D01*
G01X786333Y66963D02*
X788970Y69600D01*
X800800D01*
X806750Y75550D01*
Y82400D01*
G01D02*
X805800D01*
X800380Y87820D01*
X795838D01*
G01X773638Y98060D02*
X773500Y98198D01*
Y104614D01*
X773617Y104731D01*
G01X795838Y90380D02*
X801720D01*
X802600Y89500D01*
G01X806750Y90600D02*
X803700D01*
X802600Y89500D01*
G01X795838Y92940D02*
X799626D01*
X799898Y93212D01*
X802093D01*
X804381Y95500D01*
X805950D01*
X806850Y94600D01*
G01Y98700D02*
X805625Y97475D01*
X803562D01*
X801274Y95187D01*
X799898D01*
X799585Y95500D01*
X795838D01*
G01X777050Y135200D02*
X781050D01*
X781100Y135150D01*
G01X776538Y129460D02*
Y134688D01*
X777050Y135200D01*
G01X781100Y135150D02*
X785150D01*
X786200Y136200D01*
G01X808663Y118898D02*
X806402D01*
X803520Y121780D01*
X798738D01*
G01X805247Y124676D02*
X810630D01*
X811675Y123631D01*
G01X805247Y124676D02*
X802856D01*
X802520Y124340D01*
X798738D01*
G01X805247Y123218D02*
Y124676D01*
G01X807801Y126651D02*
X802768D01*
X802519Y126900D01*
X798738D01*
G01X815634Y0D02*
X809713D01*
X807514Y2199D01*
G01X826700Y2000D02*
X819097D01*
Y2080D01*
X817500Y3677D01*
Y5200D01*
X815200Y7500D01*
G01X813214Y38497D02*
Y40735D01*
X813962Y41483D01*
Y65487D01*
X823551Y75076D01*
Y80551D01*
G01X838252Y17750D02*
Y20800D01*
G01X839467Y29400D02*
Y22167D01*
X838252Y20952D01*
Y20800D01*
G01X834252Y17750D02*
Y20552D01*
X834500Y20800D01*
G01X837892Y29400D02*
Y24976D01*
X834500Y21584D01*
Y20800D01*
G01X830252Y17750D02*
Y20552D01*
X830500Y20800D01*
G01D02*
X831700D01*
X836317Y25417D01*
Y29400D01*
G01X828283Y24734D02*
X829879Y23138D01*
X831960D01*
X834742Y25920D01*
Y29400D01*
G01X828283Y24734D02*
X826252Y22703D01*
Y17750D01*
G01X824462Y25770D02*
X825385Y26693D01*
X828996D01*
X830226Y25463D01*
X832196D01*
X833167Y26434D01*
Y29400D01*
G01X822252Y17750D02*
X824297Y19795D01*
Y25605D01*
X824462Y25770D01*
G01X824118Y47629D02*
Y44398D01*
X823996Y44276D01*
G01X824118Y51129D02*
X820018D01*
G01X824118D02*
Y55116D01*
G01D02*
Y59693D01*
X824450Y60025D01*
G01X820018Y47629D02*
Y44248D01*
X820004Y44234D01*
G01X816950Y63900D02*
X828225D01*
X828700Y63425D01*
Y48800D01*
G01X837892Y51600D02*
Y66904D01*
X839289Y68301D01*
G01X878394Y85780D02*
X867861Y75247D01*
X846235D01*
X839289Y68301D01*
G01X836317Y51600D02*
Y69489D01*
X842707Y75879D01*
G01X839467Y51600D02*
Y64434D01*
X844212Y69179D01*
G01X834742Y51600D02*
Y72242D01*
X835492Y72992D01*
G01X871696Y87082D02*
Y85597D01*
X864196Y78097D01*
X843654D01*
X843634Y78117D01*
X841780D01*
X841760Y78097D01*
X840597D01*
X835492Y72992D01*
G01X808114Y67634D02*
X809825Y69345D01*
Y69359D01*
X816600Y76134D01*
Y83025D01*
G01X816043Y94981D02*
X815361Y95663D01*
X813062D01*
X811999Y94600D01*
X810350D01*
G01X816043Y99318D02*
X814363Y97638D01*
X813062D01*
X812000Y98700D01*
X810350D01*
G01X835350Y105600D02*
X833128D01*
X833098Y105630D01*
X831310D01*
G01X835350Y105600D02*
X835500Y105450D01*
Y100500D01*
G01X838850Y105600D02*
X843820Y110570D01*
X847710D01*
G01X816600Y83025D02*
X813125Y86500D01*
X810250D01*
G01X806750Y90600D02*
Y86500D01*
G01X820694Y130312D02*
Y127149D01*
X818241Y124696D01*
X816240D01*
X815175Y123631D01*
G01X820694Y130312D02*
X822035D01*
G01X812089Y140211D02*
X818719Y133581D01*
Y127968D01*
X817422Y126671D01*
X816135D01*
X815175Y127631D01*
G01X811202Y139324D02*
X812089Y140211D01*
G01X808663Y118898D02*
Y115563D01*
X807900Y114800D01*
G01X811675Y127631D02*
X810695Y126651D01*
X807801D01*
G01D02*
Y127889D01*
G01X840500Y735500D02*
X840000Y736000D01*
Y742500D01*
X830569Y751931D01*
G01X822441Y887970D02*
Y753697D01*
X833086Y743052D01*
G01X837000Y735500D02*
Y739138D01*
X833086Y743052D01*
G01X844000Y735500D02*
Y744500D01*
X828394Y760106D01*
G01X825591Y887970D02*
Y881407D01*
X825175Y880991D01*
Y757325D01*
X830569Y751931D01*
G01X869756Y801148D02*
Y803344D01*
X864600Y808500D01*
X848000D01*
X838000Y798500D01*
Y764500D01*
X844500Y758000D01*
G01X831890Y887970D02*
Y883590D01*
X828300Y880000D01*
Y767700D01*
X848000Y748000D01*
Y735500D01*
G01X828741Y887970D02*
Y882541D01*
X826600Y880400D01*
Y761900D01*
X828394Y760106D01*
G01X860450Y3900D02*
X861000Y3350D01*
Y350D01*
G01X862250Y8000D02*
X861357D01*
X857453Y4096D01*
Y303D01*
G01X863950Y3900D02*
Y-349D01*
X864425Y-824D01*
X865500D01*
G01D02*
X868476D01*
X869830Y530D01*
X872850D01*
G01X865750Y8000D02*
X869280Y4470D01*
X872850D01*
G01Y6435D02*
Y7270D01*
X867500Y12620D01*
Y12750D01*
G01X877300Y6000D02*
X876865Y6435D01*
X872850D01*
G01X877300Y6000D02*
Y408D01*
X875457Y-1435D01*
X872850D01*
G01X850300Y14250D02*
X849100Y13050D01*
Y7818D01*
X849581Y7337D01*
Y5549D01*
X849631Y5499D01*
G01D02*
X851199Y3931D01*
X853680D01*
X853681Y3932D01*
X854453D01*
G01X845934Y-1815D02*
Y-4548D01*
X849156Y-7770D01*
X951773D01*
X966594Y7051D01*
Y15294D01*
X970064Y18764D01*
G01X963700Y21700D02*
X965000Y20400D01*
Y7473D01*
X951182Y-6345D01*
X852707D01*
X851934Y-5572D01*
Y-1815D01*
G01X867500Y23750D02*
Y25957D01*
X868819Y27276D01*
G01X873250Y22375D02*
Y25400D01*
X871374Y27276D01*
X868819D01*
G01X863300Y23575D02*
X866625Y20250D01*
X867500D01*
G01D02*
Y16250D01*
G01X875000Y41000D02*
X870435D01*
X869344Y39909D01*
X869250D01*
G01X865250Y36000D02*
Y40000D01*
G01D02*
X869159D01*
X869250Y39909D01*
G01X875000Y36000D02*
X870383D01*
X869199Y34816D01*
X869195D01*
G01X865250Y28000D02*
Y32000D01*
G01D02*
X868063Y34813D01*
X869192D01*
X869195Y34816D01*
G01X850300Y17750D02*
Y19659D01*
X849051Y20908D01*
G01X846252Y17750D02*
Y19092D01*
X845674Y19670D01*
Y20178D01*
X845052Y20800D01*
G01X842612Y29400D02*
Y23240D01*
X845052Y20800D01*
G01X842252Y17750D02*
Y19948D01*
X841652Y20548D01*
Y20800D01*
G01X841037Y29400D02*
Y22015D01*
X841400Y21652D01*
Y21052D01*
X841652Y20800D01*
G01X867500Y12750D02*
X869500Y14750D01*
Y15200D01*
X870600Y16300D01*
Y18915D01*
G01X850300Y14250D02*
X848700Y15850D01*
X848650D01*
X848200Y16300D01*
Y19160D01*
X847213Y20147D01*
Y21587D01*
X844187Y24613D01*
Y29400D01*
G01X854400Y17750D02*
Y20652D01*
X854252Y20800D01*
G01X845762Y29400D02*
Y25538D01*
X848554Y22746D01*
X849812D01*
X851558Y21000D01*
X854052D01*
X854252Y20800D01*
G01X875000Y46000D02*
X874400Y45400D01*
X869250D01*
G01D02*
X866150Y48500D01*
X865750D01*
G01D02*
X865700Y48450D01*
Y46662D01*
X865583Y46545D01*
Y45922D01*
X865533Y45872D01*
Y44084D01*
X865583Y44034D01*
G01X845762Y51600D02*
Y54468D01*
X850694Y59400D01*
X863500D01*
G01D02*
X873500D01*
X884100Y70000D01*
X894350D01*
X899200Y65150D01*
G01X842612Y51600D02*
Y58112D01*
X848781Y64281D01*
G01X892900Y85300D02*
X873050Y65450D01*
X849950D01*
X848781Y64281D01*
G01X885042Y85292D02*
X873572Y73822D01*
X848855D01*
X844212Y69179D01*
G01X841037Y51600D02*
Y62037D01*
X842300Y63300D01*
G01X888600Y85700D02*
X871613Y68713D01*
X847713D01*
X842300Y63300D01*
G01X844187Y51600D02*
Y54909D01*
X851778Y62500D01*
X856000D01*
G01X897600Y85500D02*
X883525Y71425D01*
X883509D01*
X874584Y62500D01*
X856000D01*
G01X865750Y52800D02*
Y52250D01*
X868800Y49200D01*
G01X871250Y52800D02*
Y51650D01*
X868800Y49200D01*
G01X875001Y86003D02*
X865670Y76672D01*
X843500D01*
X842707Y75879D01*
G01X875000Y89750D02*
Y89220D01*
X872862Y87082D01*
X871696D01*
G01X847710Y110570D02*
X862570D01*
X868000Y116000D01*
X868200D01*
G01X846730Y123128D02*
X846702Y123100D01*
Y117371D01*
G01X854510Y122640D02*
X854400Y122530D01*
Y117500D01*
G01X861310Y122608D02*
Y117810D01*
X861300Y117800D01*
G01X869406Y748648D02*
Y745531D01*
G01X865406Y748648D02*
Y745598D01*
G01X873406Y748574D02*
Y745374D01*
X873367Y745335D01*
G01X873352Y741450D02*
Y745320D01*
X873367Y745335D01*
G01X860826Y764298D02*
Y762626D01*
X859938Y761738D01*
X857934D01*
X854049Y757853D01*
Y757573D01*
G01X857406Y752148D02*
Y755198D01*
G01X863386Y764298D02*
Y761738D01*
X858679Y757031D01*
X858406D01*
X857406Y756031D01*
Y755198D01*
G01X865946Y764298D02*
Y761353D01*
X865599Y761006D01*
Y759599D01*
X864000Y758000D01*
G01X861406Y755198D02*
Y755406D01*
X864000Y758000D01*
G01X861406Y752148D02*
Y755198D01*
G01X869406Y752148D02*
Y758301D01*
X869562Y758457D01*
G01X871066Y764298D02*
Y759961D01*
X869562Y758457D01*
G01X871066Y786498D02*
Y782066D01*
X870500Y781500D01*
X856292D01*
X855292Y782500D01*
G01X839990Y789230D02*
X848130D01*
X854860Y782500D01*
X855292D01*
G01X865406Y752148D02*
Y753159D01*
X867410Y755163D01*
Y755824D01*
G01X868506Y764298D02*
Y761897D01*
X867024Y760415D01*
Y756210D01*
X867410Y755824D01*
G01X873626Y764298D02*
Y761418D01*
X872966Y760758D01*
Y757881D01*
X872244Y757159D01*
Y755738D01*
G01X873406Y752074D02*
Y754576D01*
X872244Y755738D01*
G01X863374Y792846D02*
Y793482D01*
X861406Y795450D01*
Y797648D01*
G01X865946Y786498D02*
Y790274D01*
X863374Y792846D01*
G01X858000Y794000D02*
X858010Y793990D01*
X860072D01*
X861136Y792926D01*
Y791888D01*
X863386Y789638D01*
Y786498D01*
G01X857406Y797648D02*
Y794594D01*
X858000Y794000D01*
G01X868506Y786498D02*
Y792903D01*
X866878Y794531D01*
G01X865478Y797681D02*
Y795931D01*
X866878Y794531D01*
G01X871066Y786498D02*
Y793743D01*
X870278Y794531D01*
G01X869756Y797648D02*
Y795053D01*
X870278Y794531D01*
G01X870900Y805350D02*
X871800Y804450D01*
Y799899D01*
X869756Y797855D01*
Y797648D01*
G01X861406Y801148D02*
Y804403D01*
G01X857406Y801148D02*
Y804403D01*
G01X889150Y530D02*
X884830D01*
X883800Y-500D01*
G01X889150Y4470D02*
X886470D01*
X885000Y3000D01*
X884976D01*
X884491Y2515D01*
X881915D01*
X881700Y2300D01*
G01X889150Y-1435D02*
X920018D01*
X927361Y5908D01*
G01Y13778D02*
X927369D01*
X930607Y10540D01*
Y-1410D01*
X927647Y-4370D01*
X879913D01*
X878755Y-3212D01*
Y-931D01*
X879500Y-186D01*
Y3700D01*
X880290Y4490D01*
X883672D01*
X885617Y6435D01*
X889150D01*
G01X886520Y16752D02*
X883247Y13479D01*
Y7378D01*
X882334Y6465D01*
X877765D01*
X877300Y6000D01*
G01X895300Y23000D02*
Y17950D01*
X896500Y16750D01*
G01X904750Y37000D02*
Y41000D01*
G01X891301Y16627D02*
X886645D01*
X886520Y16752D01*
G01X889700Y23000D02*
X885250D01*
X880750Y18500D01*
G01X895000Y36000D02*
X899000D01*
X901000Y34000D01*
G01X904750Y33000D02*
X902000D01*
X901000Y34000D01*
G01X895000Y31000D02*
X899000D01*
X901000Y29000D01*
G01X904750D02*
X901000D01*
G01X895000Y41000D02*
X900000D01*
X901000Y42000D01*
G01X904750Y41000D02*
X902000D01*
X901000Y42000D01*
G01X899200Y65150D02*
X902000Y67950D01*
Y85841D01*
X901899Y85942D01*
G01X885300Y64650D02*
X882134D01*
X878992Y61508D01*
G01D02*
X878800Y61316D01*
Y56350D01*
G01D02*
X875250Y52800D01*
X874750D01*
G01X892900Y64650D02*
X895900Y61650D01*
X899200D01*
G01D02*
X902850D01*
X903000Y61500D01*
G01X910000Y85300D02*
X906230D01*
X906200Y85270D01*
G01X884000Y89750D02*
X882693D01*
X880905Y87962D01*
X880576D01*
X878394Y85780D01*
G01X879500Y89750D02*
X879208D01*
X875461Y86003D01*
X875001D01*
G01X906500Y89750D02*
X906092D01*
X902142Y85800D01*
X902000Y85942D01*
X901899D01*
G01X897500Y89750D02*
X893050Y85300D01*
X892900D01*
G01X888500Y89750D02*
Y89300D01*
X885326Y86126D01*
Y85576D01*
X885042Y85292D01*
G01X893000Y89750D02*
X888950Y85700D01*
X888600D01*
G01X902000Y89750D02*
X897750Y85500D01*
X897600D01*
G01X903937Y141732D02*
X901969Y139764D01*
G01X903937Y137795D02*
X901969Y135827D01*
G01X903937Y133858D02*
X901969Y131890D01*
G01X907874Y141732D02*
X905906Y139764D01*
G01X907874Y137795D02*
X905906Y135827D01*
G01X907874Y133858D02*
X905906Y131890D01*
G01X903937Y149606D02*
X901969Y147638D01*
G01X903937Y145669D02*
X901969Y143701D01*
G01X907874Y157480D02*
X905906Y155512D01*
G01X907874Y153543D02*
X905906Y151575D01*
G01X907874Y149606D02*
X905906Y147638D01*
G01X907874Y145669D02*
X905906Y143701D01*
G01X903937Y157480D02*
X901969Y155512D01*
G01X903937Y153543D02*
X901969Y151575D01*
G01X894220Y318510D02*
Y310130D01*
X895000Y309350D01*
G01D02*
X896406D01*
X898817Y311761D01*
G01X887500Y312000D02*
X890150Y309350D01*
X891000D01*
G01D02*
X891660Y310010D01*
Y318510D01*
G01X894220Y334690D02*
Y339088D01*
X892837Y340471D01*
Y354937D01*
X896200Y358300D01*
G01X896780Y334690D02*
Y338544D01*
X894262Y341062D01*
Y347962D01*
X896500Y350200D01*
G01X899340Y334690D02*
Y338000D01*
X896500Y340840D01*
Y342500D01*
G01D02*
X898100D01*
X899000Y341600D01*
X900250D01*
G01D02*
Y345600D01*
G01X906500Y316500D02*
X904772Y314772D01*
X897728D01*
X896780Y315720D01*
Y318510D01*
G01X896200Y358300D02*
X896400Y358500D01*
X900250D01*
G01D02*
Y363000D01*
G01X896500Y350200D02*
X896700Y350000D01*
X900250D01*
G01D02*
Y354000D01*
G01X1034500Y108500D02*
X1035710Y109710D01*
Y115410D01*
X1037900Y117600D01*
Y246368D01*
X1207932Y416400D01*
X1270450D01*
X1316700Y462650D01*
Y608000D01*
X1302300Y622400D01*
X1120200D01*
X1089400Y591600D01*
X922500D01*
X894700Y619400D01*
Y726700D01*
X894090Y727310D01*
Y736690D01*
X895800Y738400D01*
G01X1198819Y887970D02*
Y882119D01*
X1197131Y880431D01*
Y872569D01*
X1204100Y865600D01*
Y850750D01*
X1201250Y847900D01*
Y824400D01*
X1185499Y808649D01*
Y706499D01*
X1076225Y597225D01*
X931666Y597224D01*
X920228D01*
X897500Y619952D01*
Y733000D01*
X896500Y734000D01*
G01X1172500Y742500D02*
Y697568D01*
X1170473Y695541D01*
Y694213D01*
X1074910Y598650D01*
X921999Y598649D01*
X920819D01*
X903187Y616281D01*
Y810287D01*
X906092Y813192D01*
Y813687D01*
G01X1169000Y750500D02*
Y694870D01*
X1074205Y600075D01*
X921409D01*
X904612Y616872D01*
Y808012D01*
X906396Y809796D01*
Y810300D01*
G01X906450Y806900D02*
Y617050D01*
X922000Y601500D01*
X1072416D01*
X1165375Y694459D01*
Y757000D01*
G01X884700Y721100D02*
Y731489D01*
X879549Y736640D01*
Y740949D01*
X885406Y746806D01*
Y748648D01*
G01X877406D02*
Y745406D01*
X877000Y745000D01*
G01X891056Y755641D02*
X891568Y755129D01*
Y750486D01*
X893406Y748648D01*
G01X892100Y721100D02*
Y741338D01*
X891530Y741908D01*
Y746772D01*
X893406Y748648D01*
G01X881406D02*
Y744822D01*
X878124Y741540D01*
Y741465D01*
X878064Y741405D01*
Y736106D01*
X881200Y732970D01*
Y721300D01*
G01X888400Y721400D02*
X889600Y722600D01*
Y739800D01*
G01D02*
X889406Y739994D01*
Y748648D01*
G01X885406Y752148D02*
Y755570D01*
X884778Y756198D01*
G01X881306Y764298D02*
Y762130D01*
X882428Y761008D01*
Y760993D01*
X882861Y760560D01*
X883108D01*
X884067Y759601D01*
Y759482D01*
X884778Y758771D01*
Y756198D01*
G01X877406Y752148D02*
X877206Y752348D01*
Y754311D01*
X876036Y755481D01*
G01X876186Y764298D02*
Y761686D01*
X876748Y761124D01*
Y756193D01*
X876036Y755481D01*
G01X894465Y755501D02*
Y753207D01*
X893406Y752148D01*
G01X886426Y764298D02*
Y761841D01*
X887767Y760500D01*
X890699D01*
X894465Y756734D01*
Y755501D01*
G01X897600Y752050D02*
X897502Y752148D01*
X893406D01*
G01X881406D02*
X879816Y753738D01*
Y755877D01*
G01X878746Y764298D02*
Y760476D01*
X879595Y759627D01*
X881435D01*
X882227Y758835D01*
G01D02*
X879816Y756424D01*
Y755877D01*
G01X883866Y764298D02*
Y762016D01*
X886685Y759197D01*
X886958D01*
X888087Y758068D01*
G01X889406Y752148D02*
Y753471D01*
X889114Y753763D01*
Y757041D01*
X888087Y758068D01*
G01X894200Y794500D02*
Y790371D01*
X894108Y790279D01*
G01X886426Y786498D02*
Y788681D01*
X887981Y790236D01*
X894065D01*
X894108Y790279D01*
G01X894406Y797648D02*
Y794706D01*
X894200Y794500D01*
G01X894406Y801148D02*
Y818000D01*
G01X877930Y796880D02*
Y795799D01*
X876186Y794055D01*
Y786498D01*
G01X877930Y796880D02*
Y800231D01*
X877949Y800250D01*
G01X876470Y808710D02*
Y805229D01*
X877949Y803750D01*
G01X889920Y808230D02*
X889926Y807396D01*
X888278Y805748D01*
Y802300D01*
X886276Y800298D01*
G01X881306Y786498D02*
Y790006D01*
X883905Y792605D01*
X884758D01*
X886288Y794135D01*
Y794372D01*
G01D02*
Y800286D01*
X886276Y800298D01*
G01X888100Y823338D02*
X883226Y818464D01*
X883225D01*
X882750Y817989D01*
Y809350D01*
X884017Y808083D01*
Y806057D01*
X886276Y803798D01*
G01X888986Y786498D02*
X896898D01*
X898700Y788300D01*
G01Y794200D02*
Y788300D01*
G01X898406Y797648D02*
Y794494D01*
X898700Y794200D01*
G01X898406Y801148D02*
Y815706D01*
X898700Y816000D01*
G01X878746Y786498D02*
Y791214D01*
X879696Y792164D01*
G01D02*
X882290Y794758D01*
Y796770D01*
G01D02*
X882049Y797011D01*
Y800250D01*
G01Y803750D02*
Y807061D01*
X881720Y807390D01*
G01X883866Y786498D02*
Y789387D01*
X885340Y790861D01*
X886590D01*
X887390Y791661D01*
X888494D01*
X890049Y793216D01*
G01X890406Y797648D02*
Y793573D01*
X890049Y793216D01*
G01X890200Y819200D02*
Y813476D01*
X891137Y812539D01*
G01D02*
X892210Y811466D01*
Y802952D01*
X890406Y801148D01*
G01X873626Y786498D02*
Y792026D01*
X873700Y792100D01*
G01X873850Y797650D02*
Y792250D01*
X873700Y792100D01*
G01X873850Y801150D02*
Y811100D01*
X874570Y811820D01*
G01X938000Y23250D02*
X937338D01*
X932653Y18565D01*
X927201D01*
X923300Y14664D01*
Y9722D01*
X919486Y5908D01*
G01X930720Y23540D02*
Y23185D01*
X927525Y19990D01*
X925706D01*
X922725Y17009D01*
X922717D01*
X919486Y13778D01*
G01X1021310Y2024D02*
X1020500Y2834D01*
Y5600D01*
X1017554Y8546D01*
X977000D01*
X971900Y13646D01*
Y18001D01*
X971902Y18003D01*
Y19525D01*
X971900Y19527D01*
Y21700D01*
X969932Y23668D01*
X959354D01*
X950537Y32485D01*
X934328D01*
X930750Y28907D01*
Y27270D01*
G01D02*
Y23570D01*
X930720Y23540D01*
G01X908250Y33000D02*
X909488Y31762D01*
X910140D01*
X915957Y37579D01*
Y40559D01*
X915486Y41030D01*
G01X908250Y29000D02*
X909037Y29787D01*
X910959D01*
X917932Y36760D01*
Y39660D01*
X918952Y40680D01*
G01X938000Y23250D02*
X939907D01*
X942031Y25374D01*
G01X935350Y67400D02*
Y67725D01*
X932113Y70962D01*
X928398D01*
G01X939064Y58104D02*
X930682Y66486D01*
X929616D01*
X928398Y67704D01*
Y70962D01*
G01X934881Y57322D02*
Y60271D01*
X930889Y64263D01*
X927943D01*
X925338Y66868D01*
Y76495D01*
X925300Y76533D01*
Y78500D01*
G01X911000Y89750D02*
Y86200D01*
X910100Y85300D01*
X910000D01*
G01X937642Y85562D02*
X939548Y83656D01*
Y82742D01*
X940377Y81913D01*
G01X938000Y89750D02*
Y85920D01*
X937642Y85562D01*
G01X926093Y85239D02*
X924131D01*
X922015Y83123D01*
G01X924500Y89750D02*
Y86832D01*
X926093Y85239D01*
G01X929213Y86593D02*
Y82894D01*
X929060Y82741D01*
G01X929000Y89750D02*
Y86806D01*
X929213Y86593D01*
G01X934438Y86700D02*
X934779Y86359D01*
Y82801D01*
G01X933500Y89750D02*
X931500Y87750D01*
Y85819D01*
X934779Y82540D01*
Y82801D01*
G01X919050Y85500D02*
X918341D01*
X915908Y83067D01*
G01X920000Y89750D02*
X919050Y88800D01*
Y85500D01*
G01X913979Y86580D02*
X912914Y85515D01*
Y83569D01*
X910754Y81409D01*
G01X915500Y89750D02*
Y88101D01*
X913979Y86580D01*
G01X928850Y78600D02*
X925400D01*
X925300Y78500D01*
G01X911811Y133858D02*
X909843Y131890D01*
G01X915748Y133858D02*
X913780Y131890D01*
G01X923622Y141732D02*
X921654Y139764D01*
G01X931496Y141732D02*
X929528Y139764D01*
G01X927559Y141732D02*
X925591Y139764D01*
G01X923622Y133858D02*
X921654Y131890D01*
G01X915748Y137795D02*
X913780Y135827D01*
G01X919685Y141732D02*
X917717Y139764D01*
G01X919685Y133858D02*
X917717Y131890D01*
G01X919685Y137795D02*
X917717Y135827D01*
G01X911811Y141732D02*
X909843Y139764D01*
G01X939370Y157480D02*
X937402Y155512D01*
G01X915748Y145669D02*
X913780Y143701D01*
G01X915748Y161417D02*
X913780Y159449D01*
G01X915748Y149606D02*
X913780Y147638D01*
G01X919685Y161417D02*
X917717Y159449D01*
G01X915748Y157480D02*
X913780Y155512D01*
G01X915748Y153543D02*
X913780Y151575D01*
G01X935433Y153543D02*
X933465Y151575D01*
G01X935433Y157480D02*
X933465Y155512D01*
G01X923622Y153543D02*
X921654Y151575D01*
G01X931496Y153543D02*
X929528Y151575D01*
G01X931496Y157480D02*
X929528Y155512D01*
G01X927559Y145669D02*
X925591Y143701D01*
G01X927559Y149606D02*
X925591Y147638D01*
G01X927559Y157480D02*
X925591Y155512D01*
G01X911811Y161417D02*
X909843Y159449D01*
G01X911811Y145669D02*
X909843Y143701D01*
G01X911811Y157480D02*
X909843Y155512D01*
G01X919685Y157480D02*
X917717Y155512D01*
G01X919685Y153543D02*
X917717Y151575D01*
G01X919685Y145669D02*
X917717Y143701D01*
G01X919685Y149606D02*
X917717Y147638D01*
G01X923622Y157480D02*
X921654Y155512D01*
G01X955400Y68950D02*
X958950D01*
X959300Y68600D01*
G01X958831Y64624D02*
X959300Y65093D01*
Y68600D01*
G01X955331Y64624D02*
X954232Y63525D01*
X950120D01*
G01D02*
X942850D01*
G01X942500Y93250D02*
Y102500D01*
G01X947244Y125984D02*
X945606Y124346D01*
Y117106D01*
X942500Y114000D01*
Y102500D01*
G01X947000Y93250D02*
Y106000D01*
G01X947244Y118110D02*
X947000Y117866D01*
Y106000D01*
G01X951500Y93250D02*
Y101500D01*
X953000Y103000D01*
Y108000D01*
G01X956000Y89750D02*
X960417D01*
X960522Y89645D01*
G01X956687Y85482D02*
X958482D01*
X960522Y87522D01*
Y89645D01*
G01X942800Y85700D02*
X945590Y82910D01*
Y82830D01*
G01X942500Y89750D02*
Y86000D01*
X942800Y85700D01*
G01X948200Y85900D02*
X951070Y83030D01*
Y82791D01*
X950970D01*
G01X947000Y89750D02*
Y87100D01*
X948200Y85900D01*
G01X953301Y85793D02*
Y84245D01*
X956313Y81233D01*
Y81319D01*
G01X951500Y89750D02*
Y87800D01*
X953301Y85999D01*
Y85793D01*
G01X951181Y129921D02*
X953149Y127953D01*
G01X947244Y129921D02*
X949212Y127953D01*
G01X943307Y129921D02*
X941339Y127953D01*
G01X947244Y122047D02*
X948882Y120409D01*
Y116118D01*
X953000Y112000D01*
Y108000D01*
G01X947244Y141732D02*
X949212Y139764D01*
G01X970866Y141732D02*
X972834Y139764D01*
G01X951181Y141732D02*
X953149Y139764D01*
G01X951181Y133858D02*
X953149Y131890D01*
G01X955118Y133858D02*
X957086Y131890D01*
G01X962992Y133858D02*
X964960Y131890D01*
G01X959055Y141732D02*
X961023Y139764D01*
G01X959055Y133858D02*
X961023Y131890D01*
G01X959055Y137795D02*
X961023Y135827D01*
G01X955118Y137795D02*
X957086Y135827D01*
G01X970866Y137795D02*
X972834Y135827D01*
G01X970866Y133858D02*
X972834Y131890D01*
G01X974803Y133858D02*
X976771Y131890D01*
G01X962992Y137795D02*
X964960Y135827D01*
G01X962992Y141732D02*
X964960Y139764D01*
G01X966929Y137795D02*
X968897Y135827D01*
G01X966929Y133858D02*
X968897Y131890D01*
G01X974803Y137795D02*
X976771Y135827D01*
G01X947244Y157480D02*
X949212Y155512D01*
G01X943307Y153543D02*
X941339Y151575D01*
G01X943307Y157480D02*
X941339Y155512D01*
G01X970866Y153543D02*
X972834Y151575D01*
G01X974803Y153543D02*
X976771Y151575D01*
G01X955118Y145669D02*
X957086Y143701D01*
G01X959055Y145669D02*
X961023Y143701D01*
G01X955118Y153543D02*
X957086Y151575D01*
G01X955118Y149606D02*
X957086Y147638D01*
G01X955118Y157480D02*
X957086Y155512D01*
G01X951181Y145669D02*
X953149Y143701D01*
G01X951181Y157480D02*
X953149Y155512D01*
G01X962992Y145669D02*
X964960Y143701D01*
G01X959055Y157480D02*
X961023Y155512D01*
G01X959055Y153543D02*
X961023Y151575D01*
G01X962992Y157480D02*
X964960Y155512D01*
G01X962992Y153543D02*
X964960Y151575D01*
G01X966929Y157480D02*
X968897Y155512D01*
G01X974803Y149606D02*
X976771Y147638D01*
G01X962992Y149606D02*
X964960Y147638D01*
G01X966929Y149606D02*
X968897Y147638D01*
G01X974803Y157480D02*
X976771Y155512D01*
G01X974803Y141732D02*
X976771Y139764D01*
G01X966929Y145669D02*
X968897Y143701D01*
G01X974803Y161417D02*
X976771Y159449D01*
G01X970866Y145669D02*
X972834Y143701D01*
G01X974803Y145669D02*
X976771Y143701D01*
G01X970866Y157480D02*
X972834Y155512D01*
G01X1035040Y887970D02*
Y884283D01*
X1031626Y880869D01*
Y825158D01*
X1031900Y824884D01*
Y636900D01*
X1002000Y607000D01*
X960500D01*
G01X1028741Y887970D02*
Y638241D01*
X1001500Y611000D01*
X957500D01*
X953500Y607000D01*
G01X1031890Y887970D02*
Y883190D01*
X1030201Y881501D01*
Y637217D01*
X1001984Y609000D01*
X958900D01*
X956900Y607000D01*
G01X985579Y26494D02*
X986333Y27248D01*
X989119D01*
G01Y23121D02*
X985531D01*
X985403Y22993D01*
G01X1009753Y13707D02*
Y16174D01*
X1008067Y17860D01*
Y21604D01*
X1004597Y25074D01*
X995967D01*
X994869Y26172D01*
X993695D01*
X992619Y27248D01*
G01X1004753Y13707D02*
Y16198D01*
X1006092Y17537D01*
Y20785D01*
X1003778Y23099D01*
X995148D01*
X994050Y24197D01*
X993695D01*
X992619Y23121D01*
G01X999753Y13707D02*
Y17144D01*
X999169Y17728D01*
X996129D01*
X992561Y14160D01*
X992461D01*
G01X992002Y37056D02*
X995186D01*
X997134Y39004D01*
X1000820D01*
X1002253Y37571D01*
Y34307D01*
G01X992002Y37056D02*
X990834Y38224D01*
Y40879D01*
X992531Y42576D01*
X995812D01*
X996230Y42994D01*
G01X1002253Y13707D02*
Y18895D01*
X1000667Y20481D01*
X994235D01*
X992540Y18786D01*
Y18675D01*
G01X988167Y18587D02*
X992452D01*
X992540Y18675D01*
G01X1051250Y22200D02*
X1050150Y21100D01*
X1046004D01*
X1044464Y22640D01*
X1010357D01*
X1006498Y26499D01*
X996558D01*
X989409Y33648D01*
Y48479D01*
X990628Y49698D01*
G01X1000480Y41812D02*
Y41360D01*
X1003177Y38663D01*
X1005568D01*
X1007253Y36978D01*
Y34307D01*
G01X1000480Y41812D02*
Y45497D01*
X1000683Y45700D01*
G01X990551Y141732D02*
X992519Y139764D01*
G01X978740Y137795D02*
X980708Y135827D01*
G01X978740Y133858D02*
X980708Y131890D01*
G01X986614Y141732D02*
X988582Y139764D01*
G01X986614Y137795D02*
X988582Y135827D01*
G01X982677Y133858D02*
X984645Y131890D01*
G01X986614Y133858D02*
X988582Y131890D01*
G01X982677Y141732D02*
X984645Y139764D01*
G01X978740Y161417D02*
X980708Y159449D01*
G01X978740Y157480D02*
X980708Y155512D01*
G01X982677Y157480D02*
X984645Y155512D01*
G01X982677Y153543D02*
X984645Y151575D01*
G01X982677Y145669D02*
X984645Y143701D01*
G01X986614Y153543D02*
X988582Y151575D01*
G01X978740Y145669D02*
X980708Y143701D01*
G01X978740Y149606D02*
X980708Y147638D01*
G01X978740Y153543D02*
X980708Y151575D01*
G01X1035642Y11076D02*
Y8542D01*
X1031265Y4165D01*
Y1702D01*
G01X1022711Y-4975D02*
X1024810Y-2876D01*
Y2024D01*
G01D02*
Y4490D01*
X1023600Y5700D01*
Y11500D01*
X1032276Y20176D01*
X1033747D01*
G01X1041108Y1702D02*
Y8987D01*
X1043417Y11296D01*
G01X1033017Y14743D02*
X1033022Y14738D01*
Y14578D01*
X1035642Y11958D01*
Y11076D01*
G01X1039675Y15337D02*
X1039437Y15575D01*
X1037230D01*
X1036064Y16741D01*
Y19216D01*
X1035104Y20176D01*
X1033747D01*
G01X1039917Y11296D02*
Y15095D01*
X1039675Y15337D01*
G01X1009753Y34307D02*
Y37862D01*
X1010676Y38785D01*
Y41512D01*
G01X1056650Y28600D02*
Y29650D01*
X1053400Y32900D01*
Y36593D01*
X1050765Y39228D01*
X1037443D01*
X1036692Y38477D01*
G01D02*
Y33737D01*
X1036866Y33563D01*
G01X1028330Y35032D02*
X1031897D01*
X1033366Y33563D01*
G01X1028330Y35032D02*
Y41229D01*
X1028815Y41714D01*
G01X1030139Y30209D02*
X1032301Y28047D01*
X1032445D01*
X1033571Y26921D01*
G01X1024330Y26232D02*
X1032882D01*
X1033571Y26921D01*
G01X1024432Y43718D02*
X1027659Y46945D01*
X1034127D01*
X1035355Y48173D01*
Y48210D01*
X1035409Y48264D01*
Y48500D01*
X1038052Y51143D01*
Y57740D01*
X1036750Y59042D01*
Y68750D01*
X1052240Y84240D01*
Y90155D01*
X1057000Y94915D01*
Y107700D01*
G01X1033000Y66250D02*
Y49451D01*
X1033517Y48934D01*
G01X1020000Y105250D02*
X1019900Y105350D01*
Y108500D01*
G01X1015948Y105250D02*
Y108500D01*
G01X1032500Y105250D02*
Y106500D01*
X1034500Y108500D01*
G01X1028000Y105250D02*
Y107914D01*
X1027483Y108431D01*
G01X1024000Y105250D02*
Y108500D01*
G01X1037000Y105250D02*
Y106323D01*
X1037808Y107131D01*
Y108408D01*
X1037900Y108500D01*
G01X1041500Y105250D02*
Y106979D01*
X1041361Y107118D01*
Y108439D01*
X1041300Y108500D01*
G01X1019900D02*
Y109700D01*
X1028226Y118026D01*
X1028342D01*
X1033625Y123309D01*
Y250525D01*
X1201000Y417900D01*
G01X1015948Y108500D02*
X1016800D01*
X1031800Y123500D01*
Y251400D01*
X1196600Y416200D01*
G01X1301000Y618500D02*
X1314500Y605000D01*
Y465120D01*
X1268880Y419500D01*
X1209016D01*
X1036475Y246959D01*
Y121459D01*
X1027483Y112467D01*
Y108431D01*
G01X1024000Y108500D02*
Y111000D01*
X1035050Y122050D01*
Y247550D01*
X1208500Y421000D01*
X1257500D01*
X1258000Y421500D01*
G01X1037900Y108500D02*
X1038712Y109312D01*
Y113712D01*
X1040375Y115375D01*
Y245294D01*
X1206806Y411725D01*
X1258770D01*
X1264304Y406191D01*
Y394946D01*
X1265500Y393750D01*
G01X1041300Y108500D02*
X1040687Y109113D01*
Y112893D01*
X1042350Y114556D01*
Y244475D01*
X1207625Y409750D01*
X1257951D01*
X1262329Y405372D01*
Y394579D01*
X1261500Y393750D01*
G01X1031400Y112500D02*
X1030883Y111983D01*
Y108438D01*
G01X1075809Y500D02*
Y-1896D01*
X1077558Y-3645D01*
X1091855D01*
X1097000Y1500D01*
G01X1075809Y5500D02*
Y500D01*
G01X1050951Y1702D02*
Y6449D01*
X1048736Y8664D01*
Y11208D01*
G01X1069200Y-4200D02*
Y5056D01*
X1069131Y5125D01*
Y7363D01*
G01X1076374Y35054D02*
X1071834D01*
X1071559Y35329D01*
G01X1076374Y39554D02*
X1073453D01*
X1071559Y37660D01*
Y35329D01*
G01X1075819Y22450D02*
Y26950D01*
G01D02*
X1076108D01*
X1077946Y28788D01*
X1082022D01*
X1082047Y28763D01*
X1083569D01*
X1083594Y28788D01*
X1083627D01*
X1086613Y31774D01*
G01X1043417Y11296D02*
Y15400D01*
X1043650Y15633D01*
G01X1056200Y10100D02*
X1055100Y9000D01*
X1051000D01*
X1048792Y11208D01*
X1048736D01*
G01X1069131Y7363D02*
Y9601D01*
X1064361Y14371D01*
Y27272D01*
X1059912Y31721D01*
Y42669D01*
X1060138Y42895D01*
Y46812D01*
X1058250Y48700D01*
G01X1054750Y22200D02*
Y24330D01*
X1056650Y26230D01*
Y28600D01*
G01X1068809Y16792D02*
X1068759D01*
X1066672Y18879D01*
Y22344D01*
X1068673Y24345D01*
Y24395D01*
G01D02*
Y27768D01*
X1067495Y28946D01*
X1065657D01*
G01X1056650Y36200D02*
Y38000D01*
X1058150Y39500D01*
Y44400D01*
G01X1048669Y68898D02*
Y72369D01*
X1051850Y75550D01*
G01X1068354Y68898D02*
Y75047D01*
X1057431Y85970D01*
Y89182D01*
G01X1049350Y64100D02*
X1045400D01*
X1045000Y64500D01*
G01X1042669Y68898D02*
Y66831D01*
X1045000Y64500D01*
G01X1062354Y68898D02*
Y71646D01*
X1060000Y74000D01*
G01X1058110Y69355D02*
Y72110D01*
X1060000Y74000D01*
G01X1070733Y41173D02*
X1073766D01*
X1078721Y46128D01*
X1087592D01*
X1088005Y46541D01*
G01X1070733Y41173D02*
X1069403D01*
X1065933Y44643D01*
Y48832D01*
G01X1047500Y41500D02*
X1042900Y46100D01*
X1042600D01*
G01X1051000Y41500D02*
Y43500D01*
X1049500Y45000D01*
G01X1050216Y50022D02*
Y49234D01*
X1052975Y46475D01*
X1056075D01*
X1058150Y44400D01*
G01X1050216Y50022D02*
X1053428D01*
X1054750Y48700D01*
G01X1051850Y75550D02*
X1054627Y78327D01*
Y89543D01*
X1063688Y98604D01*
Y130119D01*
X1121500Y187931D01*
Y221250D01*
G01X1136000D02*
Y200415D01*
X1065500Y129915D01*
Y97251D01*
X1057431Y89182D01*
G01X1088039Y68898D02*
X1067500Y89437D01*
Y128750D01*
X1071330Y132580D01*
G01X1050500Y105250D02*
Y106100D01*
X1048100Y108500D01*
G01X1046000Y105250D02*
Y107200D01*
X1044700Y108500D01*
G01X1150500Y221250D02*
Y211750D01*
X1071330Y132580D01*
G01X1297400Y651300D02*
X1294905Y648805D01*
Y635224D01*
X1323075Y607054D01*
Y342899D01*
X1303064Y322888D01*
X1134453D01*
X1047595Y236030D01*
Y109005D01*
X1048100Y108500D01*
G01X1290550Y651300D02*
X1292930Y648917D01*
Y634405D01*
X1321100Y606235D01*
Y343718D01*
X1302245Y324863D01*
X1133634D01*
X1045620Y236849D01*
Y109420D01*
X1044700Y108500D01*
G01X1097000Y1500D02*
X1097500D01*
X1104626Y8626D01*
X1180626D01*
X1208673Y36673D01*
Y54869D01*
X1214804Y61000D01*
X1236400D01*
X1239600Y64200D01*
Y68900D01*
X1232900Y75600D01*
X1219732D01*
X1216080Y79252D01*
G01X1090750Y5000D02*
Y500D01*
G01X1090929Y9074D02*
X1090750Y8895D01*
Y5000D01*
G01X1087250D02*
Y6950D01*
X1084800Y9400D01*
G01X1079309Y5500D02*
X1079809Y5000D01*
X1083235D01*
G01D02*
X1087250D01*
G01Y500D02*
X1084000D01*
G01D02*
X1079309D01*
G01X1090754Y40883D02*
Y36383D01*
G01X1090370Y27440D02*
Y22940D01*
G01X1172773Y79252D02*
X1177325Y74700D01*
X1190900D01*
X1195800Y69800D01*
Y61309D01*
X1193991Y59500D01*
X1161700D01*
X1157200Y55000D01*
Y27400D01*
X1151000Y21200D01*
X1110454D01*
X1104214Y27440D01*
X1090370D01*
G01X1129466Y64292D02*
X1112272D01*
X1102980Y55000D01*
Y50096D01*
X1096053Y43169D01*
X1082879D01*
X1081192Y41482D01*
X1078302D01*
X1076374Y39554D01*
G01X1172773Y64292D02*
X1164476D01*
X1155775Y55591D01*
Y27991D01*
X1150409Y22625D01*
X1114000D01*
X1104425Y32200D01*
X1087039D01*
X1086613Y31774D01*
G01X1216080Y64292D02*
X1207248Y55460D01*
Y37264D01*
X1180035Y10051D01*
X1096087D01*
X1095923Y9887D01*
X1093363D01*
X1092550Y9074D01*
X1090929D01*
G01X1087254Y36383D02*
X1083586D01*
X1083315Y36654D01*
G01X1079874Y35054D02*
X1081715D01*
X1083315Y36654D01*
G01X1169820Y84764D02*
Y72920D01*
X1154350Y57450D01*
Y28582D01*
X1149818Y24050D01*
X1114591D01*
X1104629Y34012D01*
X1084528D01*
X1082808Y32292D01*
Y30601D01*
G01X1086870Y27440D02*
X1084295D01*
X1084193Y27338D01*
X1079707D01*
X1079319Y26950D01*
G01X1092094Y30362D02*
X1089792D01*
X1086870Y27440D01*
G01X1213128Y84764D02*
Y77628D01*
X1208500Y73000D01*
Y59700D01*
X1205823Y57023D01*
Y37855D01*
X1180354Y12386D01*
X1096406D01*
X1095496Y11476D01*
X1082876D01*
X1080900Y9500D01*
X1080672D01*
G01X1079874Y39554D02*
X1082044D01*
X1083379Y40889D01*
G01X1079319Y22450D02*
X1080450D01*
X1083500Y25500D01*
G01X1086870Y22940D02*
X1086060D01*
X1083500Y25500D01*
G01X1078589Y14070D02*
Y17629D01*
X1079226Y18266D01*
G01D02*
X1079485Y18525D01*
X1086677D01*
G01X1086475Y14177D02*
X1083264D01*
X1082974Y14467D01*
G01X1090754Y40883D02*
X1097056D01*
X1105441Y49268D01*
Y54768D01*
G01X1078694Y43478D02*
X1080655D01*
X1081880Y44703D01*
X1093449D01*
X1100992Y52246D01*
Y52374D01*
G01X1087254Y40883D02*
X1083385D01*
X1083379Y40889D01*
G01X1077750Y68500D02*
Y72250D01*
X1078000Y72500D01*
G01X1082039Y68898D02*
X1078437Y72500D01*
X1078000D01*
G01X1120250Y235000D02*
Y238976D01*
X1120205Y239021D01*
G01X1143000Y242000D02*
X1123184D01*
X1120205Y239021D01*
G01X1123750Y235000D02*
X1127000D01*
X1127500Y234500D01*
G01X1125375Y228750D02*
X1127500Y230875D01*
Y234500D01*
G01X1134250D02*
Y238454D01*
X1134187Y238517D01*
G01D02*
X1134394Y238724D01*
X1143724D01*
X1147000Y242000D01*
G01X1137750Y234500D02*
X1141000D01*
X1141500Y234000D01*
G01X1139875Y228750D02*
X1141500Y230375D01*
Y234000D01*
G01X1300000Y637000D02*
X1324500Y612500D01*
Y342308D01*
X1302992Y320800D01*
X1186767D01*
X1162660Y296693D01*
Y191307D01*
X1183332Y170635D01*
X1286385D01*
X1290978Y175228D01*
G01X1148750Y234500D02*
X1151000Y236750D01*
Y242000D01*
G01D02*
X1155000D01*
G01X1152250Y234500D02*
X1156000D01*
G01D02*
X1154375Y232875D01*
Y228750D01*
G01X1172500Y742500D02*
Y811400D01*
X1169700Y814200D01*
G01X1167323Y887970D02*
Y881877D01*
X1169150Y880050D01*
Y824150D01*
X1166800Y821800D01*
Y797750D01*
X1169000Y795550D01*
Y750500D01*
G01X1164174Y887970D02*
Y882449D01*
X1167586Y879037D01*
Y824602D01*
X1165375Y822391D01*
Y757000D01*
G01X1169700Y814200D02*
X1170575Y815075D01*
Y880641D01*
X1170473Y880743D01*
Y887970D01*
G01X1201969D02*
Y882669D01*
X1198556Y879256D01*
Y873160D01*
X1205525Y866191D01*
Y850159D01*
X1202675Y847309D01*
Y666475D01*
X1210000Y659150D01*
X1328150D01*
X1331000Y662000D01*
G01X1249679Y133345D02*
Y137718D01*
X1246218Y141179D01*
G01X1248234Y145217D02*
Y143195D01*
X1246218Y141179D01*
G01X1253719Y133345D02*
Y139037D01*
X1254956Y140274D01*
Y142088D01*
X1252173Y144871D01*
X1251801D01*
G01X1307000Y282250D02*
X1290050D01*
X1255000Y317300D01*
G01X1274500Y342250D02*
X1272500Y344250D01*
Y350000D01*
G01X1278500Y342250D02*
X1275060Y345690D01*
G01X1258500Y342250D02*
X1262500D01*
G01D02*
X1262600Y342350D01*
Y346000D01*
G01X1269940D02*
Y342810D01*
X1270500Y342250D01*
G01D02*
X1266500D01*
G01X1272500Y350000D02*
Y355300D01*
G01X1275060Y345690D02*
Y355300D01*
G01X1277620Y349500D02*
Y355300D01*
G01X1282500Y342250D02*
X1277620Y347130D01*
Y349500D01*
G01X1275060Y377500D02*
Y381840D01*
X1273400Y383500D01*
G01X1272500Y377500D02*
Y380600D01*
X1268400Y384700D01*
Y386100D01*
G01X1267380Y355300D02*
Y348380D01*
X1265000Y346000D01*
X1262600D01*
G01X1269940D02*
Y355300D01*
G01X1264820D02*
Y349320D01*
G01X1265500Y390250D02*
X1265000Y389750D01*
X1265001Y389749D01*
Y385764D01*
X1269940Y380825D01*
Y377500D01*
G01X1267380D02*
Y380591D01*
X1263026Y384945D01*
Y386499D01*
X1263025Y386500D01*
G01X1278000Y385500D02*
X1277620Y385120D01*
Y377500D01*
G01X1273500Y400500D02*
X1276250Y397750D01*
X1277500D01*
G01D02*
Y393750D01*
G01Y390250D02*
X1273400Y386150D01*
Y383500D01*
G01X1268400Y386100D02*
Y389150D01*
X1269500Y390250D01*
G01D02*
X1273500D01*
G01X1265500D02*
Y390457D01*
X1267338Y392295D01*
Y395105D01*
X1267312Y395131D01*
Y396701D01*
X1266513Y397500D01*
G01X1263025Y386500D02*
X1263024Y386501D01*
Y388726D01*
X1261500Y390250D01*
G01X1263025Y386500D02*
X1261600D01*
G01X1319875Y135104D02*
X1318030Y133259D01*
Y126090D01*
X1316352Y124412D01*
X1314992D01*
X1307613Y117033D01*
Y53113D01*
X1296606Y42106D01*
Y31496D01*
G01X1316049Y120821D02*
X1314064Y120825D01*
X1309038Y115820D01*
Y52522D01*
X1308000Y51484D01*
Y32000D01*
X1296606Y20606D01*
Y7874D01*
G01X1302606Y31496D02*
X1304000Y32890D01*
Y36250D01*
G01X1302606Y7874D02*
X1304000Y9268D01*
Y12750D01*
G01X1314930Y126650D02*
X1306188Y117908D01*
Y74188D01*
X1296606Y64606D01*
Y55118D01*
G01X1302606D02*
X1304000Y56512D01*
Y59750D01*
G01X1296606Y78740D02*
X1296310Y79036D01*
Y92955D01*
X1299933Y96578D01*
Y124200D01*
X1299720Y124413D01*
Y126545D01*
X1299933Y126758D01*
Y129548D01*
G01X1302606Y78740D02*
Y80506D01*
X1304000Y81900D01*
Y83250D01*
G01X1299933Y129548D02*
X1301543Y131158D01*
Y152335D01*
G01X1306970Y139185D02*
X1305712Y140443D01*
Y141101D01*
X1305710Y141103D01*
Y144320D01*
G01X1311262Y175228D02*
X1309695Y176795D01*
X1292545D01*
X1290978Y175228D01*
G01X1305418Y159835D02*
Y156557D01*
X1310776Y151199D01*
G01X1310060Y145310D02*
X1306700D01*
X1305710Y144320D01*
G01X1289250Y300000D02*
Y303650D01*
X1288900Y304000D01*
G01X1307000Y278750D02*
X1311000D01*
G01D02*
X1315000D01*
G01X1298300Y300700D02*
Y303400D01*
X1296518Y305182D01*
X1295600D01*
G01D02*
X1294282D01*
X1292750Y303650D01*
Y300000D01*
G01D02*
Y295000D01*
G01X1307100Y296700D02*
Y305600D01*
X1308362Y306862D01*
X1319751D01*
X1321400Y305213D01*
Y301650D01*
G01X1286500Y342250D02*
X1282170Y346580D01*
X1281900D01*
G01X1290500Y342250D02*
X1288275Y344475D01*
Y344605D01*
X1285760Y347120D01*
G01X1294500Y342250D02*
Y344550D01*
X1293280Y345770D01*
G01X1298500Y342250D02*
Y344500D01*
X1294000Y349000D01*
X1290860D01*
X1289960Y349900D01*
G01X1299000Y347500D02*
X1302500Y344000D01*
Y342250D01*
G01X1281900Y346580D02*
Y346850D01*
X1280180Y348570D01*
Y355300D01*
G01X1282740Y350010D02*
Y355300D01*
G01X1285760Y347120D02*
X1282870Y350010D01*
X1282740D01*
G01X1293280Y345770D02*
X1290730D01*
X1285300Y351200D01*
Y355300D01*
G01X1289960Y349900D02*
X1287860Y352000D01*
Y355300D01*
G01X1299000Y347500D02*
X1296000Y350500D01*
X1293000D01*
X1290420Y353080D01*
Y355300D01*
G01X1292980Y377500D02*
Y379980D01*
X1295375Y382375D01*
X1297625D01*
G01X1290420Y377500D02*
Y380571D01*
X1296349Y386500D01*
X1296500D01*
G01X1287860Y377500D02*
Y380610D01*
X1290125Y382875D01*
G01X1285300Y377500D02*
Y382300D01*
X1289500Y386500D01*
G01X1282740Y383000D02*
Y377500D01*
G01X1280180D02*
Y384680D01*
X1282000Y386500D01*
G01X1305500Y390250D02*
X1297625Y382375D01*
G01X1301500Y390250D02*
X1297750Y386500D01*
X1296500D01*
G01X1297500Y390250D02*
X1290125Y382875D01*
G01X1293500Y390250D02*
X1289750Y386500D01*
X1289500D01*
G01Y390250D02*
X1282740Y383490D01*
Y383000D01*
G01X1285500Y390250D02*
Y390000D01*
X1282000Y386500D01*
G01X1302128Y680617D02*
Y685500D01*
G01X1306128Y680617D02*
Y685628D01*
X1307000Y686500D01*
G01X1286800Y671100D02*
X1297325Y660575D01*
X1325975D01*
X1327200Y661800D01*
G01X1322128Y677117D02*
Y676928D01*
X1319953Y674753D01*
Y663453D01*
X1318500Y662000D01*
X1299500D01*
X1297500Y664000D01*
G01X1312132Y684293D02*
X1310128Y682289D01*
Y680617D01*
G01D02*
X1310209D01*
X1311966Y678860D01*
Y674035D01*
X1311017Y673086D01*
G01X1310128Y677117D02*
X1310078D01*
X1308506Y675545D01*
Y665701D01*
X1310207Y664000D01*
G01X1310668Y714967D02*
Y718705D01*
X1309741Y719632D01*
X1308861D01*
X1308206Y720287D01*
Y720816D01*
X1306623Y722399D01*
G01X1301625Y722567D02*
X1302592Y721600D01*
X1304099D01*
X1308108Y717591D01*
Y714967D01*
G01X1305548Y692767D02*
Y693452D01*
X1303500Y695500D01*
X1302000D01*
G01X1308108Y692767D02*
Y690207D01*
X1303401Y685500D01*
X1302128D01*
G01X1310668Y692767D02*
Y690168D01*
X1307000Y686500D01*
G01X1313228Y692767D02*
Y687357D01*
X1312132Y686261D01*
Y684293D01*
G01X1306128Y726117D02*
Y722872D01*
X1306600Y722400D01*
Y722399D01*
X1306623D01*
G01X1301625Y722567D02*
X1302128Y723070D01*
Y726117D01*
G01X1310200Y726150D02*
Y723300D01*
X1310500Y723000D01*
G01X1313228Y714967D02*
Y720272D01*
X1310500Y723000D01*
G01X1306128Y729617D02*
Y732872D01*
G01X1302128Y729617D02*
Y732872D01*
G01X1296457Y887970D02*
Y882682D01*
X1296989Y882150D01*
Y876080D01*
X1297525Y875544D01*
Y873527D01*
X1297531Y873521D01*
Y870817D01*
X1297525Y870811D01*
Y829625D01*
X1296562Y828662D01*
Y781823D01*
X1339910Y738475D01*
X1340640D01*
X1350338Y728777D01*
Y706500D01*
X1348669Y704831D01*
G01X1302756Y887970D02*
Y881655D01*
X1299962Y878861D01*
Y877339D01*
X1300483Y876818D01*
Y829485D01*
X1300500Y829401D01*
X1307038Y822862D01*
Y803738D01*
X1302562Y799262D01*
Y780438D01*
X1340500Y742500D01*
G01X1293308Y887970D02*
Y881900D01*
X1295564Y879644D01*
Y875490D01*
X1296100Y874953D01*
Y872936D01*
X1296106Y872930D01*
Y871408D01*
X1296100Y871402D01*
Y830216D01*
X1295137Y829253D01*
Y781232D01*
X1339320Y737049D01*
X1340050D01*
X1347200Y729899D01*
Y714299D01*
X1346662Y713761D01*
Y712239D01*
X1347200Y711701D01*
Y706527D01*
X1346431Y705758D01*
Y703904D01*
X1348038Y702297D01*
Y675843D01*
X1346757Y674562D01*
X1340562D01*
X1340000Y674000D01*
G01X1351500Y675000D02*
Y681468D01*
X1354850Y684818D01*
Y726281D01*
X1340631Y740500D01*
X1339901D01*
X1298800Y781601D01*
Y818400D01*
G01D02*
X1298950Y818550D01*
Y870220D01*
X1298956Y870226D01*
Y874112D01*
X1298950Y874118D01*
Y876135D01*
X1298500Y876585D01*
Y880015D01*
X1299607Y881122D01*
Y887970D01*
G01X1314930Y126650D02*
Y134850D01*
X1314470Y135310D01*
G01X1325530Y140759D02*
X1319875Y135104D01*
G01X1316049Y120821D02*
X1317240Y119630D01*
X1322980D01*
X1325220Y121870D01*
G01X1335071Y137861D02*
X1336478Y139268D01*
X1339471D01*
G01X1329095Y129370D02*
Y134725D01*
X1329618Y135248D01*
G01X1335071Y134361D02*
X1333926Y135506D01*
X1329876D01*
X1329618Y135248D01*
G01X1314276Y151199D02*
X1314738D01*
X1316590Y149347D01*
Y147210D01*
G01X1313560Y145310D02*
X1315250Y143620D01*
X1317400D01*
G01X1335100Y141920D02*
X1336070D01*
X1340130Y145980D01*
G01X1329405Y148259D02*
X1332261D01*
X1335100Y145420D01*
G01X1327357Y271124D02*
X1325280D01*
X1323838Y272566D01*
Y275000D01*
X1325161Y276323D01*
Y279162D01*
G01X1327357Y269156D02*
X1325232D01*
X1320888Y273500D01*
X1319750D01*
X1318750Y274500D01*
G01D02*
Y274750D01*
X1320500Y276500D01*
X1322000D01*
G01X1325161Y279162D02*
X1324564Y279759D01*
X1320910D01*
X1319851Y278700D01*
X1319050D01*
X1319000Y278750D01*
G01X1315000D02*
X1319000D01*
G01X1314128Y680617D02*
Y685628D01*
X1315000Y686500D01*
G01X1314128Y677117D02*
X1313607Y676596D01*
Y664000D01*
G01X1330128Y680617D02*
Y684039D01*
X1329500Y684667D01*
G01X1330128Y677117D02*
Y675342D01*
X1333308Y672162D01*
X1340761D01*
X1341736Y673137D01*
X1347348D01*
X1349463Y675252D01*
Y702888D01*
X1348625Y703726D01*
Y704787D01*
X1348669Y704831D01*
G01X1322128Y680617D02*
Y683598D01*
X1321928Y683798D01*
G01X1322400Y673050D02*
X1324100Y674750D01*
Y678700D01*
X1322183Y680617D01*
X1322128D01*
G01Y677117D02*
X1320290Y678955D01*
Y682877D01*
X1318500Y684667D01*
G01X1338128Y680617D02*
Y682026D01*
X1339934Y683832D01*
G01X1342300Y680250D02*
X1341933Y680617D01*
X1338128D01*
G01Y677117D02*
X1336795Y678450D01*
Y678729D01*
X1336290Y679234D01*
Y681972D01*
X1336703Y682385D01*
Y682617D01*
X1336795Y682709D01*
Y685141D01*
G01X1326758Y686678D02*
Y681247D01*
X1326128Y680617D01*
G01D02*
Y680567D01*
X1327966Y678729D01*
Y673938D01*
X1329496Y672408D01*
X1329579D01*
G01X1326128Y677117D02*
Y674000D01*
G01X1318128Y680617D02*
Y680410D01*
X1316290Y678572D01*
Y675620D01*
X1316216Y675546D01*
Y673308D01*
G01X1318128Y680617D02*
X1316662Y682083D01*
Y685661D01*
X1318348Y687347D01*
Y692767D01*
G01X1318128Y677117D02*
Y675037D01*
X1318528Y674637D01*
Y665521D01*
X1317007Y664000D01*
G01X1334128Y680617D02*
Y684944D01*
X1333052Y686020D01*
G01X1334128Y677117D02*
Y674000D01*
G01X1315788Y714967D02*
Y722212D01*
X1315000Y723000D01*
G01X1319500Y737000D02*
X1322865Y733635D01*
Y727571D01*
X1323468Y726968D01*
Y714967D01*
G01X1319500Y731500D02*
X1321440Y729560D01*
Y726980D01*
X1321675Y726745D01*
Y721475D01*
X1320908Y720708D01*
Y714967D01*
G01X1319500Y726000D02*
X1318348Y724848D01*
Y714967D01*
G01X1331148D02*
Y719648D01*
X1333500Y722000D01*
Y723000D01*
G01X1315788Y692767D02*
Y687288D01*
X1315000Y686500D01*
G01X1326028Y692767D02*
Y690007D01*
X1329500Y686535D01*
Y684667D01*
G01X1326028Y714967D02*
Y722559D01*
X1325600Y722987D01*
G01X1320908Y692767D02*
Y686092D01*
X1321928Y685072D01*
Y683798D01*
G01X1331148Y692767D02*
Y690366D01*
X1331197Y690317D01*
X1331246D01*
X1332563Y689000D01*
X1336401D01*
X1337439Y687962D01*
X1337538D01*
X1339934Y685566D01*
Y683832D01*
G01X1333708Y714967D02*
Y719609D01*
X1337099Y723000D01*
X1337500D01*
G01X1323468Y692767D02*
Y689968D01*
X1326758Y686678D01*
G01X1328588Y714967D02*
Y720588D01*
X1329500Y721500D01*
G01X1328588Y692767D02*
Y689463D01*
X1332031Y686020D01*
X1333052D01*
G01X1314628Y729617D02*
Y733000D01*
G01Y726117D02*
Y723372D01*
X1315000Y723000D01*
G01X1334128Y726117D02*
Y724128D01*
X1333500Y723500D01*
Y723000D01*
G01X1334128Y729617D02*
Y732667D01*
G01X1326128Y726117D02*
Y723515D01*
X1325600Y722987D01*
G01X1326100Y734150D02*
X1324290Y732340D01*
Y728162D01*
X1326128Y726324D01*
Y726117D01*
G01Y729617D02*
Y730428D01*
X1328290Y732590D01*
Y733428D01*
X1329862Y735000D01*
X1339500D01*
X1342000Y732500D01*
G01X1338128Y726117D02*
Y723628D01*
X1337500Y723000D01*
G01X1338128Y729617D02*
Y732872D01*
G01X1330128Y726117D02*
Y722128D01*
X1329500Y721500D01*
G01X1330128Y729617D02*
Y732667D01*
G01X1363168Y168102D02*
X1360004D01*
X1359128Y167226D01*
G01X1372093Y173852D02*
Y173230D01*
X1377095Y168228D01*
X1378998D01*
G01D02*
X1381264D01*
X1387196Y174160D01*
G01X1359011Y178934D02*
Y174983D01*
X1359124Y174870D01*
G01D02*
X1354449D01*
X1353445Y173866D01*
Y168972D01*
X1354971Y167446D01*
G01X1366668Y168102D02*
Y170722D01*
X1364343Y173047D01*
Y173852D01*
G01X1366668Y168102D02*
X1369726D01*
X1371541Y166287D01*
G01X1378134Y176959D02*
X1383023D01*
X1383319Y177255D01*
Y177216D01*
G01X1378134Y176959D02*
X1377457Y177636D01*
X1370679D01*
X1368218Y180097D01*
Y181352D01*
G01X1365804Y185197D02*
X1363041Y182434D01*
X1359011D01*
G01X1360250Y278500D02*
X1362000D01*
X1364000Y280500D01*
G01X1383319Y177216D02*
X1385467Y179364D01*
Y180543D01*
G01X1383319Y177216D02*
X1383340D01*
G54D165*
G01X47912Y294940D02*
X49430D01*
X51406Y296916D01*
X54083D01*
G01X43900Y303450D02*
X46026Y305576D01*
X48267D01*
X49053Y304790D01*
X54083D01*
G01X41300Y307200D02*
Y305270D01*
X43120Y303450D01*
X43900D01*
G01X54083Y298884D02*
X50619D01*
X49480Y297745D01*
X46105D01*
X43900Y299950D01*
G01X47355Y303376D02*
X47910Y302821D01*
X54083D01*
G01X49934Y280811D02*
X49989Y280866D01*
Y283767D01*
X51327Y285105D01*
X54083D01*
G01X54100Y422065D02*
X56435D01*
X57800Y420700D01*
G01X56000Y445300D02*
Y443930D01*
G01X59000Y445300D02*
Y443930D01*
G01X56000Y447700D02*
Y449070D01*
G01X59000Y447700D02*
Y449070D01*
G01X57253Y725150D02*
Y721073D01*
X56590Y720410D01*
G01X59500Y717400D02*
X56600Y720300D01*
Y720400D01*
X56590Y720410D01*
G01X59221Y725150D02*
Y721950D01*
X60571Y720600D01*
X63222D01*
G01X70600Y741600D02*
X66853Y737853D01*
X64050D01*
G01X72300Y265450D02*
Y270500D01*
X75700Y273900D01*
Y274100D01*
G01D02*
X75800D01*
G01X76421Y280483D02*
Y276117D01*
X76332Y276028D01*
Y274732D01*
X75700Y274100D01*
G01X88917Y300853D02*
X91853D01*
X93700Y302700D01*
Y303100D01*
G01X89400Y279300D02*
X88217Y280483D01*
X86264D01*
G01X67600Y327350D02*
Y324600D01*
X67100Y324100D01*
Y319811D01*
X66579Y319290D01*
Y315317D01*
G01X91750Y600560D02*
X97310D01*
X98500Y601750D01*
G01X128180Y314464D02*
X126930Y315714D01*
X123680D01*
G01X128180Y314464D02*
X134596D01*
X136257Y316125D01*
G01X108484Y348377D02*
X105896Y350965D01*
Y356944D01*
G01X159662Y270023D02*
Y266600D01*
G01X155662Y270023D02*
Y266438D01*
G01X159662Y272423D02*
Y275531D01*
G01X155662Y272423D02*
Y275530D01*
G01X149200Y300500D02*
X148502Y301198D01*
G01D02*
Y306553D01*
X148500Y306555D01*
Y309068D01*
X147263Y310305D01*
X143454D01*
X139491Y314268D01*
X138114D01*
X136257Y316125D01*
G01X140047Y380050D02*
Y385047D01*
X143000Y388000D01*
G01X139501Y411131D02*
X137778Y409408D01*
Y401708D01*
G01D02*
X138707Y400779D01*
X144206D01*
X145953Y399032D01*
Y395950D01*
G01X145543Y593622D02*
X145581D01*
X147143Y595184D01*
G01X148693Y593622D02*
Y593634D01*
X147143Y595184D01*
G01X136095Y615669D02*
Y615690D01*
X137671Y617266D01*
G01X249857Y148063D02*
X244063D01*
X243500Y147500D01*
G01X246500Y604400D02*
X247711D01*
G01X246500Y607400D02*
X247711D01*
G01X244100Y604400D02*
X242889D01*
G01X244100Y607400D02*
X242889D01*
G01X297512Y475360D02*
X303440D01*
G01X277826Y757498D02*
X277324Y758000D01*
X270560D01*
X268900Y756340D01*
G01X336141Y327915D02*
X330006D01*
X329241Y328680D01*
G01X336141Y325945D02*
X330006D01*
X329241Y325180D01*
G01X305986Y735298D02*
Y733014D01*
X309331Y729669D01*
X310016D01*
Y729793D01*
G01X348800Y162500D02*
X348211D01*
G01X348800Y173600D02*
X348012D01*
G01X348800Y166200D02*
X348089D01*
G01X348800Y169900D02*
X348248D01*
G01X351200Y162500D02*
X351819D01*
G01X351200Y166200D02*
X351787D01*
G01X351200Y173600D02*
X351572D01*
G01X351200Y169900D02*
X351665D01*
G01X348800Y181000D02*
X348011D01*
G01X348800Y177300D02*
X348164D01*
G01X351200Y181000D02*
X351722D01*
G01X351200Y177300D02*
X351620D01*
G01X479360Y84600D02*
Y89760D01*
X479700Y90100D01*
G01X519486Y787298D02*
Y786014D01*
X522500Y783000D01*
Y782031D01*
G01X575800Y328700D02*
Y327529D01*
G01X578800Y328700D02*
Y327529D01*
G01X575800Y331100D02*
Y332271D01*
G01X578800Y331100D02*
Y332271D01*
G01X590831Y339580D02*
X589567D01*
G01X593231D02*
X594359D01*
G01X599100Y348700D02*
X599015Y348615D01*
X596814D01*
X594214Y351215D01*
Y370513D01*
X598101Y374400D01*
X610000D01*
X615400Y369000D01*
X619200D01*
X621300Y366900D01*
G01X599100Y348700D02*
X601400D01*
X604222Y351522D01*
X606322D01*
G01X637921Y346807D02*
Y344079D01*
X639500Y342500D01*
G01X637921Y366393D02*
Y369421D01*
X639500Y371000D01*
G01X630047Y366393D02*
Y369953D01*
X629500Y370500D01*
Y371000D01*
G01X623207Y351679D02*
X619057D01*
X617205Y349827D01*
X616815D01*
X616706Y349718D01*
G01X623007Y349710D02*
X621610D01*
X618680Y346780D01*
G01X623007Y363490D02*
Y365193D01*
X621300Y366900D01*
G01X642793Y355616D02*
X646884D01*
G01X702400Y254500D02*
X703671D01*
G01X702400Y251500D02*
X703671D01*
G01X702400Y272500D02*
X703671D01*
G01X702400Y269500D02*
X703671D01*
G01X702400Y266500D02*
X703671D01*
G01X702400Y263500D02*
X703671D01*
G01X702400Y260500D02*
X703671D01*
G01X702400Y257500D02*
X703671D01*
G01X700000Y254500D02*
X698745D01*
G01X700000Y251500D02*
X698745D01*
G01X700000Y272500D02*
X698745D01*
G01X700000Y269500D02*
X698745D01*
G01X700000Y266500D02*
X698745D01*
G01X700000Y263500D02*
X698745D01*
G01X700000Y260500D02*
X698745D01*
G01X700000Y257500D02*
X698745D01*
G01X692763Y281008D02*
Y282263D01*
G01X695763Y281008D02*
Y282263D01*
G01X698763Y281008D02*
Y282263D01*
G01X692763Y278608D02*
Y277337D01*
G01X695763Y278608D02*
Y277337D01*
G01X698763Y278608D02*
Y277337D01*
G01X795838Y98060D02*
X798624D01*
X801064Y100500D01*
X804456D01*
X805100Y101144D01*
Y101600D01*
X806300Y102800D01*
X806350D01*
G01X872850Y2500D02*
X867600D01*
G01X889150D02*
X895750D01*
X896000Y2750D01*
G01X899340Y318510D02*
Y322840D01*
X901500Y325000D01*
X907500D01*
G01X891660Y334690D02*
Y329840D01*
X893000Y328500D01*
X902500D01*
X905250Y331250D01*
X905500D01*
G01X888986Y764298D02*
X894202D01*
X895278Y763222D01*
Y758885D01*
G01X1219300Y224900D02*
X1218102D01*
G01X1219300Y227900D02*
X1218102D01*
G01X1219300Y239900D02*
X1218102D01*
G01X1219300Y236900D02*
X1218102D01*
G01X1219300Y233900D02*
X1218102D01*
G01X1219300Y230900D02*
X1218102D01*
G01X1219300Y242900D02*
X1218102D01*
G01X1221700Y224900D02*
X1222898D01*
G01X1221700Y236900D02*
X1222898D01*
G01X1221700Y233900D02*
X1222898D01*
G01X1221700Y230900D02*
X1222898D01*
G01X1221700Y227900D02*
X1222898D01*
G01X1221700Y239900D02*
X1222898D01*
G01X1221700Y242900D02*
X1222898D01*
G01X1219300Y245900D02*
X1218102D01*
G01X1219300Y248900D02*
X1218102D01*
G01X1219300Y251900D02*
X1218102D01*
G01X1219300Y254900D02*
X1218102D01*
G01X1219300Y257900D02*
X1218102D01*
G01X1219300Y269900D02*
X1218102D01*
G01X1219300Y260900D02*
X1218102D01*
G01X1219300Y263900D02*
X1218102D01*
G01X1219300Y266900D02*
X1218102D01*
G01X1221700Y245900D02*
X1222898D01*
G01X1221700Y248900D02*
X1222898D01*
G01X1221700Y251900D02*
X1222898D01*
G01X1221700Y254900D02*
X1222898D01*
G01X1221700Y257900D02*
X1222898D01*
G01X1221700Y260900D02*
X1222898D01*
G01X1221700Y263900D02*
X1222898D01*
G01X1221700Y266900D02*
X1222898D01*
G01X1221700Y269900D02*
X1222898D01*
G01X1292980Y355300D02*
X1295700D01*
X1297500Y353500D01*
Y351800D01*
G01X1305548Y714967D02*
X1302095D01*
X1301728Y714600D01*
G01X1333708Y692767D02*
X1337433D01*
X1338200Y692000D01*
Y689800D01*
G54D36*
X25300Y742600D03*
X58300Y330900D03*
X62800Y330600D03*
X64500Y424200D03*
X32000Y476700D03*
X49000D03*
X53200Y470100D03*
X55261Y510841D03*
X51300Y713100D03*
X43300D03*
X57200Y694000D03*
X80300Y262600D03*
X95670Y344211D03*
X91600Y344100D03*
X70591Y366599D03*
X70654Y374260D03*
X80000Y406900D03*
X84274Y402541D03*
X96046Y426730D03*
X92500Y473200D03*
X96700Y473100D03*
X88000Y610300D03*
X72000Y609700D03*
X76000D03*
X66000Y601700D03*
X97500Y635200D03*
X65000Y766500D03*
X108500Y298100D03*
X128180Y314414D03*
X103998Y344250D03*
X99887Y344275D03*
X103617Y336215D03*
X100200Y388300D03*
X100076Y434130D03*
X111500Y461200D03*
X107500D03*
X106900Y735500D03*
X126000Y780700D03*
X151600Y409700D03*
X133000Y461200D03*
X137000D03*
X142000Y456700D03*
X160000Y778200D03*
X164500Y816200D03*
X196018Y199756D03*
X191018D03*
X197841Y433842D03*
X184116Y462010D03*
X192733Y461532D03*
X188150Y461905D03*
X172800Y461200D03*
X197500Y573732D03*
X191500Y601700D03*
X195500Y594200D03*
Y586700D03*
X199500Y699200D03*
X167200Y723100D03*
X199500Y754700D03*
X171700Y761100D03*
X224900Y112800D03*
X224600Y123500D03*
X207369Y151184D03*
X220969Y438372D03*
X209400Y453500D03*
X213500D03*
X225000Y521800D03*
X229000Y529200D03*
X201500Y573732D03*
X226200Y575862D03*
X204000Y737200D03*
Y792700D03*
X261200Y105300D03*
X235505Y148062D03*
X236331Y233780D03*
X258900Y297000D03*
X263000Y296800D03*
X266729Y349340D03*
X244900Y434300D03*
X262900Y433800D03*
X257500Y450938D03*
X253400Y450900D03*
X242500Y529200D03*
X253500D03*
X258000Y521200D03*
X245300Y639100D03*
X277500Y137200D03*
X272900Y296700D03*
X299639Y336101D03*
X294406Y723098D03*
X290406D03*
X286406D03*
X282406D03*
X298406D03*
X278406Y772098D03*
X274406D03*
X282478Y772131D03*
X316646Y296975D03*
X302700Y297962D03*
X320662Y296990D03*
X315300Y340700D03*
X310406Y723098D03*
X306406D03*
X302406D03*
X314500Y723200D03*
X355200Y332200D03*
X466000Y68900D03*
X457700D03*
X474400D03*
X500238Y133950D03*
X478800Y122700D03*
X477466Y186220D03*
X471681Y309912D03*
X476200Y363000D03*
X480700Y401000D03*
X499906Y775098D03*
X495906D03*
X491906Y824098D03*
X487906D03*
X495978Y824131D03*
X504248Y133950D03*
X528709Y294883D03*
X523906Y775098D03*
X507906D03*
X519906D03*
X503906D03*
X515906D03*
X511906D03*
X528100Y775000D03*
X558263Y136920D03*
X570100Y205700D03*
X541681Y294476D03*
X563531Y376780D03*
X558531Y384280D03*
X631363Y231808D03*
X623363D03*
X608090Y334060D03*
X632000Y337300D03*
X636000D03*
X617000Y379300D03*
X623000D03*
X640000Y337300D03*
X718302Y6724D03*
X736500Y27700D03*
X713375Y27902D03*
X724820Y18440D03*
X720700Y18370D03*
X728960Y18530D03*
X720840Y59840D03*
X742700Y15000D03*
X769400Y107600D03*
X838252Y17700D03*
X834252D03*
X830252D03*
X826252D03*
X822252D03*
X854400D03*
X846252D03*
X842252D03*
X873406Y752024D03*
X869406Y752098D03*
X865406D03*
X861406Y801098D03*
X857406D03*
X865478Y801131D03*
X891301Y16577D03*
X877406Y752098D03*
X893406D03*
X889406D03*
X885406D03*
X881406D03*
X897600Y752000D03*
X938000Y26700D03*
X911000Y93200D03*
X915500D03*
X920000D03*
X933500D03*
X929000D03*
X924500D03*
X938000D03*
X956000D03*
X1005176Y44962D03*
X1000683Y49150D03*
X1010676Y44962D03*
X1068809Y16742D03*
X1249679Y133295D03*
X1253719D03*
X1274500Y342200D03*
X1278500D03*
X1265500Y393700D03*
X1269500D03*
X1273500D03*
X1261500D03*
X1304000Y16200D03*
Y39700D03*
Y63200D03*
Y86700D03*
X1311000Y282200D03*
X1282500Y342200D03*
X1286500D03*
X1290500D03*
X1294500D03*
X1302500D03*
X1298500D03*
X1310128Y680567D03*
X1306128Y729567D03*
X1302128D03*
X1310200Y729600D03*
X1335100Y145370D03*
X1338128Y680567D03*
X1322128D03*
X1334128D03*
X1318128D03*
X1330128D03*
X1314128D03*
X1326128D03*
X1342300Y680200D03*
X1322400Y673000D03*
X1359124Y174820D03*
X1378134Y176909D03*
X1359011Y182384D03*
G54D63*
X88276Y248031D03*
G54D138*
X603363Y223858D03*
G54D72*
X84800Y590300D03*
X121700Y173000D03*
X107500Y203300D03*
X121700Y185000D03*
Y181000D03*
Y177000D03*
Y189000D03*
X104058Y427004D03*
X104062Y430420D03*
X134100Y264300D03*
X141637Y407034D03*
X180800Y289472D03*
X199700Y580500D03*
X209700Y517500D03*
X261429Y338640D03*
X252188Y577665D03*
X241500Y643400D03*
X263500Y647400D03*
X277700Y130000D03*
X287500Y465000D03*
X329658Y292248D03*
X455892Y114254D03*
X558231Y338980D03*
X619563Y221608D03*
X738800Y20300D03*
X713200Y81500D03*
Y78000D03*
Y96500D03*
Y93000D03*
Y105500D03*
Y102000D03*
Y85000D03*
Y88500D03*
Y117500D03*
Y114000D03*
X757400Y109300D03*
Y112800D03*
X802800Y106300D03*
Y102800D03*
X835186Y161691D03*
Y158240D03*
X927200Y27270D03*
X1054600Y44400D03*
X1317200Y290000D03*
G54D156*
X1041108Y1702D03*
X1031265D03*
X1050951D03*
G54D90*
X121480Y827000D03*
X135320D03*
G54D45*
X54083Y308727D03*
Y306758D03*
Y304790D03*
Y302821D03*
Y300853D03*
Y298884D03*
Y296916D03*
Y294947D03*
Y292979D03*
Y291010D03*
Y289042D03*
Y287073D03*
Y285105D03*
Y310695D03*
X88917Y285105D03*
Y287073D03*
Y289042D03*
Y291010D03*
Y292979D03*
Y294947D03*
Y296916D03*
Y298884D03*
Y300853D03*
Y302821D03*
Y304790D03*
Y306758D03*
Y308727D03*
Y310695D03*
G54D147*
X764698Y0D03*
X775460D03*
G54D54*
X59000Y445300D03*
X56000D03*
X59000Y447700D03*
X56000D03*
X159662Y272423D03*
Y270023D03*
X155662Y272423D03*
Y270023D03*
X578800Y328700D03*
Y331100D03*
X575800Y328700D03*
Y331100D03*
X698763Y278608D03*
Y281008D03*
X692763Y278608D03*
Y281008D03*
X695763Y278608D03*
Y281008D03*
G54D18*
X27300Y223000D03*
X37700Y693300D03*
X76450Y704950D03*
X114364Y132099D03*
X108224Y164187D03*
X123680Y315514D03*
X132400Y727600D03*
X111400D03*
X181838Y132011D03*
X548531Y368380D03*
X580178Y238769D03*
X994597Y58669D03*
G54D129*
X514309Y-315D03*
Y52087D03*
X530057Y106457D03*
X557616Y-315D03*
Y52087D03*
X547773Y106457D03*
X600923Y-315D03*
Y52087D03*
X591080Y106457D03*
X573364D03*
X634388D03*
X616671D03*
X644230Y-315D03*
Y52087D03*
X659978Y106457D03*
X687537Y-315D03*
Y52087D03*
X677695Y106457D03*
X1116671Y-315D03*
Y52087D03*
X1132419Y106457D03*
X1159978Y-315D03*
Y52087D03*
X1175726Y106457D03*
X1150135D03*
X1203285Y-315D03*
Y52087D03*
X1193442Y106457D03*
X1246592Y-315D03*
Y52087D03*
X1236750Y106457D03*
X1219033D03*
X1280057D03*
X1262340D03*
X1289899Y-315D03*
Y52087D03*
G54D81*
G01X130051Y648396D02*
X132088D01*
X132128Y648436D01*
X133801D01*
G01X124051Y647136D02*
X125311Y648396D01*
X130051D01*
G01X133801Y648436D02*
Y643936D01*
X113300Y276600D03*
X131700Y275700D03*
X113000Y280500D03*
X113100Y284100D03*
X125100Y282500D03*
X131700Y280000D03*
X294000Y716000D03*
X300500Y715613D03*
X528100Y767300D03*
G54D27*
X25000Y429700D03*
X47800Y763600D03*
X64900Y771100D03*
X68100Y259500D03*
X65965Y367608D03*
X69800Y763100D03*
X111400Y732500D03*
X132400D03*
X171094Y238161D03*
X290200Y706500D03*
X520909Y323741D03*
X612830Y335850D03*
X1028500Y65200D03*
X1357000Y265700D03*
G54D166*
G01X48400Y272750D02*
Y275300D01*
X49934Y276834D01*
Y280811D01*
G01X58850Y713000D02*
X62000D01*
G01X67600Y330850D02*
Y333300D01*
X66400Y334500D01*
G01X95223Y392454D02*
Y399040D01*
X95148Y399115D01*
G01X128258Y582042D02*
X126542D01*
X124100Y579600D01*
Y573749D01*
X120751Y570400D01*
X113800D01*
X110500Y573700D01*
Y590100D01*
X107600Y593000D01*
Y609687D01*
X105851Y611436D01*
G01X128258Y582042D02*
X131830Y578470D01*
X133299D01*
G01X126869Y577770D02*
X126899Y577800D01*
X128700D01*
X131530Y574970D01*
X133299D01*
G01X128258Y582042D02*
Y583511D01*
G01X124150Y714300D02*
Y710800D01*
G01Y714300D02*
X125250Y715400D01*
Y716018D01*
X125740Y716508D01*
Y721650D01*
G01X118060Y737950D02*
Y743460D01*
G01X143319Y640420D02*
Y636620D01*
G01X143301Y643936D02*
Y640438D01*
X143319Y640420D01*
G01X143301Y648436D02*
Y643936D01*
G01X137301D02*
X138801D01*
X143301Y648436D01*
G01X137301D02*
Y643936D01*
G01X136651Y653036D02*
X137301Y652386D01*
Y648436D01*
G01X153700Y736150D02*
X150200D01*
G01X153700D02*
X154800Y735050D01*
X155418D01*
X155908Y734560D01*
X161050D01*
G01X146500Y791250D02*
X143000D01*
G01X146500D02*
X147600Y790150D01*
X148218D01*
X148708Y789660D01*
X153850D01*
G01X186000Y712250D02*
X182500D01*
G01X186000D02*
X187100Y711150D01*
X187718D01*
X188208Y710660D01*
X193350D01*
G01X177350Y742240D02*
X182860D01*
G01X186000Y767750D02*
X182500D01*
G01X186000D02*
X187100Y766650D01*
X187718D01*
X188208Y766160D01*
X193350D01*
G01X170150Y797340D02*
X175660D01*
G01X213350Y494400D02*
X219100D01*
X219800Y493700D01*
G01X209650Y718340D02*
X215160D01*
G01X209650Y773840D02*
X215160D01*
G01X266231Y283559D02*
Y292181D01*
X267300Y293250D01*
G01X291050Y465000D02*
Y467562D01*
X291012Y467600D01*
Y470240D01*
G01X291002Y490150D02*
Y497202D01*
X291500Y497700D01*
G01X301500Y483550D02*
X298400D01*
X298300Y483650D01*
X296122D01*
G01X462700Y376050D02*
X459200D01*
G01X462700D02*
X463800Y374950D01*
X464418D01*
X464908Y374460D01*
X470050D01*
G01X486350Y382140D02*
X491860D01*
G54D73*
X88400Y590300D03*
X125300Y173000D03*
X111100Y203300D03*
X125300Y185000D03*
Y181000D03*
Y177000D03*
Y189000D03*
X107658Y427004D03*
X107662Y430420D03*
X137700Y264300D03*
X145237Y407034D03*
X184400Y289472D03*
X213300Y517500D03*
X203300Y580500D03*
X265029Y338640D03*
X255788Y577665D03*
X245100Y643400D03*
X267100Y647400D03*
X281300Y130000D03*
X291100Y465000D03*
X333258Y292248D03*
X459492Y114254D03*
X561831Y338980D03*
X623163Y221608D03*
X716800Y81500D03*
Y78000D03*
Y96500D03*
Y93000D03*
Y105500D03*
Y102000D03*
Y85000D03*
Y88500D03*
Y117500D03*
Y114000D03*
X742400Y20300D03*
X761000Y109300D03*
Y112800D03*
X806400Y106300D03*
Y102800D03*
X838786Y161691D03*
Y158240D03*
X930800Y27270D03*
X1058200Y44400D03*
X1320800Y290000D03*
G54D28*
X25000Y435300D03*
X47800Y769200D03*
X64900Y776700D03*
X68100Y265100D03*
X65965Y373208D03*
X69800Y768700D03*
X111400Y738100D03*
X132400D03*
X171094Y243761D03*
X290200Y712100D03*
X520909Y329341D03*
X612830Y341450D03*
X1028500Y70800D03*
X1357000Y271300D03*
G54D148*
X785950Y259820D03*
G54D157*
X1024330Y26232D03*
X1028330Y35032D03*
X1020330D03*
G54D64*
X95047Y238996D03*
X97016Y257066D03*
X114733Y238996D03*
X110796D03*
X106859D03*
X102921D03*
X98984D03*
X112764Y257066D03*
X108827D03*
X104890D03*
X100953D03*
G54D37*
X39370Y801181D03*
X293110Y55906D03*
X336417Y90551D03*
X789850Y283464D03*
X1333661Y55906D03*
X1360630Y135826D03*
Y801181D03*
X1376968Y90551D03*
G54D91*
X115355Y887120D03*
X285433D03*
X532678D03*
X702756D03*
X1028741D03*
X1198819D03*
G54D139*
X597522Y356988D03*
Y366212D03*
X603478D03*
Y356988D03*
G54D46*
X53583Y283136D03*
Y312664D03*
X54100Y427970D03*
Y426000D03*
Y424030D03*
Y422065D03*
X41900D03*
Y424030D03*
Y426000D03*
Y427970D03*
X54100Y429935D03*
X41900D03*
X89417Y283136D03*
Y312664D03*
X253200Y633930D03*
Y635900D03*
Y637870D03*
Y639835D03*
X265400D03*
Y637870D03*
Y635900D03*
Y633930D03*
X253200Y631965D03*
X265400D03*
G54D55*
X37940Y478700D03*
X40500D03*
X43060D03*
X37940Y471300D03*
X40500D03*
X43060D03*
X58060Y488800D03*
X55500D03*
X52940D03*
X58060Y496200D03*
X55500D03*
X52940D03*
X266540Y472600D03*
Y480000D03*
X271660Y472600D03*
X269100D03*
X271660Y480000D03*
X269100D03*
G54D82*
X128850Y287500D03*
X125100D03*
X121350D03*
Y298100D03*
X125100D03*
X128850D03*
X153130Y170531D03*
X149380D03*
X145630D03*
Y181131D03*
X149380D03*
X153130D03*
G54D19*
X27300Y217400D03*
X37700Y687700D03*
X76450Y699350D03*
X114364Y126499D03*
X108224Y158587D03*
X123680Y309914D03*
X132400Y722000D03*
X111400D03*
X181838Y126411D03*
X548531Y362780D03*
X580178Y233169D03*
X994597Y53069D03*
G54D167*
G01X120098Y499547D02*
G03X117404Y500922I-3469J-3469D01*
G03X116629Y500984I-777J-4844D01*
G01X113742D01*
G03X111633Y500235I-1J-3342D01*
G03X111554Y500162I536J-659D01*
G01X106780Y495388D01*
G02X105016Y494657I-1764J1763D01*
G01X101039D01*
G02X100054Y495055I0J1418D01*
G03X98569Y495607I-1484J-1720D01*
G01X97560D01*
X96860Y496307D01*
G01X116948Y499547D02*
X116944Y499551D01*
G03X116638Y499805I-1527J-1528D01*
G03X115416Y500184I-1222J-1781D01*
G01X113742D01*
G03X112138Y499614I0J-2542D01*
G01X107346Y494822D01*
G02X105016Y493857I-2329J2329D01*
G01X103816D01*
X103416Y493457D01*
X102216D01*
X101816Y493857D01*
X101039D01*
G02X99517Y494460I-2J2218D01*
G03X98570Y494807I-949J-1124D01*
G01X97560D01*
X96860Y494107D01*
G01X871300Y175792D02*
X871500Y175592D01*
X889408D01*
X890600Y174400D01*
Y172291D01*
X891200Y171691D01*
X893594D01*
X893994Y172091D01*
Y172833D01*
X893599Y173228D01*
X892126D01*
G01X871300Y174592D02*
X871500Y174792D01*
X889076D01*
X889800Y174068D01*
Y171959D01*
X890868Y170891D01*
X893926D01*
X894794Y171759D01*
Y172827D01*
X895195Y173228D01*
X896063D01*
G01X871048Y169584D02*
X871118Y169654D01*
X871400D01*
X873346Y171600D01*
X880965D01*
G03X881883Y172518I0J918D01*
G01Y172519D01*
G03X881174Y173228I-709J0D01*
G01X880315D01*
G01X871897Y168735D02*
X871967Y168805D01*
Y169089D01*
X873678Y170800D01*
X880965D01*
G03X882683Y172518I0J1718D01*
G01Y172519D01*
G02X883392Y173228I709J0D01*
G01X884252D01*
G54D29*
X25200Y424000D03*
X28500Y720400D03*
X31548Y310872D03*
X31612Y306674D03*
X45000Y321400D03*
X32700Y429000D03*
X40200Y466000D03*
X60800Y470100D03*
Y474200D03*
X40700Y484500D03*
X34000Y533500D03*
X58800Y713000D03*
X79691Y365075D03*
X79505Y360727D03*
X89100Y360000D03*
X84390Y392665D03*
X97049Y477241D03*
X82969Y513090D03*
X83844Y508831D03*
X95700Y506000D03*
X83844Y504831D03*
X66969Y502220D03*
X95700Y526500D03*
Y522500D03*
Y530500D03*
X82969Y517090D03*
X95700Y534500D03*
Y518500D03*
Y538500D03*
X84200Y534300D03*
Y538300D03*
X71120Y535931D03*
Y531831D03*
X83700Y606500D03*
X77200Y582000D03*
X83300Y681900D03*
X90900D03*
X79200Y723200D03*
X83000Y753700D03*
Y757900D03*
X110500Y212200D03*
X109500Y230100D03*
X101300Y272000D03*
X99007Y281582D03*
X104200Y294900D03*
Y290900D03*
X103890Y319780D03*
X103940Y315650D03*
X104100Y324100D03*
X104000Y328600D03*
X126400Y392300D03*
X102600Y732300D03*
X118200Y756000D03*
X135880Y311214D03*
X157500Y402200D03*
X146769Y636620D03*
X137251Y648436D03*
X140600Y727800D03*
X160200Y808500D03*
X182539Y450747D03*
X166027Y447721D03*
X167400Y753400D03*
X211149Y143587D03*
X206300Y251000D03*
X216900Y446000D03*
X223200Y469000D03*
Y465000D03*
X213200Y478000D03*
X221700Y486600D03*
X213200Y502000D03*
Y506000D03*
X227350Y491200D03*
X227362Y495300D03*
X213200Y534500D03*
Y542500D03*
Y538500D03*
Y550500D03*
Y570500D03*
X226072Y563994D03*
X199700Y729500D03*
Y785000D03*
X251800Y339700D03*
X264929Y334140D03*
X260900Y443300D03*
X281200Y126000D03*
X288740Y149350D03*
X281200Y145500D03*
X297688Y578165D03*
Y583165D03*
Y588665D03*
X312482Y293550D03*
X319100Y538300D03*
X347400Y335600D03*
X336500Y318900D03*
X486660Y13180D03*
X486670Y26720D03*
X486700Y49880D03*
Y73380D03*
X473360Y143008D03*
X494300Y166000D03*
X476400Y393300D03*
X507642Y130547D03*
X508500Y186500D03*
X554180Y133550D03*
X538412Y159035D03*
X538325Y163463D03*
X549399Y291069D03*
X561731Y342980D03*
X584763Y228608D03*
X593163Y211308D03*
X623263Y209608D03*
X630863Y209408D03*
Y217608D03*
X625563Y238108D03*
X630863Y213508D03*
X608400Y348200D03*
X655700Y340100D03*
X663200D03*
X655700Y344600D03*
Y372100D03*
Y376600D03*
X663200D03*
X655700Y367100D03*
Y362100D03*
Y352600D03*
Y348600D03*
X736500Y14000D03*
X738800Y114020D03*
X738780Y109410D03*
X759800Y35100D03*
Y26200D03*
X767600D03*
X757200Y64000D03*
X770900Y74000D03*
X761300Y98800D03*
Y94700D03*
X768900Y129400D03*
Y125300D03*
X801010Y26343D03*
X787600Y74100D03*
X777000Y135200D03*
X810200Y82400D03*
X810300Y94600D03*
Y98700D03*
X831260Y105630D03*
X815125Y123631D03*
Y127631D03*
X863900Y3900D03*
X865200Y28000D03*
Y36000D03*
X865700Y8000D03*
X865533Y44034D03*
X874700Y52800D03*
X903700Y341600D03*
Y363000D03*
Y354000D03*
X908200Y33000D03*
Y29000D03*
Y41000D03*
X930670Y23540D03*
X988117Y18587D03*
X1037021Y26921D03*
X1015178Y49109D03*
X1052186Y11208D03*
X1058060Y69355D03*
X1065883Y48832D03*
X1090700Y500D03*
Y5000D03*
X1090320Y27440D03*
X1090704Y36383D03*
X1090320Y22940D03*
X1090704Y40883D03*
X1079176Y18266D03*
X1089925Y14177D03*
X1090127Y18525D03*
X1077700Y68500D03*
X1249668Y141179D03*
X1248184Y145217D03*
X1292700Y295000D03*
X1313510Y145310D03*
X1314226Y151199D03*
X1328700Y290500D03*
X1320700Y294000D03*
X1366618Y168102D03*
G54D65*
X71500Y297900D03*
G54D158*
X1056650Y36200D03*
X1049150D03*
X1056650Y28600D03*
G54D74*
X69700Y695200D03*
Y706200D03*
X129189Y324436D03*
Y335436D03*
X216469Y168525D03*
Y179525D03*
G54D92*
X118504Y887970D03*
X121654D03*
X124803D03*
X127953D03*
X131103D03*
X134252D03*
X137402D03*
X140551D03*
X143701D03*
X146851D03*
X150000D03*
X153150D03*
X156300D03*
X159449D03*
X162599D03*
X165748D03*
X168898D03*
X172048D03*
X175197D03*
X178347D03*
X181496D03*
X184646D03*
X187796D03*
X190945D03*
X194095D03*
X197244D03*
X200394D03*
X203544D03*
X206693D03*
X209843D03*
X212992D03*
X216142D03*
X219292D03*
X222441D03*
X225591D03*
X228740D03*
X231890D03*
X235040D03*
X238189D03*
X241339D03*
X244488D03*
X247638D03*
X250788D03*
X253937D03*
X257087D03*
X260237D03*
X263386D03*
X266536D03*
X269685D03*
X272835D03*
X275985D03*
X279134D03*
X282284D03*
X288583D03*
X304331D03*
X307481D03*
X310630D03*
X313780D03*
X316929D03*
X320079D03*
X323229D03*
X326378D03*
X329528D03*
X332677D03*
X335827D03*
X338977D03*
X342126D03*
X345276D03*
X348426D03*
X351575D03*
X354725D03*
X357874D03*
X361024D03*
X364174D03*
X367323D03*
X370473D03*
X373622D03*
X376772D03*
X379922D03*
X383071D03*
X386221D03*
X389370D03*
X392520D03*
X395670D03*
X398819D03*
X401969D03*
X405118D03*
X408268D03*
X411418D03*
X414567D03*
X417717D03*
X420866D03*
X424016D03*
X427166D03*
X430315D03*
X433465D03*
X436614D03*
X439764D03*
X535827D03*
X538977D03*
X542126D03*
X545276D03*
X548426D03*
X551575D03*
X554725D03*
X557874D03*
X561024D03*
X564174D03*
X567323D03*
X570473D03*
X573623D03*
X576772D03*
X579922D03*
X583071D03*
X586221D03*
X589371D03*
X592520D03*
X595670D03*
X598819D03*
X601969D03*
X605119D03*
X608268D03*
X611418D03*
X614567D03*
X617717D03*
X620867D03*
X624016D03*
X627166D03*
X630315D03*
X633465D03*
X636615D03*
X639764D03*
X642914D03*
X646063D03*
X649213D03*
X652363D03*
X655512D03*
X658662D03*
X661811D03*
X664961D03*
X668111D03*
X671260D03*
X674410D03*
X677560D03*
X680709D03*
X683859D03*
X687008D03*
X690158D03*
X693308D03*
X696457D03*
X699607D03*
X705906D03*
X721654D03*
X724804D03*
X727953D03*
X731103D03*
X734252D03*
X737402D03*
X740552D03*
X743701D03*
X746851D03*
X750000D03*
X753150D03*
X756300D03*
X759449D03*
X762599D03*
X765749D03*
X768898D03*
X772048D03*
X775197D03*
X778347D03*
X781497D03*
X784646D03*
X787796D03*
X790945D03*
X794095D03*
X797245D03*
X800394D03*
X803544D03*
X806693D03*
X809843D03*
X812993D03*
X816142D03*
X819292D03*
X822441D03*
X825591D03*
X828741D03*
X831890D03*
X835040D03*
X838189D03*
X841339D03*
X844489D03*
X847638D03*
X850788D03*
X853937D03*
X857087D03*
X1031890D03*
X1035040D03*
X1038189D03*
X1041339D03*
X1044489D03*
X1047638D03*
X1050788D03*
X1053937D03*
X1057087D03*
X1060237D03*
X1063386D03*
X1066536D03*
X1069686D03*
X1072835D03*
X1075985D03*
X1079134D03*
X1082284D03*
X1085434D03*
X1088583D03*
X1091733D03*
X1094882D03*
X1098032D03*
X1101182D03*
X1104331D03*
X1107481D03*
X1110630D03*
X1113780D03*
X1116930D03*
X1120079D03*
X1123229D03*
X1126378D03*
X1129528D03*
X1132678D03*
X1135827D03*
X1138977D03*
X1142126D03*
X1145276D03*
X1148426D03*
X1151575D03*
X1154725D03*
X1157874D03*
X1161024D03*
X1164174D03*
X1167323D03*
X1170473D03*
X1173623D03*
X1176772D03*
X1179922D03*
X1183071D03*
X1186221D03*
X1189371D03*
X1192520D03*
X1195670D03*
X1201969D03*
X1217717D03*
X1220867D03*
X1224016D03*
X1227166D03*
X1230315D03*
X1233465D03*
X1236615D03*
X1239764D03*
X1242914D03*
X1246063D03*
X1249213D03*
X1252363D03*
X1255512D03*
X1258662D03*
X1261812D03*
X1264961D03*
X1268111D03*
X1271260D03*
X1274410D03*
X1277560D03*
X1280709D03*
X1283859D03*
X1287008D03*
X1290158D03*
X1293308D03*
X1296457D03*
X1299607D03*
X1302756D03*
X1305906D03*
X1309056D03*
X1312205D03*
X1315355D03*
X1318504D03*
X1321654D03*
X1324804D03*
X1327953D03*
X1331103D03*
X1334252D03*
X1337402D03*
X1340552D03*
X1343701D03*
X1346851D03*
X1350000D03*
X1353150D03*
G54D56*
X64350Y741790D03*
Y728010D03*
X44250D03*
Y741790D03*
G54D47*
X56736Y279983D03*
Y315817D03*
X86264Y279983D03*
Y315817D03*
G54D83*
G01X876378Y129921D02*
X874410Y127953D01*
G01X876378Y165354D02*
X874410Y163386D01*
G01X876378Y200787D02*
X874410Y202755D01*
G01X876378Y236220D02*
X874410Y238188D01*
G01X876378Y240157D02*
X874410Y242125D01*
G01X876378Y244094D02*
X874410Y246062D01*
G01X876378Y248031D02*
X874410Y249999D01*
G01X876378Y251968D02*
X874410Y253936D01*
G01X876378Y255905D02*
X874410Y257873D01*
G01X896063Y133858D02*
X894095Y131890D01*
G01X900000Y137795D02*
X898032Y135827D01*
G01X900000Y133858D02*
X898032Y131890D01*
G01X900000Y141732D02*
X898032Y139764D01*
G01X907874Y129921D02*
X905906Y127953D01*
G01X880315Y129921D02*
X878347Y127953D01*
G01X884252Y129921D02*
X882284Y127953D01*
G01X888189Y129921D02*
X886221Y127953D01*
G01X880315Y125984D02*
X878347Y124016D01*
G01X888189Y125984D02*
X886221Y124016D01*
G01X884252Y133858D02*
X882284Y131890D01*
G01X888189Y137795D02*
X886221Y135827D01*
G01X884252Y141732D02*
X882284Y139764D01*
G01X896063Y129921D02*
X894095Y127953D01*
G01X900000Y129921D02*
X898032Y127953D01*
G01X903937Y129921D02*
X901969Y127953D01*
G01X892126Y129921D02*
X890158Y127953D01*
G01X896063Y125984D02*
X894095Y124016D01*
G01X903937Y125984D02*
X901969Y124016D01*
G01X907874Y118110D02*
X905906Y116142D01*
G01X907874Y122047D02*
X905906Y120079D01*
G01X907874Y125984D02*
X905906Y124016D01*
G01X896063Y141732D02*
X894095Y139764D01*
G01X900000Y161417D02*
X898032Y159449D01*
G01X900000Y157480D02*
X898032Y155512D01*
G01X900000Y153543D02*
X898032Y151575D01*
G01X900000Y149606D02*
X898032Y147638D01*
G01X900000Y145669D02*
X898032Y143701D01*
G01X907874Y165354D02*
X905906Y163386D01*
G01X903937Y165354D02*
X901969Y163386D01*
G01X900000Y177165D02*
X898032Y175197D01*
G01X900000Y173228D02*
X898032Y171260D01*
G01X900000Y169291D02*
X898032Y167323D01*
G01X900000Y165354D02*
X898032Y163386D01*
G01X896063Y165354D02*
X894095Y163386D01*
G01X888189Y145669D02*
X886221Y143701D01*
G01X884252Y149606D02*
X882284Y147638D01*
G01X888189Y153543D02*
X886221Y151575D01*
G01X884252Y157480D02*
X882284Y155512D01*
G01X888189Y161417D02*
X886221Y159449D01*
G01X880315Y165354D02*
X878347Y163386D01*
G01X884252Y165354D02*
X882284Y163386D01*
G01X888189Y165354D02*
X886221Y163386D01*
G01X884252Y169291D02*
X882284Y167323D01*
G01X896063Y149606D02*
X894095Y147638D01*
G01X896063Y157480D02*
X894095Y155512D01*
G01X903937Y161417D02*
X901969Y159449D01*
G01X907874Y161417D02*
X905906Y159449D01*
G01X896063Y177165D02*
X894095Y175197D01*
G01X896063Y169291D02*
X894095Y167323D01*
G01X892126Y165354D02*
X890158Y163386D01*
G01X907874Y177165D02*
X905906Y175197D01*
G01X903937Y177165D02*
X901969Y175197D01*
G01X907874Y173228D02*
X905906Y171260D01*
G01X903937Y173228D02*
X901969Y171260D01*
G01X907874Y169291D02*
X905906Y167323D01*
G01X903937Y169291D02*
X901969Y167323D01*
G01X888189Y173228D02*
X886221Y171260D01*
G01X903937Y185039D02*
X901969Y183071D01*
G01X907874Y185039D02*
X905906Y183071D01*
G01X900000Y188976D02*
X898032Y190944D01*
G01X900000Y185039D02*
X898032Y183071D01*
G01X900000Y181102D02*
X898032Y179134D01*
G01X896063Y200787D02*
X894095Y202755D01*
G01X900000Y208661D02*
X898032Y210629D01*
G01X900000Y200787D02*
X898032Y202755D01*
G01X900000Y196850D02*
X898032Y198818D01*
G01X900000Y192913D02*
X898032Y194881D01*
G01X888189Y181102D02*
X886221Y179134D01*
G01X884252Y192913D02*
X882284Y194881D01*
G01X888189Y196850D02*
X886221Y198818D01*
G01X880315Y200787D02*
X878347Y202755D01*
G01X884252Y200787D02*
X882284Y202755D01*
G01X888189Y200787D02*
X886221Y202755D01*
G01X884252Y204724D02*
X882284Y206692D01*
G01X888189Y208661D02*
X886221Y210629D01*
G01X896063Y185039D02*
X894095Y183071D01*
G01X907874Y188976D02*
X905906Y190944D01*
G01X903937Y188976D02*
X901969Y190944D01*
G01X907874Y181102D02*
X905906Y179134D01*
G01X903937Y181102D02*
X901969Y179134D01*
G01X896063Y192913D02*
X894095Y194881D01*
G01X896063Y204724D02*
X894095Y206692D01*
G01X900000Y204724D02*
X898032Y206692D01*
G01X892126Y200787D02*
X890158Y202755D01*
G01X907874Y208661D02*
X905906Y210629D01*
G01X903937Y208661D02*
X901969Y210629D01*
G01X907874Y204724D02*
X905906Y206692D01*
G01X903937Y204724D02*
X901969Y206692D01*
G01X907874Y200787D02*
X905906Y202755D01*
G01X903937Y200787D02*
X901969Y202755D01*
G01X907874Y196850D02*
X905906Y198818D01*
G01X903937Y196850D02*
X901969Y198818D01*
G01X907874Y192913D02*
X905906Y194881D01*
G01X903937Y192913D02*
X901969Y194881D01*
G01X884252Y185039D02*
X888189Y188976D01*
G01D02*
X886221Y190944D01*
G01X884252Y177165D02*
X886221Y179134D01*
G01X900000Y212598D02*
X898032Y214566D01*
G01X900000Y216535D02*
X898032Y218503D01*
G01X900000Y220472D02*
X898032Y222440D01*
G01X900000Y224409D02*
X898032Y226377D01*
G01X903937Y236220D02*
X901969Y238188D01*
G01X907874Y236220D02*
X905906Y238188D01*
G01X900000Y228346D02*
X898032Y230314D01*
G01X900000Y232283D02*
X898032Y234251D01*
G01X896063Y236220D02*
X894095Y238188D01*
G01X900000Y236220D02*
X898032Y238188D01*
G01X884252Y212598D02*
X882284Y214566D01*
G01X888189Y216535D02*
X886221Y218503D01*
G01X884252Y228346D02*
X882284Y230314D01*
G01X888189Y232283D02*
X886221Y234251D01*
G01X880315Y236220D02*
X878347Y238188D01*
G01X884252Y236220D02*
X882284Y238188D01*
G01X888189Y236220D02*
X886221Y238188D01*
G01X880315Y240157D02*
X878347Y242125D01*
G01X888189Y240157D02*
X886221Y242125D01*
G01X884252Y220472D02*
X882284Y222440D01*
G01X888189Y224409D02*
X886221Y226377D01*
G01X896063Y212598D02*
X894095Y214566D01*
G01X907874Y216535D02*
X905906Y218503D01*
G01X903937Y216535D02*
X901969Y218503D01*
G01X907874Y212598D02*
X905906Y214566D01*
G01X903937Y212598D02*
X901969Y214566D01*
G01X903937Y240157D02*
X901969Y242125D01*
G01X896063Y228346D02*
X894095Y230314D01*
G01X896063Y240157D02*
X894095Y242125D01*
G01X892126Y236220D02*
X890158Y238188D01*
G01X896063Y220472D02*
X894095Y222440D01*
G01X903937Y232283D02*
X901969Y234251D01*
G01X907874Y228346D02*
X905906Y230314D01*
G01X903937Y228346D02*
X901969Y230314D01*
G01X907874Y232283D02*
X905906Y234251D01*
G01X907874Y224409D02*
X905906Y226377D01*
G01X903937Y224409D02*
X901969Y226377D01*
G01X907874Y220472D02*
X905906Y222440D01*
G01X903937Y220472D02*
X901969Y222440D01*
G01X884252Y248031D02*
X882284Y249999D01*
G01X888189Y251968D02*
X886221Y253936D01*
G01X880315Y251968D02*
X878347Y253936D01*
G01X900000Y248031D02*
X898032Y249999D01*
G01X907874Y248031D02*
X905906Y249999D01*
G01X892126Y248031D02*
X890158Y249999D01*
G01X896063Y251968D02*
X894095Y253936D01*
G01X903937Y251968D02*
X901969Y253936D01*
G01X915748Y129921D02*
X913780Y127953D01*
G01X915748Y141732D02*
X913780Y139764D01*
G01X923622Y129921D02*
X921654Y127953D01*
G01X931496Y129921D02*
X929528Y127953D01*
G01X939370Y129921D02*
X937402Y127953D01*
G01X939370Y141732D02*
X937402Y139764D01*
G01X911811Y129921D02*
X909843Y127953D01*
G01X915748Y125984D02*
X913780Y124016D01*
G01X911811Y137795D02*
X909843Y135827D01*
G01X919685Y129921D02*
X917717Y127953D01*
G01X923622Y125984D02*
X921654Y124016D01*
G01X927559Y129921D02*
X925591Y127953D01*
G01X931496Y125984D02*
X929528Y124016D01*
G01X935433Y129921D02*
X933465Y127953D01*
G01X939370Y125984D02*
X937402Y124016D01*
G01X943307Y118110D02*
X941339Y116142D01*
G01X943307Y122047D02*
X941339Y120079D01*
G01X943307Y125984D02*
X941339Y124016D01*
G01X923622Y137795D02*
X921654Y135827D01*
G01X935433Y141732D02*
X933465Y139764D01*
G01X943307Y141732D02*
X941339Y139764D01*
G01X931496Y161417D02*
X929528Y159449D01*
G01X923622Y161417D02*
X921654Y159449D01*
G01X919685Y173228D02*
X917717Y171260D01*
G01X919685Y165354D02*
X917717Y163386D01*
G01X923622Y169291D02*
X921654Y167323D01*
G01X927559Y165354D02*
X925591Y163386D01*
G01X923622Y177165D02*
X921654Y175197D01*
G01X927559Y173228D02*
X925591Y171260D01*
G01X935433Y165354D02*
X933465Y163386D01*
G01X931496Y169291D02*
X929528Y167323D01*
G01X935433Y173228D02*
X933465Y171260D01*
G01X931496Y177165D02*
X929528Y175197D01*
G01X943307Y165354D02*
X941339Y163386D01*
G01X939370Y169291D02*
X937402Y167323D01*
G01X943307Y173228D02*
X941339Y171260D01*
G01X939370Y177165D02*
X937402Y175197D01*
G01X927559Y153543D02*
X925591Y151575D01*
G01X939370Y161417D02*
X937402Y159449D01*
G01X911811Y149606D02*
X909843Y147638D01*
G01X915748Y177165D02*
X913780Y175197D01*
G01X911811Y177165D02*
X909843Y175197D01*
G01X915748Y173228D02*
X913780Y171260D01*
G01X911811Y173228D02*
X909843Y171260D01*
G01X915748Y169291D02*
X913780Y167323D01*
G01X911811Y169291D02*
X909843Y167323D01*
G01X915748Y165354D02*
X913780Y163386D01*
G01X911811Y165354D02*
X909843Y163386D01*
G01X923622Y149606D02*
X921654Y147638D01*
G01X927559Y161417D02*
X925591Y159449D01*
G01X935433Y161417D02*
X933465Y159449D01*
G01X939370Y153543D02*
X937402Y151575D01*
G01X943307Y161417D02*
X941339Y159449D01*
G01X931496Y165354D02*
X929528Y163386D01*
G01X919685Y177165D02*
X917717Y175197D01*
G01X923622Y173228D02*
X921654Y171260D01*
G01X919685Y169291D02*
X917717Y167323D01*
G01X927559Y169291D02*
X925591Y167323D01*
G01X923622Y165354D02*
X921654Y163386D01*
G01X927559Y177165D02*
X925591Y175197D01*
G01X931496Y173228D02*
X929528Y171260D01*
G01X939370Y165354D02*
X937402Y163386D01*
G01X935433Y169291D02*
X933465Y167323D01*
G01X939370Y173228D02*
X937402Y171260D01*
G01X935433Y177165D02*
X933465Y175197D01*
G01X943307Y169291D02*
X941339Y167323D01*
G01X943307Y177165D02*
X941339Y175197D01*
G01X919685Y181102D02*
X917717Y179134D01*
G01X915748Y185039D02*
X913780Y183071D01*
G01X919685Y188976D02*
X917717Y190944D01*
G01X943307Y181102D02*
X941339Y179134D01*
G01X939370Y185039D02*
X937402Y183071D01*
G01X935433Y188976D02*
X933465Y190944D01*
G01X943307Y188976D02*
X941339Y190944D01*
G01X923622Y185039D02*
X921654Y183071D01*
G01X927559Y181102D02*
X925591Y179134D01*
G01X931496Y185039D02*
X929528Y183071D01*
G01X935433Y181102D02*
X933465Y179134D01*
G01X927559Y188976D02*
X925591Y190944D01*
G01X943307Y204724D02*
X941339Y206692D01*
G01X939370Y208661D02*
X937402Y210629D01*
G01X943307Y196850D02*
X941339Y198818D01*
G01X939370Y200787D02*
X937402Y202755D01*
G01X935433Y204724D02*
X933465Y206692D01*
G01X931496Y208661D02*
X929528Y210629D01*
G01X919685Y204724D02*
X917717Y206692D01*
G01X923622Y200787D02*
X921654Y202755D01*
G01X927559Y196850D02*
X925591Y198818D01*
G01X931496Y192913D02*
X929528Y194881D01*
G01X923622Y208661D02*
X921654Y210629D01*
G01X927559Y204724D02*
X925591Y206692D01*
G01X931496Y200787D02*
X929528Y202755D01*
G01X935433Y196850D02*
X933465Y198818D01*
G01X939370Y192913D02*
X937402Y194881D01*
G01X919685Y196850D02*
X917717Y198818D01*
G01X923622Y192913D02*
X921654Y194881D01*
G01X915748Y188976D02*
X913780Y190944D01*
G01X911811Y188976D02*
X909843Y190944D01*
G01X911811Y185039D02*
X909843Y183071D01*
G01X915748Y181102D02*
X913780Y179134D01*
G01X911811Y181102D02*
X909843Y179134D01*
G01X915748Y208661D02*
X913780Y210629D01*
G01X911811Y208661D02*
X909843Y210629D01*
G01X915748Y204724D02*
X913780Y206692D01*
G01X911811Y204724D02*
X909843Y206692D01*
G01X915748Y200787D02*
X913780Y202755D01*
G01X911811Y200787D02*
X909843Y202755D01*
G01X915748Y196850D02*
X913780Y198818D01*
G01X911811Y196850D02*
X909843Y198818D01*
G01X915748Y192913D02*
X913780Y194881D01*
G01X911811Y192913D02*
X909843Y194881D01*
G01X923622Y188976D02*
X921654Y190944D01*
G01X919685Y185039D02*
X917717Y183071D01*
G01X939370Y188976D02*
X937402Y190944D01*
G01X923622Y181102D02*
X921654Y179134D01*
G01X927559Y185039D02*
X925591Y183071D01*
G01X931496Y181102D02*
X929528Y179134D01*
G01X931496Y188976D02*
X929528Y190944D01*
G01X935433Y185039D02*
X933465Y183071D01*
G01X919685Y192913D02*
X917717Y194881D01*
G01X919685Y208661D02*
X917717Y210629D01*
G01X923622Y204724D02*
X921654Y206692D01*
G01X927559Y200787D02*
X925591Y202755D01*
G01X931496Y196850D02*
X929528Y198818D01*
G01X935433Y192913D02*
X933465Y194881D01*
G01X927559Y208661D02*
X925591Y210629D01*
G01X931496Y204724D02*
X929528Y206692D01*
G01X935433Y200787D02*
X933465Y202755D01*
G01X939370Y196850D02*
X937402Y198818D01*
G01X943307Y192913D02*
X941339Y194881D01*
G01X943307Y200787D02*
X941339Y202755D01*
G01X939370Y204724D02*
X937402Y206692D01*
G01X935433Y208661D02*
X933465Y210629D01*
G01X919685Y200787D02*
X917717Y202755D01*
G01X923622Y196850D02*
X921654Y198818D01*
G01X927559Y192913D02*
X925591Y194881D01*
G01X939370Y181102D02*
X937402Y179134D01*
G01X943307Y185039D02*
X939370Y181102D01*
G01X911811Y236220D02*
X909843Y238188D01*
G01X915748Y236220D02*
X913780Y238188D01*
G01X919685Y212598D02*
X917717Y214566D01*
G01X919685Y236220D02*
X917717Y238188D01*
G01X923622Y236220D02*
X921654Y238188D01*
G01X915748Y212598D02*
X913780Y214566D01*
G01X927559Y232283D02*
X925591Y234251D01*
G01X931496Y236220D02*
X929528Y238188D01*
G01X935433Y232283D02*
X933465Y234251D01*
G01X939370Y236220D02*
X937402Y238188D01*
G01X943307Y232283D02*
X941339Y234251D01*
G01X939370Y228346D02*
X937402Y230314D01*
G01X931496Y228346D02*
X929528Y230314D01*
G01X927559Y224409D02*
X925591Y226377D01*
G01X931496Y220472D02*
X929528Y222440D01*
G01X935433Y224409D02*
X933465Y226377D01*
G01X939370Y220472D02*
X937402Y222440D01*
G01X943307Y224409D02*
X941339Y226377D01*
G01X935433Y212598D02*
X933465Y214566D01*
G01X943307Y212598D02*
X941339Y214566D01*
G01X927559Y212598D02*
X925591Y214566D01*
G01X915748Y216535D02*
X913780Y218503D01*
G01X911811Y216535D02*
X909843Y218503D01*
G01X911811Y212598D02*
X909843Y214566D01*
G01X911811Y240157D02*
X909843Y242125D01*
G01X915748Y240157D02*
X913780Y242125D01*
G01X915748Y232283D02*
X913780Y234251D01*
G01X915748Y228346D02*
X913780Y230314D01*
G01X911811Y232283D02*
X909843Y234251D01*
G01X911811Y228346D02*
X909843Y230314D01*
G01X911811Y224409D02*
X909843Y226377D01*
G01X915748Y220472D02*
X913780Y222440D01*
G01X911811Y220472D02*
X909843Y222440D01*
G01X915748Y224409D02*
X913780Y226377D01*
G01X919685Y216535D02*
X917717Y218503D01*
G01X923622Y212598D02*
X921654Y214566D01*
G01X943307Y216535D02*
X941339Y218503D01*
G01X939370Y216535D02*
X937402Y218503D01*
G01X935433Y216535D02*
X933465Y218503D01*
G01X931496Y216535D02*
X929528Y218503D01*
G01X927559Y216535D02*
X925591Y218503D01*
G01X923622Y216535D02*
X921654Y218503D01*
G01X931496Y212598D02*
X929528Y214566D01*
G01X923622Y240157D02*
X921654Y242125D01*
G01X927559Y236220D02*
X925591Y238188D01*
G01X931496Y232283D02*
X929528Y234251D01*
G01X931496Y240157D02*
X929528Y242125D01*
G01X935433Y228346D02*
X933465Y230314D01*
G01X935433Y236220D02*
X933465Y238188D01*
G01X939370Y232283D02*
X937402Y234251D01*
G01X939370Y240157D02*
X937402Y242125D01*
G01X943307Y228346D02*
X941339Y230314D01*
G01X943307Y236220D02*
X941339Y238188D01*
G01X931496Y224409D02*
X929528Y226377D01*
G01X939370Y224409D02*
X937402Y226377D01*
G01X943307Y220472D02*
X941339Y222440D01*
G01X935433Y220472D02*
X933465Y222440D01*
G01X927559Y220472D02*
X925591Y222440D01*
G01X927559Y228346D02*
X925591Y230314D01*
G01X923622Y232283D02*
X921654Y234251D01*
G01X923622Y228346D02*
X921654Y230314D01*
G01X919685Y232283D02*
X917717Y234251D01*
G01X919685Y228346D02*
X917717Y230314D01*
G01X923622Y224409D02*
X921654Y226377D01*
G01X923622Y220472D02*
X921654Y222440D01*
G01X919685Y224409D02*
X917717Y226377D01*
G01X919685Y220472D02*
X917717Y222440D01*
G01X939370Y212598D02*
X937402Y214566D01*
G01X943307Y208661D02*
X939370Y212598D01*
G01X911811Y244094D02*
X909843Y246062D01*
G01X911811Y248031D02*
X909843Y249999D01*
G01X911811Y251968D02*
X909843Y253936D01*
G01X911811Y255905D02*
X909843Y257873D01*
G01X911811Y259842D02*
X909843Y261810D01*
G01X915748Y251968D02*
X913780Y253936D01*
G01X919685Y248031D02*
X917717Y249999D01*
G01X927559Y248031D02*
X925591Y249999D01*
G01X935433Y248031D02*
X933465Y249999D01*
G01X943307Y248031D02*
X941339Y249999D01*
G01X923622Y251968D02*
X921654Y253936D01*
G01X931496Y251968D02*
X929528Y253936D01*
G01X939370Y251968D02*
X937402Y253936D01*
G01X955118Y141732D02*
X957086Y139764D01*
G01X970866Y129921D02*
X972834Y127953D01*
G01X962992Y129921D02*
X964960Y127953D01*
G01X955118Y129921D02*
X957086Y127953D01*
G01X955118Y125984D02*
X957086Y124016D01*
G01X959055Y129921D02*
X961023Y127953D01*
G01X962992Y125984D02*
X964960Y124016D01*
G01X966929Y129921D02*
X968897Y127953D01*
G01X970866Y125984D02*
X972834Y124016D01*
G01X974803Y129921D02*
X976771Y127953D01*
G01X951181Y118110D02*
X953149Y116142D01*
G01X951181Y122047D02*
X953149Y120079D01*
G01X951181Y125984D02*
X953149Y124016D01*
G01X966929Y141732D02*
X968897Y139764D01*
G01X951181Y137795D02*
X953149Y135827D01*
G01X951181Y165354D02*
X953149Y163386D01*
G01X970866Y177165D02*
X972834Y175197D01*
G01X974803Y173228D02*
X976771Y171260D01*
G01X962992Y177165D02*
X964960Y175197D01*
G01X966929Y173228D02*
X968897Y171260D01*
G01X970866Y169291D02*
X972834Y167323D01*
G01X974803Y165354D02*
X976771Y163386D01*
G01X955118Y169291D02*
X957086Y167323D01*
G01X959055Y165354D02*
X961023Y163386D01*
G01X947244Y177165D02*
X949212Y175197D01*
G01X951181Y173228D02*
X953149Y171260D01*
G01X959055Y173228D02*
X961023Y171260D01*
G01X955118Y177165D02*
X957086Y175197D01*
G01X966929Y165354D02*
X968897Y163386D01*
G01X962992Y169291D02*
X964960Y167323D01*
G01X947244Y169291D02*
X949212Y167323D01*
G01X955118Y161417D02*
X957086Y159449D01*
G01X962992Y161417D02*
X964960Y159449D01*
G01X966929Y153543D02*
X968897Y151575D01*
G01X970866Y161417D02*
X972834Y159449D01*
G01X947244Y161417D02*
X949212Y159449D01*
G01X951181Y153543D02*
X953149Y151575D01*
G01X959055Y149606D02*
X961023Y147638D01*
G01X959055Y161417D02*
X961023Y159449D01*
G01X966929Y161417D02*
X968897Y159449D01*
G01X970866Y149606D02*
X972834Y147638D01*
G01X947244Y153543D02*
X949212Y151575D01*
G01X951181Y161417D02*
X953149Y159449D01*
G01X955118Y173228D02*
X957086Y171260D01*
G01X951181Y177165D02*
X953149Y175197D01*
G01X962992Y165354D02*
X964960Y163386D01*
G01X959055Y169291D02*
X961023Y167323D01*
G01X959055Y177165D02*
X961023Y175197D01*
G01X962992Y173228D02*
X964960Y171260D01*
G01X966929Y169291D02*
X968897Y167323D01*
G01X970866Y165354D02*
X972834Y163386D01*
G01X966929Y177165D02*
X968897Y175197D01*
G01X970866Y173228D02*
X972834Y171260D01*
G01X974803Y169291D02*
X976771Y167323D01*
G01X947244Y165354D02*
X949212Y163386D01*
G01X947244Y173228D02*
X949212Y171260D01*
G01X955118Y165354D02*
X957086Y163386D01*
G01X951181Y169291D02*
X953149Y167323D01*
G01X974803Y181102D02*
X976771Y179134D01*
G01X966929Y181102D02*
X968897Y179134D01*
G01X962992Y185039D02*
X964960Y183071D01*
G01X959055Y188976D02*
X961023Y190944D01*
G01X970866Y185039D02*
X972834Y183071D01*
G01X966929Y188976D02*
X968897Y190944D01*
G01X976771D02*
X974803Y188976D01*
G01X951181D02*
X953149Y190944D01*
G01X955118Y185039D02*
X957086Y183071D01*
G01X959055Y181102D02*
X961023Y179134D01*
G01X951181Y181102D02*
X953149Y179134D01*
G01X947244Y185039D02*
X949212Y183071D01*
G01X962992Y208661D02*
X964960Y210629D01*
G01X966929Y204724D02*
X968897Y206692D01*
G01X970866Y200787D02*
X972834Y202755D01*
G01X974803Y196850D02*
X976771Y198818D01*
G01X970866Y208661D02*
X972834Y210629D01*
G01X974803Y204724D02*
X976771Y206692D01*
G01X955118Y192913D02*
X957086Y194881D01*
G01X951181Y196850D02*
X953149Y198818D01*
G01X947244Y200787D02*
X949212Y202755D01*
G01X955118Y200787D02*
X957086Y202755D01*
G01X959055Y196850D02*
X961023Y198818D01*
G01X962992Y192913D02*
X964960Y194881D01*
G01X951181Y204724D02*
X953149Y206692D01*
G01X947244Y208661D02*
X949212Y210629D01*
G01X970866Y192913D02*
X972834Y194881D01*
G01X959055Y204724D02*
X961023Y206692D01*
G01X955118Y208661D02*
X957086Y210629D01*
G01X962992Y200787D02*
X964960Y202755D01*
G01X966929Y196850D02*
X968897Y198818D01*
G01X947244Y192913D02*
X949212Y194881D01*
G01X974803Y185039D02*
X976771Y183071D01*
G01X974803Y177165D02*
X976771Y175197D01*
G01X970866Y181102D02*
X972834Y179134D01*
G01X966929Y185039D02*
X968897Y183071D01*
G01X962992Y188976D02*
X964960Y190944D01*
G01X947244Y181102D02*
X949212Y179134D01*
G01X955118Y181102D02*
X957086Y179134D01*
G01X951181Y185039D02*
X953149Y183071D01*
G01X955118Y188976D02*
X957086Y190944D01*
G01X959055Y185039D02*
X961023Y183071D01*
G01X962992Y181102D02*
X964960Y179134D01*
G01X970866Y188976D02*
X972834Y190944D01*
G01X974803Y192913D02*
X976771Y194881D01*
G01X959055Y208661D02*
X961023Y210629D01*
G01X962992Y204724D02*
X964960Y206692D01*
G01X966929Y200787D02*
X968897Y202755D01*
G01X970866Y196850D02*
X972834Y198818D01*
G01X974803Y208661D02*
X976771Y210629D01*
G01X966929Y208661D02*
X968897Y210629D01*
G01X970866Y204724D02*
X972834Y206692D01*
G01X974803Y200787D02*
X976771Y202755D01*
G01X955118Y196850D02*
X957086Y198818D01*
G01X959055Y192913D02*
X961023Y194881D01*
G01X951181Y200787D02*
X953149Y202755D01*
G01X947244Y204724D02*
X949212Y206692D01*
G01X947244Y196850D02*
X949212Y198818D01*
G01X966929Y192913D02*
X968897Y194881D01*
G01X955118Y204724D02*
X957086Y206692D01*
G01X959055Y200787D02*
X961023Y202755D01*
G01X962992Y196850D02*
X964960Y198818D01*
G01X951181Y208661D02*
X953149Y210629D01*
G01X947244Y188976D02*
X951181Y192913D01*
G01D02*
X953149Y194881D01*
G01X974803Y212598D02*
X976771Y214566D01*
G01X970866Y236220D02*
X972834Y238188D01*
G01X974803Y236220D02*
X976771Y238188D01*
G01X966929Y224409D02*
X968897Y226377D01*
G01X966929Y232283D02*
X968897Y234251D01*
G01X955118Y236220D02*
X957086Y238188D01*
G01X959055Y232283D02*
X961023Y234251D01*
G01X962992Y236220D02*
X964960Y238188D01*
G01X947244Y236220D02*
X949212Y238188D01*
G01X951181Y232283D02*
X953149Y234251D01*
G01X955118Y228346D02*
X957086Y230314D01*
G01X962992Y228346D02*
X964960Y230314D01*
G01X955118Y220472D02*
X957086Y222440D01*
G01X959055Y224409D02*
X961023Y226377D01*
G01X962992Y220472D02*
X964960Y222440D01*
G01X947244Y228346D02*
X949212Y230314D01*
G01X947244Y220472D02*
X949212Y222440D01*
G01X951181Y224409D02*
X953149Y226377D01*
G01X959055Y212598D02*
X961023Y214566D01*
G01X966929Y212598D02*
X968897Y214566D01*
G01X951181Y212598D02*
X953149Y214566D01*
G01X966929Y216535D02*
X968897Y218503D01*
G01X962992Y216535D02*
X964960Y218503D01*
G01X959055Y216535D02*
X961023Y218503D01*
G01X955118Y216535D02*
X957086Y218503D01*
G01X970866Y212598D02*
X972834Y214566D01*
G01X955118Y212598D02*
X957086Y214566D01*
G01X951181Y216535D02*
X953149Y218503D01*
G01X947244Y216535D02*
X949212Y218503D01*
G01X970866Y216535D02*
X972834Y218503D01*
G01X974803Y216535D02*
X976771Y218503D01*
G01X962992Y212598D02*
X964960Y214566D01*
G01X947244Y212598D02*
X949212Y214566D01*
G01X955118Y232283D02*
X957086Y234251D01*
G01X955118Y240157D02*
X957086Y242125D01*
G01X959055Y228346D02*
X961023Y230314D01*
G01X959055Y236220D02*
X961023Y238188D01*
G01X962992Y232283D02*
X964960Y234251D01*
G01X962992Y240157D02*
X964960Y242125D01*
G01X966929Y236220D02*
X968897Y238188D01*
G01X947244Y232283D02*
X949212Y234251D01*
G01X947244Y240157D02*
X949212Y242125D01*
G01X951181Y228346D02*
X953149Y230314D01*
G01X951181Y236220D02*
X953149Y238188D01*
G01X955118Y224409D02*
X957086Y226377D01*
G01X962992Y224409D02*
X964960Y226377D01*
G01X947244Y224409D02*
X949212Y226377D01*
G01X970866Y240157D02*
X972834Y242125D01*
G01X959055Y220472D02*
X961023Y222440D01*
G01X951181Y220472D02*
X953149Y222440D01*
G01X966929Y220472D02*
X968897Y222440D01*
G01X966929Y228346D02*
X968897Y230314D01*
G01X974803Y232283D02*
X976771Y234251D01*
G01X974803Y228346D02*
X976771Y230314D01*
G01X970866Y232283D02*
X972834Y234251D01*
G01X970866Y228346D02*
X972834Y230314D01*
G01X974803Y224409D02*
X976771Y226377D01*
G01X974803Y220472D02*
X976771Y222440D01*
G01X970866Y224409D02*
X972834Y226377D01*
G01X970866Y220472D02*
X972834Y222440D01*
G01X959055Y248031D02*
X961023Y249999D01*
G01X966929Y248031D02*
X968897Y249999D01*
G01X947244Y244094D02*
X949212Y246062D01*
G01X947244Y248031D02*
X949212Y249999D01*
G01X951181Y248031D02*
X953149Y249999D01*
G01X974803Y248031D02*
X976771Y249999D01*
G01X955118Y251968D02*
X957086Y253936D01*
G01X962992Y251968D02*
X964960Y253936D01*
G01X947244Y251968D02*
X949212Y253936D01*
G01X947244Y255905D02*
X949212Y257873D01*
G01X947244Y259842D02*
X949212Y261810D01*
G01X970866Y251968D02*
X972834Y253936D01*
G01X998425Y133858D02*
X1000393Y131890D01*
G01X994488Y137795D02*
X996456Y135827D01*
G01X994488Y133858D02*
X996456Y131890D01*
G01X994488Y141732D02*
X996456Y139764D01*
G01X978740Y141732D02*
X980708Y139764D01*
G01X978740Y129921D02*
X980708Y127953D01*
G01X1002362Y129921D02*
X1004330Y127953D01*
G01X998425Y129921D02*
X1000393Y127953D01*
G01X998425Y125984D02*
X1000393Y124016D01*
G01X994488Y129921D02*
X996456Y127953D01*
G01X978740Y125984D02*
X980708Y124016D01*
G01X982677Y129921D02*
X984645Y127953D01*
G01X986614Y118110D02*
X988582Y116142D01*
G01X986614Y122047D02*
X988582Y120079D01*
G01X986614Y125984D02*
X988582Y124016D01*
G01X986614Y129921D02*
X988582Y127953D01*
G01X990551Y125984D02*
X992519Y124016D01*
G01X990551Y129921D02*
X992519Y127953D01*
G01X998425Y141732D02*
X1000393Y139764D01*
G01X982677Y137795D02*
X984645Y135827D01*
G01X1006299Y125984D02*
X1008267Y124016D01*
G01X1006299Y129921D02*
X1008267Y127953D01*
G01X1006299Y137795D02*
X1008267Y135827D01*
G01X994488Y161417D02*
X996456Y159449D01*
G01X994488Y157480D02*
X996456Y155512D01*
G01X994488Y153543D02*
X996456Y151575D01*
G01X994488Y149606D02*
X996456Y147638D01*
G01X994488Y145669D02*
X996456Y143701D01*
G01X978740Y177165D02*
X980708Y175197D01*
G01X986614Y165354D02*
X988582Y163386D01*
G01X990551Y165354D02*
X992519Y163386D01*
G01X994488Y177165D02*
X996456Y175197D01*
G01X994488Y173228D02*
X996456Y171260D01*
G01X994488Y169291D02*
X996456Y167323D01*
G01X998425Y165354D02*
X1000393Y163386D01*
G01X994488Y165354D02*
X996456Y163386D01*
G01X998425Y157480D02*
X1000393Y155512D01*
G01X998425Y149606D02*
X1000393Y147638D01*
G01X982677Y149606D02*
X984645Y147638D01*
G01X990551Y161417D02*
X992519Y159449D01*
G01X986614Y161417D02*
X988582Y159449D01*
G01X998425Y177165D02*
X1000393Y175197D01*
G01X1002362Y165354D02*
X1004330Y163386D01*
G01X998425Y169291D02*
X1000393Y167323D01*
G01X982677Y177165D02*
X984645Y175197D01*
G01X990551Y177165D02*
X992519Y175197D01*
G01X986614Y177165D02*
X988582Y175197D01*
G01X982677Y173228D02*
X984645Y171260D01*
G01X978740Y173228D02*
X980708Y171260D01*
G01X990551Y173228D02*
X992519Y171260D01*
G01X986614Y173228D02*
X988582Y171260D01*
G01X982677Y169291D02*
X984645Y167323D01*
G01X978740Y169291D02*
X980708Y167323D01*
G01X990551Y169291D02*
X992519Y167323D01*
G01X986614Y169291D02*
X988582Y167323D01*
G01X982677Y165354D02*
X984645Y163386D01*
G01X978740Y165354D02*
X980708Y163386D01*
G01X1006299Y153543D02*
X1008267Y151575D01*
G01X1006299Y145669D02*
X1008267Y143701D01*
G01X1006299Y161417D02*
X1008267Y159449D01*
G01X1006299Y173228D02*
X1008267Y171260D01*
G01X1006299Y165354D02*
X1008267Y163386D01*
G01X986614Y185039D02*
X988582Y183071D01*
G01X990551Y185039D02*
X992519Y183071D01*
G01X994488Y188976D02*
X996456Y190944D01*
G01X994488Y185039D02*
X996456Y183071D01*
G01X994488Y181102D02*
X996456Y179134D01*
G01X994488Y208661D02*
X996456Y210629D01*
G01X998425Y200787D02*
X1000393Y202755D01*
G01X994488Y200787D02*
X996456Y202755D01*
G01X994488Y196850D02*
X996456Y198818D01*
G01X994488Y192913D02*
X996456Y194881D01*
G01X978740Y185039D02*
X980708Y183071D01*
G01X998425Y185039D02*
X1000393Y183071D01*
G01X982677Y185039D02*
X984645Y183071D01*
G01X982677Y181102D02*
X984645Y179134D01*
G01X978740Y181102D02*
X980708Y179134D01*
G01X982677Y188976D02*
X984645Y190944D01*
G01X978740Y188976D02*
X980708Y190944D01*
G01X990551Y188976D02*
X992519Y190944D01*
G01X986614Y188976D02*
X988582Y190944D01*
G01X990551Y181102D02*
X992519Y179134D01*
G01X986614Y181102D02*
X988582Y179134D01*
G01X998425Y192913D02*
X1000393Y194881D01*
G01X1002362Y200787D02*
X1004330Y202755D01*
G01X994488Y204724D02*
X996456Y206692D01*
G01X998425Y204724D02*
X1000393Y206692D01*
G01X982677Y208661D02*
X984645Y210629D01*
G01X978740Y208661D02*
X980708Y210629D01*
G01X990551Y208661D02*
X992519Y210629D01*
G01X986614Y208661D02*
X988582Y210629D01*
G01X982677Y204724D02*
X984645Y206692D01*
G01X978740Y204724D02*
X980708Y206692D01*
G01X990551Y204724D02*
X992519Y206692D01*
G01X986614Y204724D02*
X988582Y206692D01*
G01X982677Y200787D02*
X984645Y202755D01*
G01X978740Y200787D02*
X980708Y202755D01*
G01X990551Y200787D02*
X992519Y202755D01*
G01X986614Y200787D02*
X988582Y202755D01*
G01X982677Y196850D02*
X984645Y198818D01*
G01X990551Y196850D02*
X992519Y198818D01*
G01X986614Y196850D02*
X988582Y198818D01*
G01X982677Y192913D02*
X984645Y194881D01*
G01X978740Y192913D02*
X980708Y194881D01*
G01X990551Y192913D02*
X992519Y194881D01*
G01X986614Y192913D02*
X988582Y194881D01*
G01X978740Y196850D02*
X980708Y198818D01*
G01X1006299Y181102D02*
X1008267Y179134D01*
G01X1006299Y188976D02*
X1008267Y190944D01*
G01X1006299Y196850D02*
X1008267Y198818D01*
G01X1006299Y200787D02*
X1008267Y202755D01*
G01X1006299Y208661D02*
X1008267Y210629D01*
G01X994488Y212598D02*
X996456Y214566D01*
G01X994488Y216535D02*
X996456Y218503D01*
G01X994488Y220472D02*
X996456Y222440D01*
G01X994488Y224409D02*
X996456Y226377D01*
G01X994488Y228346D02*
X996456Y230314D01*
G01X994488Y232283D02*
X996456Y234251D01*
G01X994488Y236220D02*
X996456Y238188D01*
G01X998425Y236220D02*
X1000393Y238188D01*
G01X978740Y236220D02*
X980708Y238188D01*
G01X982677Y236220D02*
X984645Y238188D01*
G01X986614Y236220D02*
X988582Y238188D01*
G01X990551Y236220D02*
X992519Y238188D01*
G01X978740Y212598D02*
X980708Y214566D01*
G01X998425Y212598D02*
X1000393Y214566D01*
G01X982677Y216535D02*
X984645Y218503D01*
G01X978740Y216535D02*
X980708Y218503D01*
G01X990551Y216535D02*
X992519Y218503D01*
G01X986614Y216535D02*
X988582Y218503D01*
G01X990551Y212598D02*
X992519Y214566D01*
G01X986614Y212598D02*
X988582Y214566D01*
G01X982677Y212598D02*
X984645Y214566D01*
G01X990551Y240157D02*
X992519Y242125D01*
G01X982677Y240157D02*
X984645Y242125D01*
G01X978740Y240157D02*
X980708Y242125D01*
G01X998425Y240157D02*
X1000393Y242125D01*
G01X1002362Y236220D02*
X1004330Y238188D01*
G01X998425Y228346D02*
X1000393Y230314D01*
G01X986614Y232283D02*
X988582Y234251D01*
G01X982677Y232283D02*
X984645Y234251D01*
G01X982677Y228346D02*
X984645Y230314D01*
G01X978740Y232283D02*
X980708Y234251D01*
G01X978740Y228346D02*
X980708Y230314D01*
G01X990551Y232283D02*
X992519Y234251D01*
G01X990551Y228346D02*
X992519Y230314D01*
G01X986614Y228346D02*
X988582Y230314D01*
G01X978740Y224409D02*
X980708Y226377D01*
G01X982677Y224409D02*
X984645Y226377D01*
G01X990551Y224409D02*
X992519Y226377D01*
G01X986614Y224409D02*
X988582Y226377D01*
G01X982677Y220472D02*
X984645Y222440D01*
G01X978740Y220472D02*
X980708Y222440D01*
G01X990551Y220472D02*
X992519Y222440D01*
G01X986614Y220472D02*
X988582Y222440D01*
G01X998425Y220472D02*
X1000393Y222440D01*
G01X1006299Y216535D02*
X1008267Y218503D01*
G01X1006299Y232283D02*
X1008267Y234251D01*
G01X1006299Y236220D02*
X1008267Y238188D01*
G01X1006299Y240157D02*
X1008267Y242125D01*
G01X1006299Y224409D02*
X1008267Y226377D01*
G01X1002362Y248031D02*
X1004330Y249999D01*
G01X994488Y248031D02*
X996456Y249999D01*
G01X986614Y248031D02*
X988582Y249999D01*
G01X982677Y248031D02*
X984645Y249999D01*
G01X982677Y244094D02*
X984645Y246062D01*
G01X998425Y251968D02*
X1000393Y253936D01*
G01X990551Y251968D02*
X992519Y253936D01*
G01X982677Y259842D02*
X984645Y261810D01*
G01X982677Y255905D02*
X984645Y257873D01*
G01X982677Y251968D02*
X984645Y253936D01*
G01X978740Y251968D02*
X980708Y253936D01*
G01X1006299Y251968D02*
X1008267Y253936D01*
G01X1014173Y129921D02*
X1016141Y127953D01*
G01X1018110Y129921D02*
X1020078Y127953D01*
G01X1014173Y125984D02*
X1016141Y124016D01*
G01X1010236Y129921D02*
X1012204Y127953D01*
G01X1010236Y141732D02*
X1012204Y139764D01*
G01X1010236Y133858D02*
X1012204Y131890D01*
G01X1010236Y157480D02*
X1012204Y155512D01*
G01X1010236Y149606D02*
X1012204Y147638D01*
G01X1010236Y177165D02*
X1012204Y175197D01*
G01X1018110Y165354D02*
X1020078Y163386D01*
G01X1014173Y165354D02*
X1016141Y163386D01*
G01X1010236Y165354D02*
X1012204Y163386D01*
G01X1010236Y169291D02*
X1012204Y167323D01*
G01X1010236Y185039D02*
X1012204Y183071D01*
G01X1018110Y200787D02*
X1020078Y202755D01*
G01X1014173Y200787D02*
X1016141Y202755D01*
G01X1010236Y192913D02*
X1012204Y194881D01*
G01X1010236Y200787D02*
X1012204Y202755D01*
G01X1010236Y204724D02*
X1012204Y206692D01*
G01X1010236Y212598D02*
X1012204Y214566D01*
G01X1018110Y236220D02*
X1020078Y238188D01*
G01X1014173Y236220D02*
X1016141Y238188D01*
G01X1018110Y240157D02*
X1020078Y242125D01*
G01X1014173Y240157D02*
X1016141Y242125D01*
G01X1010236Y228346D02*
X1012204Y230314D01*
G01X1010236Y236220D02*
X1012204Y238188D01*
G01X1010236Y220472D02*
X1012204Y222440D01*
G01X1018110Y244094D02*
X1020078Y246062D01*
G01X1018110Y248031D02*
X1020078Y249999D01*
G01X1010236Y248031D02*
X1012204Y249999D01*
G01X1018110Y251968D02*
X1020078Y253936D01*
G01X1014173Y251968D02*
X1016141Y253936D01*
G01X1018110Y255905D02*
X1020078Y257873D01*
X122700Y476100D03*
Y478400D03*
X122600Y473800D03*
Y471500D03*
X121673Y491672D03*
X130985Y504300D03*
X124822Y504271D03*
X127973Y504272D03*
X121673Y497973D03*
Y494822D03*
X118524Y491672D03*
X118500Y504238D03*
X115373Y504271D03*
X127973Y510571D03*
X124823D03*
X121673D03*
X131121Y513721D03*
X121673D03*
X131121Y510570D03*
X127971Y513721D03*
X124821D03*
X127971Y494823D03*
X131122Y491674D03*
X127973Y488524D03*
X131122D03*
Y485374D03*
X121673Y504272D03*
X124823Y501122D03*
X121673D03*
X127973Y497973D03*
X124822Y488523D03*
X127973Y491674D03*
X124823Y497973D03*
Y491674D03*
X127973Y485374D03*
X124823Y494822D03*
X131121Y494823D03*
X127973Y501122D03*
Y529469D03*
X124823Y523170D03*
Y542067D03*
X127973Y532618D03*
Y542067D03*
X124823Y532617D03*
X124822Y545216D03*
X131122Y532618D03*
X124823Y535766D03*
X127973Y538918D03*
X127996Y535781D03*
X121673Y545215D03*
Y523170D03*
X131121Y529467D03*
Y520018D03*
X127971D03*
X131121Y523168D03*
X124822Y520019D03*
X121673Y520020D03*
X115374Y529467D03*
X118524D03*
X121673D03*
X124823D03*
X121673Y532617D03*
X124822Y538917D03*
X121673Y535766D03*
X127973Y523170D03*
X121673Y538916D03*
X126869Y577770D03*
X122547Y564452D03*
Y558100D03*
Y551748D03*
X121601Y574686D03*
X126801Y574386D03*
X124900Y559638D03*
X124847Y550110D03*
X124900Y556462D03*
Y565990D03*
Y562814D03*
Y553286D03*
X122547Y561276D03*
Y554924D03*
Y567628D03*
X131369Y610945D03*
X115622Y604646D03*
X121911Y614076D03*
X131369Y588898D03*
X121922Y592048D03*
X118771Y595196D03*
X125072Y610945D03*
X125070Y598347D03*
X131370Y601496D03*
X118773Y601495D03*
X126646Y606400D03*
X115622Y614094D03*
Y601496D03*
X121922Y610945D03*
X128220Y614095D03*
X118773Y604645D03*
X125070Y614095D03*
X118773Y598345D03*
X118805Y614099D03*
X115623Y598345D03*
X118773Y610945D03*
X131369Y614095D03*
X118773Y589748D03*
X128221Y610945D03*
X121922Y588872D03*
X118773Y592048D03*
X121922Y617244D03*
X128221D03*
X131369D03*
X118771D03*
X125070D03*
X125072Y620392D03*
X121921D03*
X140571Y491674D03*
X140570Y488523D03*
X162618Y485374D03*
X150020Y491674D03*
X156319Y485374D03*
X146870Y491674D03*
Y482225D03*
X150020Y510571D03*
X153169D03*
X146870D03*
X153169Y513721D03*
X146870D03*
X150020D03*
X143721Y491674D03*
Y488524D03*
Y485374D03*
X140569Y494823D03*
X134270Y510571D03*
Y504272D03*
X146869Y494823D03*
X153168D03*
X159467D03*
X165768Y488524D03*
X153170Y491674D03*
X150020Y485374D03*
Y482225D03*
X146870Y485374D03*
Y488524D03*
X162618D03*
Y491674D03*
X134272D03*
X165768D03*
X134272Y488524D03*
Y485374D03*
X137421Y491674D03*
Y485374D03*
X140571D03*
X156318Y488523D03*
X156319Y491674D03*
X153169Y485374D03*
Y488524D03*
X159469Y491674D03*
Y488524D03*
Y485374D03*
X150020Y488524D03*
X137421D03*
X165766Y542066D03*
X143721Y532618D03*
X146870Y516870D03*
X150020D03*
X153169D03*
X137421Y535768D03*
Y542066D03*
X134270Y538916D03*
X137421Y532618D03*
X134272Y542066D03*
Y535768D03*
X140570Y535767D03*
X137421Y538918D03*
X153188Y538899D03*
X162617Y535766D03*
X146869Y538954D03*
X146858Y535742D03*
X159449Y542048D03*
Y538898D03*
X159456Y532642D03*
X162617Y542066D03*
Y538916D03*
X149981Y538917D03*
X153132Y535767D03*
X149985Y535771D03*
X153194Y542078D03*
X153187Y532636D03*
X140571Y532618D03*
X143718Y538953D03*
X143686Y542070D03*
X146869Y529469D03*
X134270Y523170D03*
X153168Y529469D03*
X140569D03*
X134270Y516869D03*
X159467Y529469D03*
X134272Y532618D03*
X162618D03*
X165766Y538916D03*
X151989Y552538D03*
X147451Y554136D03*
X142951Y553336D03*
X161280Y553800D03*
Y561700D03*
Y564000D03*
X147451Y551836D03*
Y549536D03*
X142951Y551036D03*
X161280Y566300D03*
X159537Y548256D03*
X147451Y556436D03*
X142951Y555636D03*
X160700Y551356D03*
X151989Y557138D03*
X161280Y556100D03*
X151989Y554838D03*
X161280Y558400D03*
X143968Y614095D03*
X143967Y610945D03*
X137669Y604645D03*
X162865Y595196D03*
Y604645D03*
X156566Y610945D03*
X159716Y598345D03*
X153417Y614095D03*
X150269D03*
X153418Y595197D03*
X162865Y610945D03*
X137661Y614096D03*
X137670Y595197D03*
X147143Y595184D03*
X137669Y610945D03*
Y601495D03*
X140818D03*
X134521Y595196D03*
X134519Y614095D03*
X150269Y598347D03*
X156566Y614095D03*
X143968Y601495D03*
X140821Y614106D03*
X166016Y601496D03*
X159716Y610945D03*
Y614095D03*
Y595197D03*
X166016Y610944D03*
X162867Y614095D03*
X147115Y598360D03*
X150268Y601496D03*
X147141Y614096D03*
X143968Y588898D03*
X153417Y610945D03*
X159716Y604645D03*
X166015Y598345D03*
X147117Y610945D03*
X162865Y601495D03*
X150268Y610944D03*
X159716Y601495D03*
X140818Y610945D03*
X134520Y610944D03*
X153418Y592048D03*
X159716D03*
X134521Y598345D03*
X143968Y592048D03*
X147117Y601495D03*
X143969Y617244D03*
X162881Y617266D03*
X153417Y617244D03*
X150251Y617226D03*
X134521Y617266D03*
X137671D03*
X140821D03*
X156566Y617244D03*
X159716D03*
X150351Y620436D03*
X181514Y479075D03*
X172065Y513721D03*
X175215D03*
X178365Y510571D03*
X175215D03*
X172065D03*
Y501122D03*
X178365Y507422D03*
X175215D03*
Y491674D03*
Y497973D03*
X172065Y491674D03*
X175215Y485374D03*
X175217Y482225D03*
X175215Y501122D03*
X178365D03*
X184664Y485372D03*
X172065Y494823D03*
X178365Y491674D03*
X181514Y488524D03*
X184664Y488522D03*
X175215Y494823D03*
X172065Y497973D03*
X178365Y494823D03*
X172065Y485374D03*
X172067Y482225D03*
X178365Y497973D03*
X172065Y504272D03*
X175216Y504271D03*
X172065Y507422D03*
X178365Y504272D03*
X168916Y510571D03*
Y504272D03*
X178365Y513721D03*
X172065Y488524D03*
X175216Y488523D03*
X178365Y485374D03*
Y488524D03*
X181514Y485374D03*
X178365Y520020D03*
X181514D03*
X172065Y535768D03*
Y526319D03*
X178365Y529469D03*
X175215D03*
X172065D03*
X175215Y523170D03*
X178365D03*
X175216Y535767D03*
X184664Y516869D03*
X172065Y523170D03*
Y520020D03*
X175216Y520019D03*
X168916Y523170D03*
Y516870D03*
X184665Y520019D03*
X178365Y526319D03*
X175215D03*
Y532618D03*
X178365Y535768D03*
X172065Y532618D03*
X175215Y538918D03*
X168916Y535766D03*
X172065Y538918D03*
X168916Y542066D03*
Y538916D03*
X178365Y532618D03*
X874410Y127953D03*
Y139764D03*
Y131890D03*
Y120079D03*
Y124016D03*
Y163386D03*
Y155512D03*
Y147638D03*
Y202755D03*
Y206692D03*
Y194881D03*
Y183071D03*
Y242125D03*
Y238188D03*
Y230314D03*
Y222440D03*
Y214566D03*
Y257873D03*
Y253936D03*
Y249999D03*
Y246062D03*
X876378Y129921D03*
Y133858D03*
Y141732D03*
X880315Y129921D03*
Y133858D03*
Y137795D03*
Y141732D03*
X884252Y129921D03*
Y133858D03*
Y137795D03*
Y141732D03*
X888189Y118110D03*
Y122047D03*
Y125984D03*
Y129921D03*
Y133858D03*
Y137795D03*
Y141732D03*
X892126Y122047D03*
Y125984D03*
Y129921D03*
Y133858D03*
Y137795D03*
Y141732D03*
X896063Y118110D03*
Y122047D03*
Y125984D03*
Y129921D03*
Y133858D03*
Y137795D03*
Y141732D03*
X900000Y122047D03*
Y125984D03*
Y129921D03*
Y133858D03*
Y137795D03*
Y141732D03*
X903937Y118110D03*
Y122047D03*
Y125984D03*
Y129921D03*
Y133858D03*
Y137795D03*
Y141732D03*
X907874Y118110D03*
Y122047D03*
Y125984D03*
Y129921D03*
Y133858D03*
Y137795D03*
Y141732D03*
X894095Y131890D03*
X898032Y139764D03*
Y131890D03*
Y135827D03*
X905906Y127953D03*
X894095Y139764D03*
X905906Y124016D03*
Y120079D03*
Y116142D03*
X901969Y124016D03*
X894095D03*
X890158Y127953D03*
X901969D03*
X898032D03*
X894095D03*
X882284Y139764D03*
X886221Y135827D03*
X882284Y131890D03*
X886221Y124016D03*
X878347D03*
X886221Y127953D03*
X882284D03*
X878347D03*
X901969Y139764D03*
Y135827D03*
Y131890D03*
X886221Y139764D03*
X890158Y135827D03*
X886221Y131890D03*
X890158Y139764D03*
X894095Y135827D03*
X890158Y131890D03*
X878347Y135827D03*
Y116142D03*
X882284Y120079D03*
X886221Y116142D03*
X890158Y120079D03*
X894095Y116142D03*
X898032Y120079D03*
X901969Y116142D03*
X878347Y139764D03*
X882284Y135827D03*
X878347Y131890D03*
Y120079D03*
X882300Y124032D03*
X886221Y120079D03*
X890158Y124016D03*
X894095Y120079D03*
X898032Y124016D03*
X901969Y120079D03*
X905906Y139764D03*
Y135827D03*
Y131890D03*
X876378Y149606D03*
Y157480D03*
Y165354D03*
Y169291D03*
X880315Y145669D03*
Y149606D03*
Y153543D03*
Y157480D03*
Y161417D03*
Y165354D03*
Y169291D03*
Y173228D03*
X884252Y145669D03*
Y149606D03*
Y153543D03*
Y157480D03*
Y161417D03*
Y165354D03*
Y169291D03*
Y173228D03*
X888189Y145669D03*
Y149606D03*
Y153543D03*
Y157480D03*
Y161417D03*
Y165354D03*
Y169291D03*
Y173228D03*
X892126Y145669D03*
Y149606D03*
Y153543D03*
Y157480D03*
Y161417D03*
Y165354D03*
Y169291D03*
Y173228D03*
X896063Y145669D03*
Y149606D03*
Y153543D03*
Y157480D03*
Y161417D03*
Y165354D03*
Y169291D03*
Y173228D03*
X900000Y145669D03*
Y149606D03*
Y153543D03*
Y157480D03*
Y161417D03*
Y165354D03*
Y169291D03*
Y173228D03*
X903937Y145669D03*
Y149606D03*
Y153543D03*
Y157480D03*
Y161417D03*
Y165354D03*
Y169291D03*
Y173228D03*
X907874Y145669D03*
Y149606D03*
Y153543D03*
Y157480D03*
Y161417D03*
Y165354D03*
Y169291D03*
Y173228D03*
X894095Y163386D03*
X898032D03*
Y167323D03*
Y171260D03*
Y175197D03*
X901969Y163386D03*
X905906D03*
X898032Y143701D03*
Y147638D03*
Y151575D03*
Y155512D03*
Y159449D03*
X886221Y171260D03*
X901969Y167323D03*
X905906D03*
X901969Y171260D03*
X905906D03*
X901969Y175197D03*
X905906D03*
X890158Y163386D03*
X894095Y167323D03*
Y175197D03*
X905906Y159449D03*
X901969D03*
X894095Y155512D03*
Y147638D03*
X882284Y167323D03*
X886221Y163386D03*
X882284D03*
X878347D03*
X886221Y159449D03*
X882284Y155512D03*
X886221Y151575D03*
X882284Y147638D03*
X886221Y143701D03*
X901969Y147638D03*
Y143701D03*
X890158Y159449D03*
X886221Y155512D03*
X890158Y151575D03*
X886221Y147638D03*
X890158Y143701D03*
X894095Y159449D03*
X890158Y155512D03*
X894095Y151575D03*
X890158Y147638D03*
X894095Y143701D03*
X878347Y159449D03*
Y151575D03*
Y143701D03*
X882284Y159449D03*
X878347Y155512D03*
X882284Y151575D03*
X878347Y147638D03*
X882284Y143701D03*
X905906Y155512D03*
Y151575D03*
Y147638D03*
Y143701D03*
X901969Y155512D03*
Y151575D03*
X876378Y177165D03*
Y185039D03*
Y192913D03*
Y200787D03*
Y204724D03*
X880315Y177165D03*
Y181102D03*
Y185039D03*
Y188976D03*
Y192913D03*
Y196850D03*
Y200787D03*
Y204724D03*
Y208661D03*
X884252Y177165D03*
Y181102D03*
Y185039D03*
Y188976D03*
Y192913D03*
Y196850D03*
Y200787D03*
Y204724D03*
Y208661D03*
X888189Y177165D03*
Y181102D03*
Y185039D03*
Y188976D03*
Y192913D03*
Y196850D03*
Y200787D03*
Y204724D03*
Y208661D03*
X892126Y177165D03*
Y181102D03*
Y185039D03*
Y188976D03*
Y192913D03*
Y196850D03*
Y200787D03*
Y204724D03*
Y208661D03*
X896063Y177165D03*
Y181102D03*
Y185039D03*
Y188976D03*
Y192913D03*
Y196850D03*
Y200787D03*
Y204724D03*
Y208661D03*
X900000Y177165D03*
Y181102D03*
Y185039D03*
Y188976D03*
Y192913D03*
Y196850D03*
Y200787D03*
Y204724D03*
Y208661D03*
X903937Y177165D03*
Y181102D03*
Y185039D03*
Y188976D03*
Y192913D03*
Y196850D03*
Y200787D03*
Y204724D03*
Y208661D03*
X907874Y177165D03*
Y181102D03*
Y185039D03*
Y188976D03*
Y192913D03*
Y196850D03*
Y200787D03*
Y204724D03*
Y208661D03*
X898032Y194881D03*
Y198818D03*
Y202755D03*
X894095D03*
X898032Y179134D03*
Y183071D03*
Y190944D03*
X905906Y183071D03*
X901969D03*
Y194881D03*
X905906D03*
X901969Y198818D03*
X905906D03*
X901969Y202755D03*
X905906D03*
X901969Y206692D03*
X905906D03*
X890158Y202755D03*
X898032Y206692D03*
X894095D03*
Y194881D03*
X901969Y179134D03*
X905906D03*
X901969Y190944D03*
X905906D03*
X894095Y183071D03*
X882284Y206692D03*
X886221Y202755D03*
X882284D03*
X878347D03*
X886221Y198818D03*
X882284Y194881D03*
X886221Y190944D03*
Y179134D03*
Y206692D03*
X890158Y198818D03*
X886221Y194881D03*
X890158Y190944D03*
X886221Y183071D03*
X890158Y179134D03*
Y206692D03*
X894095Y198818D03*
X890158Y194881D03*
X894095Y190944D03*
X890158Y183071D03*
X894095Y179134D03*
X878347Y198818D03*
Y190944D03*
Y206692D03*
X882284Y198818D03*
X878347Y194881D03*
X882284Y190944D03*
X878347Y183071D03*
X876378Y212598D03*
Y220472D03*
Y228346D03*
Y236220D03*
Y240157D03*
X880315Y212598D03*
Y216535D03*
Y220472D03*
Y224409D03*
Y228346D03*
Y232283D03*
Y236220D03*
Y240157D03*
X884252Y212598D03*
Y216535D03*
Y220472D03*
Y224409D03*
Y228346D03*
Y232283D03*
Y236220D03*
Y240157D03*
X888189Y212598D03*
Y216535D03*
Y220472D03*
Y224409D03*
Y228346D03*
Y232283D03*
Y236220D03*
Y240157D03*
X892126Y212598D03*
Y216535D03*
Y220472D03*
Y224409D03*
Y228346D03*
Y232283D03*
Y236220D03*
Y240157D03*
X896063Y212598D03*
Y216535D03*
Y220472D03*
Y224409D03*
Y228346D03*
Y232283D03*
Y236220D03*
Y240157D03*
X900000Y212598D03*
Y216535D03*
Y220472D03*
Y224409D03*
Y228346D03*
Y232283D03*
Y236220D03*
Y240157D03*
X903937Y212598D03*
Y216535D03*
Y220472D03*
Y224409D03*
Y228346D03*
Y232283D03*
Y236220D03*
Y240157D03*
X907874Y212598D03*
Y216535D03*
Y220472D03*
Y224409D03*
Y228346D03*
Y232283D03*
Y236220D03*
Y240157D03*
X898032Y238188D03*
X894095D03*
X898032Y234251D03*
Y230314D03*
X905906Y238188D03*
X901969D03*
X898032Y226377D03*
Y222440D03*
Y218503D03*
Y214566D03*
Y210629D03*
X901969Y222440D03*
X905906D03*
X901969Y226377D03*
X905906D03*
Y234251D03*
X901969Y230314D03*
X905906D03*
X901969Y234251D03*
X894095Y222440D03*
X890158Y238188D03*
X894095Y242125D03*
Y230314D03*
X901969Y242125D03*
Y210629D03*
X905906D03*
X901969Y214566D03*
X905906D03*
X901969Y218503D03*
X905906D03*
X894095Y214566D03*
X886221Y226377D03*
X882284Y222440D03*
X886221Y242125D03*
X878347D03*
X886221Y238188D03*
X882284D03*
X878347D03*
X886221Y234251D03*
X882284Y230314D03*
X886221Y218503D03*
X882284Y214566D03*
X886221Y210629D03*
X890158Y234251D03*
X886221Y230314D03*
X890158Y226377D03*
X886221Y222440D03*
X890158Y218503D03*
X886221Y214566D03*
X890158Y210629D03*
X905906Y242125D03*
X898032D03*
X890158D03*
X882284D03*
X894095Y234251D03*
X890158Y230314D03*
X894095Y226377D03*
X890158Y222440D03*
X894095Y218503D03*
X890158Y214566D03*
X894095Y210629D03*
X878347Y234251D03*
Y226377D03*
Y218503D03*
Y210629D03*
X882284Y234251D03*
X878347Y230314D03*
X882284Y226377D03*
X878347Y222440D03*
X882284Y218503D03*
X878347Y214566D03*
X882284Y210629D03*
X876378Y244094D03*
Y248031D03*
X880315Y244094D03*
Y248031D03*
X884252Y244094D03*
Y248031D03*
X888189Y244094D03*
Y248031D03*
Y251968D03*
Y255905D03*
Y259842D03*
X892126Y244094D03*
Y248031D03*
Y251968D03*
Y255905D03*
X896063Y244094D03*
Y248031D03*
Y251968D03*
Y255905D03*
Y259842D03*
X900000Y244094D03*
Y248031D03*
Y251968D03*
Y255905D03*
X903937Y244094D03*
Y248031D03*
Y251968D03*
Y255905D03*
Y259842D03*
X907874Y244094D03*
Y248031D03*
Y251968D03*
Y255905D03*
X901969Y253936D03*
X894095D03*
X890158Y249999D03*
X905906D03*
X898032D03*
X878347Y253936D03*
X886221D03*
X882284Y249999D03*
X905906Y246062D03*
X901969Y249999D03*
X898032Y246062D03*
X894095Y249999D03*
X890158Y246062D03*
X886221Y249999D03*
X882284Y246062D03*
X878347Y249999D03*
X901969Y246062D03*
X894095D03*
X886221D03*
X878347D03*
X905906Y257873D03*
X901969Y261810D03*
X898032Y257873D03*
X894095Y261810D03*
X890158Y257873D03*
X886221Y261810D03*
X882284Y257873D03*
X878347Y261810D03*
X905906Y253936D03*
X901969Y257873D03*
X898032Y253936D03*
X894095Y257873D03*
X890158Y253936D03*
X886221Y257873D03*
X882284Y253936D03*
X878347Y257873D03*
X911811Y122047D03*
Y125984D03*
Y129921D03*
Y133858D03*
Y137795D03*
Y141732D03*
X915748Y118110D03*
Y122047D03*
Y125984D03*
Y129921D03*
Y133858D03*
Y137795D03*
Y141732D03*
X919685Y122047D03*
Y125984D03*
Y129921D03*
Y133858D03*
Y137795D03*
Y141732D03*
X923622Y118110D03*
Y122047D03*
Y125984D03*
Y129921D03*
Y133858D03*
Y137795D03*
Y141732D03*
X927559Y122047D03*
Y125984D03*
Y129921D03*
Y133858D03*
Y137795D03*
Y141732D03*
X931496Y118110D03*
Y122047D03*
Y125984D03*
Y129921D03*
Y133858D03*
Y137795D03*
Y141732D03*
X935433Y122047D03*
Y125984D03*
Y129921D03*
Y133858D03*
Y137795D03*
Y141732D03*
X939370Y118110D03*
Y122047D03*
Y125984D03*
Y129921D03*
Y133858D03*
Y137795D03*
Y141732D03*
X909843Y131890D03*
X941339Y127953D03*
X913780Y131890D03*
Y127953D03*
Y139764D03*
X921654Y127953D03*
X929528D03*
X937402Y139764D03*
Y127953D03*
X941339Y139764D03*
X933465D03*
X921654Y135827D03*
X941339Y124016D03*
Y120079D03*
Y116142D03*
X937402Y124016D03*
X933465Y127953D03*
X929528Y124016D03*
X925591Y127953D03*
X921654Y124016D03*
X917717Y127953D03*
X909843Y135827D03*
X913780Y124016D03*
X909843Y127953D03*
X921654Y139764D03*
X929528D03*
X925591D03*
X921654Y131890D03*
X941339D03*
Y135827D03*
X933465Y131890D03*
Y135827D03*
X937402Y131890D03*
Y135827D03*
X929528Y131890D03*
Y135827D03*
X925591Y131890D03*
Y135827D03*
X909843Y120079D03*
X913780Y116142D03*
X917717Y120079D03*
X921654Y116142D03*
X925591Y120079D03*
X929528Y116142D03*
X933465Y120079D03*
X937402Y116142D03*
X909843Y124016D03*
X913780Y120079D03*
X917717Y124016D03*
X921654Y120079D03*
X925591Y124016D03*
X929528Y120079D03*
X933465Y124016D03*
X937402Y120079D03*
X913780Y135827D03*
X917717Y139764D03*
Y131890D03*
Y135827D03*
X909843Y139764D03*
X911811Y145669D03*
Y149606D03*
Y153543D03*
Y157480D03*
Y161417D03*
Y165354D03*
Y169291D03*
Y173228D03*
X915748Y145669D03*
Y149606D03*
Y153543D03*
Y157480D03*
Y161417D03*
Y165354D03*
Y169291D03*
Y173228D03*
X919685Y145669D03*
Y149606D03*
Y153543D03*
Y157480D03*
Y161417D03*
Y165354D03*
Y169291D03*
Y173228D03*
X923622Y145669D03*
Y149606D03*
Y153543D03*
Y157480D03*
Y161417D03*
Y165354D03*
Y169291D03*
Y173228D03*
X927559Y145669D03*
Y149606D03*
Y153543D03*
Y157480D03*
Y161417D03*
Y165354D03*
Y169291D03*
Y173228D03*
X931496Y145669D03*
Y149606D03*
Y153543D03*
Y157480D03*
Y161417D03*
Y165354D03*
Y169291D03*
Y173228D03*
X935433Y145669D03*
Y149606D03*
Y153543D03*
Y157480D03*
Y161417D03*
Y165354D03*
Y169291D03*
Y173228D03*
X939370Y145669D03*
Y149606D03*
Y153543D03*
Y157480D03*
Y161417D03*
Y165354D03*
Y169291D03*
Y173228D03*
X937402Y155512D03*
X941339Y151575D03*
Y155512D03*
X929528Y159449D03*
X913780Y143701D03*
Y159449D03*
X937402Y175197D03*
X941339Y171260D03*
X937402Y167323D03*
X941339Y163386D03*
X929528Y175197D03*
X933465Y171260D03*
X929528Y167323D03*
X933465Y163386D03*
X925591Y171260D03*
X921654Y175197D03*
X925591Y163386D03*
X921654Y167323D03*
X917717Y163386D03*
Y171260D03*
X921654Y159449D03*
X937402D03*
X925591Y151575D03*
X913780Y147638D03*
X917717Y159449D03*
X913780Y155512D03*
Y151575D03*
X941339Y175197D03*
Y167323D03*
X933465Y175197D03*
X937402Y171260D03*
X933465Y167323D03*
X937402Y163386D03*
X929528Y171260D03*
X925591Y175197D03*
X921654Y163386D03*
X925591Y167323D03*
X917717D03*
X921654Y171260D03*
X917717Y175197D03*
X929528Y163386D03*
X941339Y159449D03*
X937402Y151575D03*
X933465Y159449D03*
X925591D03*
X921654Y147638D03*
X909843Y163386D03*
X913780D03*
X909843Y167323D03*
X913780D03*
X909843Y171260D03*
X913780D03*
X909843Y175197D03*
X913780D03*
X909843Y147638D03*
X933465Y151575D03*
Y155512D03*
X921654Y151575D03*
X929528D03*
Y155512D03*
X925591Y143701D03*
Y147638D03*
Y155512D03*
X909843Y159449D03*
Y143701D03*
Y155512D03*
X941339Y143701D03*
Y147638D03*
X933465Y143701D03*
Y147638D03*
X937402Y143701D03*
Y147638D03*
X929528Y143701D03*
Y147638D03*
X917717Y155512D03*
Y151575D03*
Y143701D03*
Y147638D03*
X921654Y155512D03*
X911811Y177165D03*
Y181102D03*
Y185039D03*
Y188976D03*
Y192913D03*
Y196850D03*
Y200787D03*
Y204724D03*
Y208661D03*
X915748Y177165D03*
Y181102D03*
Y185039D03*
Y188976D03*
Y192913D03*
Y196850D03*
Y200787D03*
Y204724D03*
Y208661D03*
X919685Y177165D03*
Y181102D03*
Y185039D03*
Y188976D03*
Y192913D03*
Y196850D03*
Y200787D03*
Y204724D03*
Y208661D03*
X923622Y177165D03*
Y181102D03*
Y185039D03*
Y188976D03*
Y192913D03*
Y196850D03*
Y200787D03*
Y204724D03*
Y208661D03*
X927559Y177165D03*
Y181102D03*
Y185039D03*
Y188976D03*
Y192913D03*
Y196850D03*
Y200787D03*
Y204724D03*
Y208661D03*
X931496Y177165D03*
Y181102D03*
Y185039D03*
Y188976D03*
Y192913D03*
Y196850D03*
Y200787D03*
Y204724D03*
Y208661D03*
X935433Y177165D03*
Y181102D03*
Y185039D03*
Y188976D03*
Y192913D03*
Y196850D03*
Y200787D03*
Y204724D03*
Y208661D03*
X939370Y177165D03*
Y181102D03*
Y185039D03*
Y188976D03*
Y192913D03*
Y196850D03*
Y200787D03*
Y204724D03*
Y208661D03*
X917717Y179134D03*
X913780Y183071D03*
X921654Y194881D03*
X917717Y198818D03*
X937402Y194881D03*
X933465Y198818D03*
X929528Y202755D03*
X925591Y206692D03*
X929528Y194881D03*
X925591Y198818D03*
X921654Y202755D03*
X917717Y206692D03*
X933465D03*
X937402Y202755D03*
X941339Y198818D03*
Y206692D03*
X925591Y190944D03*
X933465Y179134D03*
X929528Y183071D03*
X925591Y179134D03*
X921654Y183071D03*
X941339Y190944D03*
X933465D03*
X937402Y183071D03*
X941339Y179134D03*
X917717Y190944D03*
X925591Y194881D03*
X921654Y198818D03*
X917717Y202755D03*
X937402Y206692D03*
X941339Y202755D03*
Y194881D03*
X937402Y198818D03*
X933465Y202755D03*
X929528Y206692D03*
X933465Y194881D03*
X929528Y198818D03*
X925591Y202755D03*
X921654Y206692D03*
X917717Y194881D03*
X937402Y179134D03*
X933465Y183071D03*
X929528Y190944D03*
Y179134D03*
X925591Y183071D03*
X921654Y179134D03*
X937402Y190944D03*
X917717Y183071D03*
X921654Y190944D03*
X909843Y194881D03*
X913780D03*
X909843Y198818D03*
X913780D03*
X909843Y202755D03*
X913780D03*
X909843Y206692D03*
X913780D03*
X909843Y179134D03*
X913780D03*
X909843Y183071D03*
Y190944D03*
X913780D03*
X911811Y212598D03*
Y216535D03*
Y220472D03*
Y224409D03*
Y228346D03*
Y232283D03*
Y236220D03*
Y240157D03*
X915748Y212598D03*
Y216535D03*
Y220472D03*
Y224409D03*
Y228346D03*
Y232283D03*
Y236220D03*
Y240157D03*
X919685Y212598D03*
Y216535D03*
Y220472D03*
Y224409D03*
Y228346D03*
Y232283D03*
Y236220D03*
Y240157D03*
X923622Y212598D03*
Y216535D03*
Y220472D03*
Y224409D03*
Y228346D03*
Y232283D03*
Y236220D03*
Y240157D03*
X927559Y212598D03*
Y216535D03*
Y220472D03*
Y224409D03*
Y228346D03*
Y232283D03*
Y236220D03*
Y240157D03*
X931496Y212598D03*
Y216535D03*
Y220472D03*
Y224409D03*
Y228346D03*
Y232283D03*
Y236220D03*
Y240157D03*
X935433Y212598D03*
Y216535D03*
Y220472D03*
Y224409D03*
Y228346D03*
Y232283D03*
Y236220D03*
Y240157D03*
X939370Y212598D03*
Y216535D03*
Y220472D03*
Y224409D03*
Y228346D03*
Y232283D03*
Y236220D03*
Y240157D03*
X921654Y238188D03*
X917717D03*
Y214566D03*
X913780Y238188D03*
X909843D03*
X913780Y214566D03*
X941339Y226377D03*
X937402Y222440D03*
X933465Y226377D03*
X929528Y222440D03*
X925591Y226377D03*
X929528Y230314D03*
X937402D03*
X941339Y234251D03*
X937402Y238188D03*
X933465Y234251D03*
X929528Y238188D03*
X925591Y234251D03*
X921654Y210629D03*
X925591Y214566D03*
X929528Y210629D03*
X941339Y214566D03*
X933465D03*
X937402Y210629D03*
X917717Y222440D03*
Y226377D03*
X921654Y222440D03*
Y226377D03*
X917717Y230314D03*
Y234251D03*
X921654Y230314D03*
Y234251D03*
X925591Y230314D03*
Y222440D03*
X933465D03*
X941339D03*
X937402Y226377D03*
X929528D03*
X941339Y238188D03*
Y230314D03*
X937402Y242125D03*
Y234251D03*
X933465Y238188D03*
Y230314D03*
X929528Y242125D03*
Y234251D03*
X925591Y238188D03*
X921654Y242125D03*
X929528Y214566D03*
X933465Y210629D03*
X925591D03*
X917717D03*
X921654Y218503D03*
X925591D03*
X929528D03*
X933465D03*
X937402D03*
X941339D03*
X921654Y214566D03*
X917717Y218503D03*
X937402Y214566D03*
X913780Y226377D03*
X909843Y222440D03*
X913780D03*
X909843Y226377D03*
Y230314D03*
Y234251D03*
X913780Y230314D03*
Y234251D03*
Y242125D03*
X909843D03*
Y214566D03*
Y210629D03*
X913780D03*
X909843Y218503D03*
X913780D03*
X941339Y242125D03*
X933465D03*
X925591D03*
X917717D03*
X911811Y244094D03*
Y248031D03*
Y251968D03*
Y255905D03*
Y259842D03*
X915748Y244094D03*
Y248031D03*
Y251968D03*
Y255905D03*
Y259842D03*
X919685Y244094D03*
Y248031D03*
Y251968D03*
Y255905D03*
X923622Y244094D03*
Y248031D03*
Y251968D03*
Y255905D03*
Y259842D03*
X927559Y244094D03*
Y248031D03*
Y251968D03*
Y255905D03*
X931496Y244094D03*
Y248031D03*
Y251968D03*
Y255905D03*
Y259842D03*
X935433Y244094D03*
Y248031D03*
Y251968D03*
Y255905D03*
X939370Y244094D03*
Y248031D03*
Y251968D03*
Y255905D03*
Y259842D03*
X937402Y253936D03*
X929528D03*
X921654D03*
X941339Y249999D03*
X933465D03*
X925591D03*
X917717D03*
X913780Y253936D03*
X909843Y261810D03*
Y257873D03*
Y253936D03*
Y249999D03*
Y246062D03*
X941339D03*
X937402Y249999D03*
X933465Y246062D03*
X929528Y249999D03*
X925591Y246062D03*
X921654Y249999D03*
X917717Y246062D03*
X913780Y249999D03*
X937402Y246062D03*
X929528D03*
X921654D03*
X913780D03*
X941339Y257873D03*
X937402Y261810D03*
X933465Y257873D03*
X929528Y261810D03*
X925591Y257873D03*
X921654Y261810D03*
X917717Y257873D03*
X913780Y261810D03*
X941339Y253936D03*
X937402Y257873D03*
X933465Y253936D03*
X929528Y257873D03*
X925591Y253936D03*
X921654Y257873D03*
X917717Y253936D03*
X913780Y257873D03*
X943307Y118110D03*
Y122047D03*
Y125984D03*
Y129921D03*
Y133858D03*
Y137795D03*
Y141732D03*
X947244Y118110D03*
Y122047D03*
Y125984D03*
Y129921D03*
Y133858D03*
Y137795D03*
Y141732D03*
X951181Y118110D03*
Y122047D03*
Y125984D03*
Y129921D03*
Y133858D03*
Y137795D03*
Y141732D03*
X955118Y118110D03*
Y122047D03*
Y125984D03*
Y129921D03*
Y133858D03*
Y137795D03*
Y141732D03*
X959055Y122047D03*
Y125984D03*
Y129921D03*
Y133858D03*
Y137795D03*
Y141732D03*
X962992Y118110D03*
Y122047D03*
Y125984D03*
Y129921D03*
Y133858D03*
Y137795D03*
Y141732D03*
X966929Y122047D03*
Y125984D03*
Y129921D03*
Y133858D03*
Y137795D03*
Y141732D03*
X970866Y118110D03*
Y122047D03*
Y125984D03*
Y129921D03*
Y133858D03*
Y137795D03*
Y141732D03*
X974803Y122047D03*
Y125984D03*
Y129921D03*
Y133858D03*
Y137795D03*
Y141732D03*
X953149Y127953D03*
X949212D03*
Y139764D03*
X957086Y127953D03*
X964960D03*
X972834D03*
X957086Y139764D03*
X953149Y135827D03*
X968897Y139764D03*
X953149Y124016D03*
Y120079D03*
Y116142D03*
X972834Y124016D03*
X968897Y127953D03*
X964960Y124016D03*
X961023Y127953D03*
X957086Y124016D03*
X972834Y139764D03*
X953149D03*
Y131890D03*
X957086D03*
X964960D03*
X961023Y139764D03*
Y131890D03*
Y135827D03*
X957086D03*
Y116142D03*
X961023Y120079D03*
X964960Y116142D03*
X968897Y120079D03*
X972834Y116142D03*
X957086Y120079D03*
X961023Y124016D03*
X964960Y120079D03*
X968897Y124016D03*
X972834Y120079D03*
Y135827D03*
Y131890D03*
X964960Y135827D03*
Y139764D03*
X968897Y135827D03*
Y131890D03*
X943307Y145669D03*
Y149606D03*
Y153543D03*
Y157480D03*
Y161417D03*
Y165354D03*
Y169291D03*
Y173228D03*
X947244Y145669D03*
Y149606D03*
Y153543D03*
Y157480D03*
Y161417D03*
Y165354D03*
Y169291D03*
Y173228D03*
X951181Y145669D03*
Y149606D03*
Y153543D03*
Y157480D03*
Y161417D03*
Y165354D03*
Y169291D03*
Y173228D03*
X955118Y145669D03*
Y149606D03*
Y153543D03*
Y157480D03*
Y161417D03*
Y165354D03*
Y169291D03*
Y173228D03*
X959055Y145669D03*
Y149606D03*
Y153543D03*
Y157480D03*
Y161417D03*
Y165354D03*
Y169291D03*
Y173228D03*
X962992Y145669D03*
Y149606D03*
Y153543D03*
Y157480D03*
Y161417D03*
Y165354D03*
Y169291D03*
Y173228D03*
X966929Y145669D03*
Y149606D03*
Y153543D03*
Y157480D03*
Y161417D03*
Y165354D03*
Y169291D03*
Y173228D03*
X970866Y145669D03*
Y149606D03*
Y153543D03*
Y157480D03*
Y161417D03*
Y165354D03*
Y169291D03*
Y173228D03*
X974803Y145669D03*
Y149606D03*
Y153543D03*
Y157480D03*
Y161417D03*
Y165354D03*
Y169291D03*
Y173228D03*
X949212Y155512D03*
X953149Y163386D03*
X949212Y167323D03*
X964960D03*
X968897Y163386D03*
X957086Y175197D03*
X961023Y171260D03*
X953149D03*
X949212Y175197D03*
X961023Y163386D03*
X957086Y167323D03*
X972834D03*
X968897Y171260D03*
X964960Y175197D03*
X972834D03*
X968897Y151575D03*
X964960Y159449D03*
X957086D03*
X953149Y151575D03*
X949212Y159449D03*
X972834D03*
X953149Y167323D03*
X957086Y163386D03*
X949212Y171260D03*
Y163386D03*
X972834Y171260D03*
X968897Y175197D03*
X972834Y163386D03*
X968897Y167323D03*
X964960Y171260D03*
X961023Y175197D03*
Y167323D03*
X964960Y163386D03*
X953149Y175197D03*
X957086Y171260D03*
X953149Y159449D03*
X949212Y151575D03*
X972834Y147638D03*
X968897Y159449D03*
X961023D03*
Y147638D03*
X972834Y151575D03*
X957086Y143701D03*
X961023D03*
X957086Y151575D03*
Y147638D03*
Y155512D03*
X953149Y143701D03*
Y155512D03*
X949212Y143701D03*
Y147638D03*
X964960Y143701D03*
X961023Y155512D03*
Y151575D03*
X964960Y155512D03*
Y151575D03*
X968897Y155512D03*
X964960Y147638D03*
X968897D03*
Y143701D03*
X972834D03*
Y155512D03*
X943307Y177165D03*
Y181102D03*
Y185039D03*
Y188976D03*
Y192913D03*
Y196850D03*
Y200787D03*
Y204724D03*
Y208661D03*
X947244Y177165D03*
Y181102D03*
Y185039D03*
Y188976D03*
Y192913D03*
Y196850D03*
Y200787D03*
Y204724D03*
Y208661D03*
X951181Y177165D03*
Y181102D03*
Y185039D03*
Y188976D03*
Y192913D03*
Y196850D03*
Y200787D03*
Y204724D03*
Y208661D03*
X955118Y177165D03*
Y181102D03*
Y185039D03*
Y188976D03*
Y192913D03*
Y196850D03*
Y200787D03*
Y204724D03*
Y208661D03*
X959055Y177165D03*
Y181102D03*
Y185039D03*
Y188976D03*
Y192913D03*
Y196850D03*
Y200787D03*
Y204724D03*
Y208661D03*
X962992Y177165D03*
Y181102D03*
Y185039D03*
Y188976D03*
Y192913D03*
Y196850D03*
Y200787D03*
Y204724D03*
Y208661D03*
X966929Y177165D03*
Y181102D03*
Y185039D03*
Y188976D03*
Y192913D03*
Y196850D03*
Y200787D03*
Y204724D03*
Y208661D03*
X970866Y177165D03*
Y181102D03*
Y185039D03*
Y188976D03*
Y192913D03*
Y196850D03*
Y200787D03*
Y204724D03*
Y208661D03*
X974803Y177165D03*
Y181102D03*
Y185039D03*
Y188976D03*
Y192913D03*
Y196850D03*
Y200787D03*
Y204724D03*
Y208661D03*
X949212Y194881D03*
X968897Y198818D03*
X964960Y202755D03*
X961023Y206692D03*
X972834Y194881D03*
X953149Y206692D03*
X964960Y194881D03*
X961023Y198818D03*
X957086Y202755D03*
X949212D03*
X953149Y198818D03*
X957086Y194881D03*
X972834Y202755D03*
X968897Y206692D03*
X949212Y183071D03*
X953149Y179134D03*
X961023D03*
X957086Y183071D03*
X953149Y190944D03*
X968897D03*
X972834Y183071D03*
X961023Y190944D03*
X964960Y183071D03*
X968897Y179134D03*
X964960Y198818D03*
X961023Y202755D03*
X957086Y206692D03*
X968897Y194881D03*
X953149D03*
X949212Y198818D03*
Y206692D03*
X953149Y202755D03*
X961023Y194881D03*
X957086Y198818D03*
X972834Y206692D03*
Y198818D03*
X968897Y202755D03*
X964960Y206692D03*
X972834Y190944D03*
X964960Y179134D03*
X961023Y183071D03*
X957086Y190944D03*
X953149Y183071D03*
X957086Y179134D03*
X949212D03*
X964960Y190944D03*
X968897Y183071D03*
X972834Y179134D03*
X943307Y212598D03*
Y216535D03*
Y220472D03*
Y224409D03*
Y228346D03*
Y232283D03*
Y236220D03*
Y240157D03*
X947244Y212598D03*
Y216535D03*
Y220472D03*
Y224409D03*
Y228346D03*
Y232283D03*
Y236220D03*
Y240157D03*
X951181Y212598D03*
Y216535D03*
Y220472D03*
Y224409D03*
Y228346D03*
Y232283D03*
Y236220D03*
Y240157D03*
X955118Y212598D03*
Y216535D03*
Y220472D03*
Y224409D03*
Y228346D03*
Y232283D03*
Y236220D03*
Y240157D03*
X959055Y212598D03*
Y216535D03*
Y220472D03*
Y224409D03*
Y228346D03*
Y232283D03*
Y236220D03*
Y240157D03*
X962992Y212598D03*
Y216535D03*
Y220472D03*
Y224409D03*
Y228346D03*
Y232283D03*
Y236220D03*
Y240157D03*
X966929Y212598D03*
Y216535D03*
Y220472D03*
Y224409D03*
Y228346D03*
Y232283D03*
Y236220D03*
Y240157D03*
X970866Y212598D03*
Y216535D03*
Y220472D03*
Y224409D03*
Y228346D03*
Y232283D03*
Y236220D03*
Y240157D03*
X974803Y212598D03*
Y216535D03*
Y220472D03*
Y224409D03*
Y228346D03*
Y232283D03*
Y236220D03*
Y240157D03*
X972834Y238188D03*
X968897Y226377D03*
Y234251D03*
X953149Y226377D03*
X949212Y222440D03*
Y230314D03*
X964960Y222440D03*
X961023Y226377D03*
X957086Y222440D03*
X964960Y230314D03*
X957086D03*
X953149Y234251D03*
X949212Y238188D03*
X964960D03*
X961023Y234251D03*
X957086Y238188D03*
X953149Y214566D03*
X957086Y210629D03*
X949212D03*
X972834D03*
X968897Y214566D03*
X961023D03*
X964960Y210629D03*
X972834Y222440D03*
Y226377D03*
Y230314D03*
Y234251D03*
X968897Y230314D03*
Y222440D03*
X953149D03*
X961023D03*
X972834Y242125D03*
X949212Y226377D03*
X964960D03*
X957086D03*
X953149Y238188D03*
Y230314D03*
X949212Y242125D03*
Y234251D03*
X968897Y238188D03*
X964960Y242125D03*
Y234251D03*
X961023Y238188D03*
Y230314D03*
X957086Y242125D03*
Y234251D03*
X949212Y214566D03*
X953149Y210629D03*
X968897D03*
X964960Y214566D03*
X972834Y218503D03*
X949212D03*
X953149D03*
X957086Y214566D03*
X961023Y210629D03*
X972834Y214566D03*
X957086Y218503D03*
X961023D03*
X964960D03*
X968897D03*
Y242125D03*
X961023D03*
X953149D03*
X943307Y244094D03*
Y248031D03*
Y251968D03*
Y255905D03*
X947244Y244094D03*
Y248031D03*
Y251968D03*
Y255905D03*
Y259842D03*
X951181Y244094D03*
Y248031D03*
Y251968D03*
Y255905D03*
X955118Y244094D03*
Y248031D03*
Y251968D03*
Y255905D03*
Y259842D03*
X959055Y244094D03*
Y248031D03*
Y251968D03*
Y255905D03*
X962992Y244094D03*
Y248031D03*
Y251968D03*
Y255905D03*
Y259842D03*
X966929Y244094D03*
Y248031D03*
Y251968D03*
Y255905D03*
X970866Y244094D03*
Y248031D03*
Y251968D03*
Y255905D03*
Y259842D03*
X974803Y244094D03*
Y248031D03*
Y251968D03*
Y255905D03*
X972834Y253936D03*
X949212Y261810D03*
Y257873D03*
Y253936D03*
X964960D03*
X957086D03*
X953149Y249999D03*
X949212D03*
Y246062D03*
X968897Y249999D03*
X961023D03*
X972834D03*
X968897Y246062D03*
X964960Y249999D03*
X961023Y246062D03*
X957086Y249999D03*
X953149Y246062D03*
X972834D03*
X964960D03*
X957086D03*
X972834Y261810D03*
X968897Y257873D03*
X964960Y261810D03*
X961023Y257873D03*
X957086Y261810D03*
X953149Y257873D03*
X972834D03*
X968897Y253936D03*
X964960Y257873D03*
X961023Y253936D03*
X957086Y257873D03*
X953149Y253936D03*
X978740Y118110D03*
Y122047D03*
Y125984D03*
Y129921D03*
Y133858D03*
Y137795D03*
Y141732D03*
X982677Y122047D03*
Y125984D03*
Y129921D03*
Y133858D03*
Y137795D03*
Y141732D03*
X986614Y118110D03*
Y122047D03*
Y125984D03*
Y129921D03*
Y133858D03*
Y137795D03*
Y141732D03*
X990551Y118110D03*
Y122047D03*
Y125984D03*
Y129921D03*
Y133858D03*
Y137795D03*
Y141732D03*
X994488Y122047D03*
Y125984D03*
Y129921D03*
Y133858D03*
Y137795D03*
Y141732D03*
X998425Y118110D03*
Y122047D03*
Y125984D03*
Y129921D03*
Y133858D03*
Y137795D03*
Y141732D03*
X1002362Y122047D03*
Y125984D03*
Y129921D03*
Y133858D03*
Y137795D03*
Y141732D03*
X1006299Y118110D03*
Y122047D03*
Y125984D03*
Y129921D03*
Y133858D03*
Y137795D03*
Y141732D03*
X992519Y139764D03*
X996456D03*
Y131890D03*
Y135827D03*
X1000393Y131890D03*
X980708Y127953D03*
Y139764D03*
X1008267Y135827D03*
Y127953D03*
Y124016D03*
X984645Y135827D03*
X1000393Y139764D03*
X992519Y127953D03*
Y124016D03*
X988582Y127953D03*
Y124016D03*
Y120079D03*
Y116142D03*
X984645Y127953D03*
X980708Y124016D03*
X996456Y127953D03*
X1000393Y124016D03*
Y127953D03*
X1004330D03*
X976771D03*
X980708Y135827D03*
Y131890D03*
X1008267Y139764D03*
X976771Y120079D03*
X980708Y116142D03*
X984645Y120079D03*
X1008267Y131890D03*
X1004330Y135827D03*
Y139764D03*
X976771Y124016D03*
X980708Y120079D03*
X984645Y124016D03*
X1004330Y131890D03*
X1000393Y135827D03*
X992519Y115742D03*
X996456Y120079D03*
X1000393Y116142D03*
X1004330Y120079D03*
X1008267Y116142D03*
X992519Y120079D03*
X996456Y124016D03*
X1000393Y120079D03*
X1004330Y124016D03*
X1008267Y120079D03*
X988582Y139764D03*
Y135827D03*
X984645Y131890D03*
X976771D03*
Y139764D03*
X988582Y131890D03*
X984645Y139764D03*
X976771Y135827D03*
X978740Y145669D03*
Y149606D03*
Y153543D03*
Y157480D03*
Y161417D03*
Y165354D03*
Y169291D03*
Y173228D03*
X982677Y145669D03*
Y149606D03*
Y153543D03*
Y157480D03*
Y161417D03*
Y165354D03*
Y169291D03*
Y173228D03*
X986614Y145669D03*
Y149606D03*
Y153543D03*
Y157480D03*
Y161417D03*
Y165354D03*
Y169291D03*
Y173228D03*
X990551Y145669D03*
Y149606D03*
Y153543D03*
Y157480D03*
Y161417D03*
Y165354D03*
Y169291D03*
Y173228D03*
X994488Y145669D03*
Y149606D03*
Y153543D03*
Y157480D03*
Y161417D03*
Y165354D03*
Y169291D03*
Y173228D03*
X998425Y145669D03*
Y149606D03*
Y153543D03*
Y157480D03*
Y161417D03*
Y165354D03*
Y169291D03*
Y173228D03*
X1002362Y145669D03*
Y149606D03*
Y153543D03*
Y157480D03*
Y161417D03*
Y165354D03*
Y169291D03*
Y173228D03*
X1006299Y145669D03*
Y149606D03*
Y153543D03*
Y157480D03*
Y161417D03*
Y165354D03*
Y169291D03*
Y173228D03*
X996456Y163386D03*
X1000393D03*
X996456Y167323D03*
Y171260D03*
Y175197D03*
X992519Y163386D03*
X988582D03*
X980708Y175197D03*
X996456Y143701D03*
Y147638D03*
Y151575D03*
Y155512D03*
Y159449D03*
X976771Y163386D03*
Y171260D03*
X1008267Y163386D03*
Y171260D03*
Y159449D03*
Y143701D03*
Y151575D03*
X980708Y163386D03*
X984645D03*
X988582Y167323D03*
X992519D03*
X980708D03*
X984645D03*
X988582Y171260D03*
X992519D03*
X980708D03*
X984645D03*
X988582Y175197D03*
X992519D03*
X984645D03*
X1000393Y167323D03*
X1004330Y163386D03*
X1000393Y175197D03*
X988582Y159449D03*
X992519D03*
X984645Y147638D03*
X1000393D03*
Y155512D03*
X976771Y167323D03*
Y175197D03*
X980708Y159449D03*
Y155512D03*
X976771Y151575D03*
X1004330Y143701D03*
X1008267Y147638D03*
X1004330Y151575D03*
X1008267Y155512D03*
X1004330Y159449D03*
X1008267Y167323D03*
X1004330Y171260D03*
X1008267Y175197D03*
X1000393Y143701D03*
X1004330Y147638D03*
X1000393Y151575D03*
X1004330Y155512D03*
X1000393Y159449D03*
X1004330Y167323D03*
X1000393Y171260D03*
X1004330Y175197D03*
X988582Y147638D03*
Y143701D03*
X984645Y155512D03*
Y151575D03*
Y143701D03*
X988582Y151575D03*
X976771Y147638D03*
X980708Y143701D03*
X976771Y155512D03*
X980708Y147638D03*
Y151575D03*
X976771Y159449D03*
Y143701D03*
X978740Y177165D03*
Y181102D03*
Y185039D03*
Y188976D03*
Y192913D03*
Y196850D03*
Y200787D03*
Y204724D03*
Y208661D03*
X982677Y177165D03*
Y181102D03*
Y185039D03*
Y188976D03*
Y192913D03*
Y196850D03*
Y200787D03*
Y204724D03*
Y208661D03*
X986614Y177165D03*
Y181102D03*
Y185039D03*
Y188976D03*
Y192913D03*
Y196850D03*
Y200787D03*
Y204724D03*
Y208661D03*
X990551Y177165D03*
Y181102D03*
Y185039D03*
Y188976D03*
Y192913D03*
Y196850D03*
Y200787D03*
Y204724D03*
Y208661D03*
X994488Y177165D03*
Y181102D03*
Y185039D03*
Y188976D03*
Y192913D03*
Y196850D03*
Y200787D03*
Y204724D03*
Y208661D03*
X998425Y177165D03*
Y181102D03*
Y185039D03*
Y188976D03*
Y192913D03*
Y196850D03*
Y200787D03*
Y204724D03*
Y208661D03*
X1002362Y177165D03*
Y181102D03*
Y185039D03*
Y188976D03*
Y192913D03*
Y196850D03*
Y200787D03*
Y204724D03*
Y208661D03*
X1006299Y177165D03*
Y181102D03*
Y185039D03*
Y188976D03*
Y192913D03*
Y196850D03*
Y200787D03*
Y204724D03*
Y208661D03*
X996456Y194881D03*
Y198818D03*
Y202755D03*
X1000393D03*
X996456Y179134D03*
Y183071D03*
Y190944D03*
X992519Y183071D03*
X988582D03*
X976771Y179134D03*
X980708Y183071D03*
X976771Y206692D03*
Y198818D03*
Y190944D03*
X1008267Y202755D03*
Y198818D03*
Y190944D03*
Y179134D03*
X980708Y198818D03*
X988582Y194881D03*
X992519D03*
X980708D03*
X984645D03*
X988582Y198818D03*
X992519D03*
X984645D03*
X988582Y202755D03*
X992519D03*
X980708D03*
X984645D03*
X988582Y206692D03*
X992519D03*
X980708D03*
X984645D03*
X1000393D03*
X996456D03*
X1004330Y202755D03*
X1000393Y194881D03*
X988582Y179134D03*
X992519D03*
X988582Y190944D03*
X992519D03*
X980708D03*
X984645D03*
X980708Y179134D03*
X984645D03*
Y183071D03*
X1000393D03*
X976771Y202755D03*
Y194881D03*
Y183071D03*
X1004330Y179134D03*
X1008267Y183071D03*
X1004330Y190944D03*
X1008267Y194881D03*
X1004330Y198818D03*
X1008267Y206692D03*
X1000393Y179134D03*
X1004330Y183071D03*
X1000393Y190944D03*
X1004330Y194881D03*
X1000393Y198818D03*
X1004330Y206692D03*
X978740Y212598D03*
Y216535D03*
Y220472D03*
Y224409D03*
Y228346D03*
Y232283D03*
Y236220D03*
Y240157D03*
X982677Y212598D03*
Y216535D03*
Y220472D03*
Y224409D03*
Y228346D03*
Y232283D03*
Y236220D03*
Y240157D03*
X986614Y212598D03*
Y216535D03*
Y220472D03*
Y224409D03*
Y228346D03*
Y232283D03*
Y236220D03*
Y240157D03*
X990551Y212598D03*
Y216535D03*
Y220472D03*
Y224409D03*
Y228346D03*
Y232283D03*
Y236220D03*
Y240157D03*
X994488Y212598D03*
Y216535D03*
Y220472D03*
Y224409D03*
Y228346D03*
Y232283D03*
Y236220D03*
Y240157D03*
X998425Y212598D03*
Y216535D03*
Y220472D03*
Y224409D03*
Y228346D03*
Y232283D03*
Y236220D03*
Y240157D03*
X1002362Y212598D03*
Y216535D03*
Y220472D03*
Y224409D03*
Y228346D03*
Y232283D03*
Y236220D03*
Y240157D03*
X1006299Y212598D03*
Y216535D03*
Y220472D03*
Y224409D03*
Y228346D03*
Y232283D03*
Y236220D03*
Y240157D03*
X992519Y238188D03*
X988582D03*
X984645D03*
X980708D03*
X1000393D03*
X996456D03*
Y234251D03*
Y230314D03*
Y226377D03*
Y222440D03*
Y218503D03*
Y214566D03*
Y210629D03*
X976771Y238188D03*
Y214566D03*
X980708D03*
X1008267Y226377D03*
Y242125D03*
Y238188D03*
Y234251D03*
Y218503D03*
Y210629D03*
X1000393Y222440D03*
X988582D03*
X992519D03*
X980708D03*
X984645D03*
X988582Y226377D03*
X992519D03*
X984645D03*
X980708D03*
X988582Y230314D03*
X992519D03*
Y234251D03*
X980708Y230314D03*
Y234251D03*
X984645Y230314D03*
Y234251D03*
X988582D03*
X1000393Y230314D03*
X1004330Y238188D03*
X1000393Y242125D03*
X980708D03*
X984645D03*
X992519D03*
X984645Y214566D03*
X988582Y210629D03*
X992519D03*
X980708D03*
X984645D03*
X988582Y214566D03*
X992519D03*
X988582Y218503D03*
X992519D03*
X980708D03*
X984645D03*
X1000393Y214566D03*
X976771Y222440D03*
Y226377D03*
Y230314D03*
Y234251D03*
Y210629D03*
Y218503D03*
X1004330Y210629D03*
X1008267Y214566D03*
X1004330Y218503D03*
X1008267Y222440D03*
X1004330Y226377D03*
X1008267Y230314D03*
X1004330Y234251D03*
X1000393Y210629D03*
X1004330Y214566D03*
X1000393Y218503D03*
X1004330Y222440D03*
X1000393Y226377D03*
X1004330Y230314D03*
X1000393Y234251D03*
X1004330Y242125D03*
X996456D03*
X988582D03*
X976771D03*
X978740Y244094D03*
Y248031D03*
Y251968D03*
Y255905D03*
Y259842D03*
X982677Y244094D03*
Y248031D03*
Y251968D03*
Y255905D03*
Y259842D03*
X986614Y244094D03*
Y248031D03*
Y251968D03*
Y255905D03*
X990551Y244094D03*
Y248031D03*
Y251968D03*
Y255905D03*
Y259842D03*
X994488Y244094D03*
Y248031D03*
Y251968D03*
Y255905D03*
X998425Y244094D03*
Y248031D03*
Y251968D03*
Y255905D03*
Y259842D03*
X1002362Y244094D03*
Y248031D03*
Y251968D03*
Y255905D03*
X1006299Y244094D03*
Y248031D03*
Y251968D03*
Y255905D03*
Y259842D03*
X1008267Y253936D03*
X980708D03*
X984645D03*
Y257873D03*
Y261810D03*
X992519Y253936D03*
X1000393D03*
X984645Y246062D03*
Y249999D03*
X988582D03*
X996456D03*
X1004330D03*
X976771D03*
X1008267D03*
X1004330Y246062D03*
X1000393Y249999D03*
X996456Y246062D03*
X992519Y249999D03*
X988582Y246062D03*
X980708Y249999D03*
X976771Y246062D03*
X1008267D03*
X1000393D03*
X992519D03*
X980708D03*
X1008267Y261810D03*
X1004330Y257873D03*
X1000393Y261810D03*
X996456Y257873D03*
X992519Y261810D03*
X988582Y257873D03*
X980708Y261810D03*
X976771Y257873D03*
X1008267D03*
X1004330Y253936D03*
X1000393Y257873D03*
X996456Y253936D03*
X992519Y257873D03*
X988582Y253936D03*
X980708Y257873D03*
X976771Y253936D03*
X1010236Y129921D03*
Y133858D03*
Y137795D03*
Y141732D03*
X1014173Y129921D03*
Y133858D03*
Y137795D03*
Y141732D03*
X1018110Y129921D03*
Y133858D03*
Y141732D03*
X1021751Y117469D03*
X1012204Y131890D03*
Y139764D03*
Y127953D03*
X1016141Y124016D03*
X1020078Y127953D03*
X1016141D03*
X1020078Y139764D03*
X1012204Y120079D03*
X1016141Y116142D03*
X1020078Y120079D03*
Y131890D03*
X1016141Y135827D03*
Y139764D03*
X1012204Y124016D03*
X1016141Y120079D03*
X1023278D03*
X1016141Y131890D03*
X1012204Y135827D03*
X1010236Y145669D03*
Y149606D03*
Y153543D03*
Y157480D03*
Y161417D03*
Y165354D03*
Y169291D03*
Y173228D03*
X1014173Y145669D03*
Y149606D03*
Y153543D03*
Y157480D03*
Y161417D03*
Y165354D03*
Y169291D03*
Y173228D03*
X1018110Y149606D03*
Y157480D03*
Y165354D03*
Y169291D03*
X1012204Y167323D03*
Y163386D03*
X1016141D03*
X1020078D03*
X1012204Y175197D03*
Y147638D03*
Y155512D03*
X1016141Y143701D03*
X1020078Y147638D03*
X1016141Y151575D03*
X1020078Y155512D03*
X1016141Y159449D03*
X1020078Y167323D03*
X1016141Y171260D03*
X1020078Y175197D03*
X1012204Y143701D03*
X1016141Y147638D03*
X1012204Y151575D03*
X1016141Y155512D03*
X1012204Y159449D03*
X1016141Y167323D03*
X1012204Y171260D03*
X1016141Y175197D03*
X1010236Y177165D03*
Y181102D03*
Y185039D03*
Y188976D03*
Y192913D03*
Y196850D03*
Y200787D03*
Y204724D03*
Y208661D03*
X1014173Y177165D03*
Y181102D03*
Y185039D03*
Y188976D03*
Y192913D03*
Y196850D03*
Y200787D03*
Y204724D03*
Y208661D03*
X1018110Y177165D03*
Y185039D03*
Y192913D03*
Y200787D03*
Y204724D03*
X1012204Y206692D03*
Y202755D03*
Y194881D03*
X1016141Y202755D03*
X1020078D03*
X1012204Y183071D03*
X1016141Y179134D03*
X1020078Y183071D03*
X1016141Y190944D03*
X1020078Y194881D03*
X1016141Y198818D03*
X1020078Y206692D03*
X1012204Y179134D03*
X1016141Y183071D03*
X1012204Y190944D03*
X1016141Y194881D03*
X1012204Y198818D03*
X1016141Y206692D03*
X1010236Y212598D03*
Y216535D03*
Y220472D03*
Y224409D03*
Y228346D03*
Y232283D03*
Y236220D03*
Y240157D03*
X1014173Y212598D03*
Y216535D03*
Y220472D03*
Y224409D03*
Y228346D03*
Y232283D03*
Y236220D03*
Y240157D03*
X1018110Y212598D03*
Y220472D03*
Y228346D03*
Y236220D03*
Y240157D03*
X1012204Y222440D03*
Y238188D03*
Y230314D03*
X1016141Y242125D03*
X1020078D03*
X1016141Y238188D03*
X1020078D03*
X1012204Y214566D03*
Y242125D03*
X1016141Y210629D03*
X1020078Y214566D03*
X1016141Y218503D03*
X1020078Y222440D03*
X1016141Y226377D03*
X1020078Y230314D03*
X1016141Y234251D03*
X1012204Y210629D03*
X1016141Y214566D03*
X1012204Y218503D03*
X1016141Y222440D03*
X1012204Y226377D03*
X1016141Y230314D03*
X1012204Y234251D03*
X1010236Y244094D03*
Y248031D03*
X1014173Y244094D03*
Y248031D03*
X1018110Y244094D03*
Y248031D03*
X1020078Y257873D03*
X1016141Y253936D03*
X1020078D03*
X1012204Y249999D03*
X1020078D03*
Y246062D03*
X1016141Y249999D03*
X1012204Y246062D03*
X1016141D03*
Y261810D03*
X1012204Y257873D03*
X1016141D03*
X1012204Y253936D03*
G54D38*
G01X88276Y248031D02*
Y232700D01*
G01X121504Y248031D02*
X127328D01*
X127330Y248029D01*
X4100Y865800D03*
X46678Y-681D03*
X50400Y826100D03*
X93450Y562220D03*
X107400Y119000D03*
X226500Y424700D03*
X854450Y99220D03*
X1037450Y272220D03*
X1374900Y761800D03*
X1383700Y138500D03*
X1396600Y862800D03*
G54D149*
X783300Y1100D03*
X794900D03*
X838300Y2000D03*
X826700D03*
G54D168*
G01X145579Y-328699D02*
Y-346199D01*
X154313D01*
G01X167446Y-334533D02*
Y-346199D01*
G01Y-329866D02*
X167009Y-329574D01*
Y-328991D01*
X167446Y-328699D01*
X167883Y-328991D01*
Y-329574D01*
X167446Y-329866D01*
G01X181889Y-350574D02*
X183418Y-351741D01*
X185164Y-352032D01*
X186692Y-351741D01*
X188003Y-350283D01*
X188876Y-348241D01*
Y-334533D01*
G01Y-336866D02*
X188003Y-335699D01*
X186692Y-334824D01*
X185164Y-334533D01*
X183418Y-335116D01*
X182326Y-336282D01*
X181452Y-338324D01*
X181016Y-340366D01*
X181234Y-342116D01*
X182108Y-344158D01*
X183418Y-345616D01*
X185164Y-346199D01*
X186474Y-345907D01*
X188003Y-344741D01*
X188876Y-343575D01*
G01X198734Y-346199D02*
Y-328699D01*
G01Y-337157D02*
X199826Y-335699D01*
X200918Y-334824D01*
X202664Y-334533D01*
X203974Y-334824D01*
X205503Y-335991D01*
X206158Y-337741D01*
Y-346199D01*
G01X219946Y-328699D02*
Y-346199D01*
G01X216889Y-334533D02*
X223003D01*
G01X233734Y-346199D02*
Y-334533D01*
G01Y-337449D02*
X234608Y-335991D01*
X235918Y-334824D01*
X237664Y-334533D01*
X239192Y-334824D01*
X240503Y-335991D01*
X241158Y-338032D01*
Y-346199D01*
G01X254946Y-334533D02*
Y-346199D01*
G01Y-329866D02*
X254509Y-329574D01*
Y-328991D01*
X254946Y-328699D01*
X255383Y-328991D01*
Y-329574D01*
X254946Y-329866D01*
G01X268734Y-346199D02*
Y-334533D01*
G01Y-337449D02*
X269608Y-335991D01*
X270918Y-334824D01*
X272664Y-334533D01*
X274192Y-334824D01*
X275503Y-335991D01*
X276158Y-338032D01*
Y-346199D01*
G01X286889Y-350574D02*
X288418Y-351741D01*
X290164Y-352032D01*
X291692Y-351741D01*
X293003Y-350283D01*
X293876Y-348241D01*
Y-334533D01*
G01Y-336866D02*
X293003Y-335699D01*
X291692Y-334824D01*
X290164Y-334533D01*
X288418Y-335116D01*
X287326Y-336282D01*
X286452Y-338324D01*
X286016Y-340366D01*
X286234Y-342116D01*
X287108Y-344158D01*
X288418Y-345616D01*
X290164Y-346199D01*
X291474Y-345907D01*
X293003Y-344741D01*
X293876Y-343575D01*
G01X320579Y-346199D02*
Y-328699D01*
X325819D01*
X327566Y-329574D01*
X328876Y-331616D01*
X329313Y-333949D01*
X328876Y-336282D01*
X327784Y-338032D01*
X325819Y-338908D01*
X320579D01*
G01X346813Y-346199D02*
X338079D01*
Y-328699D01*
X346813D01*
G01X343319Y-337157D02*
X338079D01*
G01X361692Y-336866D02*
X362566Y-335991D01*
X363221Y-334533D01*
X363658Y-332490D01*
X363221Y-330741D01*
X362348Y-329574D01*
X360819Y-328699D01*
X354924D01*
Y-346199D01*
X362129D01*
X363658Y-345033D01*
X364531Y-343282D01*
X364968Y-341241D01*
X364531Y-339199D01*
X363221Y-337449D01*
X361692Y-336866D01*
X354924D01*
G01X390579Y-346199D02*
Y-328699D01*
X395819D01*
X397566Y-329574D01*
X398876Y-331616D01*
X399313Y-333949D01*
X398876Y-336282D01*
X397784Y-338032D01*
X395819Y-338908D01*
X390579D01*
G01X406769Y-346199D02*
Y-328699D01*
X412446Y-343282D01*
X418123Y-328699D01*
Y-346199D01*
G01X434749Y-330158D02*
X433439Y-329282D01*
X431911Y-328699D01*
X430164D01*
X428199Y-329574D01*
X426671Y-331032D01*
X425579Y-332783D01*
X424706Y-335699D01*
X424487Y-338324D01*
X424924Y-340949D01*
X425579Y-342699D01*
X426889Y-344449D01*
X428418Y-345616D01*
X429946Y-346199D01*
X431474D01*
X433003Y-345616D01*
X434313Y-344741D01*
X435405Y-343575D01*
G01X460579Y-346199D02*
Y-328699D01*
X465819D01*
X467566Y-329574D01*
X468876Y-331616D01*
X469313Y-333949D01*
X468876Y-336282D01*
X467784Y-338032D01*
X465819Y-338908D01*
X460579D01*
G01X476987Y-328699D02*
X482446Y-346199D01*
X487905Y-328699D01*
G01X499946D02*
Y-346199D01*
G01X494924Y-328699D02*
X504968D01*
G01X284269Y-301199D02*
Y-283699D01*
X289946Y-298282D01*
X295623Y-283699D01*
Y-301199D01*
G01X307446D02*
X306136Y-300907D01*
X304826Y-299741D01*
X303952Y-297699D01*
X303516Y-295366D01*
X303952Y-293032D01*
X304826Y-290991D01*
X306136Y-289824D01*
X307446Y-289533D01*
X308756Y-289824D01*
X310066Y-290991D01*
X310939Y-293032D01*
X311158Y-295366D01*
X310939Y-297699D01*
X310066Y-299741D01*
X308756Y-300907D01*
X307446Y-301199D01*
G01X328876Y-283699D02*
Y-301199D01*
G01Y-298575D02*
X328003Y-300033D01*
X326692Y-300907D01*
X325164Y-301199D01*
X323418Y-300616D01*
X322108Y-299158D01*
X321234Y-297408D01*
X321016Y-295366D01*
X321234Y-293324D01*
X322108Y-291574D01*
X323418Y-290116D01*
X325164Y-289533D01*
X326692Y-289824D01*
X327784Y-290408D01*
X328876Y-291574D01*
G01X339171Y-293324D02*
X346158D01*
X345503Y-291282D01*
X344411Y-290116D01*
X342883Y-289533D01*
X341354Y-289824D01*
X340044Y-290699D01*
X339171Y-292741D01*
X338734Y-294491D01*
Y-296241D01*
X339171Y-297991D01*
X340263Y-299741D01*
X341573Y-300907D01*
X343101Y-301199D01*
X344629Y-300616D01*
X346158Y-298866D01*
G01X359946Y-301199D02*
Y-283699D01*
G01X556346Y-346199D02*
Y-328699D01*
X553726Y-332199D01*
G01Y-346199D02*
X558966D01*
G01X569043Y-343575D02*
X570352Y-345033D01*
X571881Y-345907D01*
X573846Y-346199D01*
X575811Y-345616D01*
X577339Y-344449D01*
X578431Y-342408D01*
X578649Y-340074D01*
X578213Y-337741D01*
X577121Y-336282D01*
X575592Y-335116D01*
X574064Y-334824D01*
X572536Y-335116D01*
X570571Y-336282D01*
X571226Y-328699D01*
X577121D01*
G01X591346Y-346199D02*
Y-328699D01*
X588726Y-332199D01*
G01Y-346199D02*
X593966D01*
G01X608846Y-328699D02*
X607099Y-329282D01*
X605789Y-330741D01*
X604916Y-332490D01*
X604261Y-334824D01*
X604043Y-337449D01*
X604261Y-340074D01*
X604916Y-342408D01*
X605789Y-344158D01*
X607099Y-345616D01*
X608846Y-346199D01*
X610592Y-345616D01*
X611903Y-344158D01*
X612776Y-342408D01*
X613431Y-340074D01*
X613649Y-337449D01*
X613431Y-334824D01*
X612776Y-332490D01*
X611903Y-330741D01*
X610592Y-329282D01*
X608846Y-328699D01*
G01X621543Y-343575D02*
X622852Y-345033D01*
X624381Y-345907D01*
X626346Y-346199D01*
X628311Y-345616D01*
X629839Y-344449D01*
X630931Y-342408D01*
X631149Y-340074D01*
X630713Y-337741D01*
X629621Y-336282D01*
X628092Y-335116D01*
X626564Y-334824D01*
X625036Y-335116D01*
X623071Y-336282D01*
X623726Y-328699D01*
X629621D01*
G01X543229Y-301199D02*
Y-283699D01*
X548469D01*
X550216Y-284574D01*
X551526Y-286616D01*
X551963Y-288949D01*
X551526Y-291282D01*
X550434Y-293032D01*
X548469Y-293908D01*
X543229D01*
G01X569899Y-285158D02*
X568589Y-284282D01*
X567061Y-283699D01*
X565314D01*
X563349Y-284574D01*
X561821Y-286032D01*
X560729Y-287783D01*
X559856Y-290699D01*
X559637Y-293324D01*
X560074Y-295949D01*
X560729Y-297699D01*
X562039Y-299449D01*
X563568Y-300616D01*
X565096Y-301199D01*
X566624D01*
X568153Y-300616D01*
X569463Y-299741D01*
X570555Y-298575D01*
G01X584342Y-291866D02*
X585216Y-290991D01*
X585871Y-289533D01*
X586308Y-287490D01*
X585871Y-285741D01*
X584998Y-284574D01*
X583469Y-283699D01*
X577574D01*
Y-301199D01*
X584779D01*
X586308Y-300033D01*
X587181Y-298282D01*
X587618Y-296241D01*
X587181Y-294199D01*
X585871Y-292449D01*
X584342Y-291866D01*
X577574D01*
G01X593546Y-307032D02*
X606646D01*
G01X612574Y-301199D02*
Y-283699D01*
X622618Y-301199D01*
Y-283699D01*
G01X635096Y-301199D02*
X633349Y-300907D01*
X631821Y-299741D01*
X630511Y-297991D01*
X629637Y-295949D01*
X629201Y-293616D01*
Y-291282D01*
X629637Y-288949D01*
X630511Y-286907D01*
X631821Y-285158D01*
X633349Y-283991D01*
X635096Y-283699D01*
X636842Y-283991D01*
X638371Y-285158D01*
X639681Y-286907D01*
X640555Y-288949D01*
X640991Y-291282D01*
Y-293616D01*
X640555Y-295949D01*
X639681Y-297991D01*
X638371Y-299741D01*
X636842Y-300907D01*
X635096Y-301199D01*
G01X685937Y-283699D02*
X691396Y-301199D01*
X696855Y-283699D01*
G01X713263Y-301199D02*
X704529D01*
Y-283699D01*
X713263D01*
G01X709769Y-292157D02*
X704529D01*
G01X722029Y-301199D02*
Y-283699D01*
X727488D01*
X729234Y-284574D01*
X730326Y-285741D01*
X730763Y-288074D01*
X730326Y-290408D01*
X729016Y-291866D01*
X727488Y-292741D01*
X722029D01*
G01X727488D02*
X730763Y-301199D01*
G01X743896Y-301782D02*
X743459Y-301491D01*
Y-300907D01*
X743896Y-300616D01*
X744333Y-300907D01*
Y-301491D01*
X743896Y-301782D01*
G01X717646Y-346199D02*
Y-328699D01*
X715026Y-332199D01*
G01Y-346199D02*
X720266D01*
G01X819479Y-283699D02*
Y-301199D01*
X828213D01*
G01X845276D02*
Y-289533D01*
G01Y-291574D02*
X844403Y-290408D01*
X843092Y-289824D01*
X841564Y-289533D01*
X840036Y-290116D01*
X838726Y-291282D01*
X837852Y-293032D01*
X837416Y-295366D01*
X837852Y-297699D01*
X838726Y-299449D01*
X840036Y-300616D01*
X841564Y-301199D01*
X843092Y-300907D01*
X844403Y-300033D01*
X845276Y-298866D01*
G01X854261Y-306449D02*
X855571Y-307032D01*
X857318Y-306449D01*
X858409Y-305283D01*
X859283Y-303824D01*
X860592Y-299158D01*
X863431Y-289533D01*
G01X856444D02*
X860592Y-299158D01*
G01X873071Y-293324D02*
X880058D01*
X879403Y-291282D01*
X878311Y-290116D01*
X876783Y-289533D01*
X875254Y-289824D01*
X873944Y-290699D01*
X873071Y-292741D01*
X872634Y-294491D01*
Y-296241D01*
X873071Y-297991D01*
X874163Y-299741D01*
X875473Y-300907D01*
X877001Y-301199D01*
X878529Y-300616D01*
X880058Y-298866D01*
G01X890789Y-301199D02*
Y-289533D01*
G01Y-291866D02*
X891881Y-290699D01*
X892973Y-289824D01*
X894501Y-289533D01*
X895592Y-289824D01*
X896903Y-290699D01*
G01X845729Y-328699D02*
Y-346199D01*
X854463D01*
G01X867596D02*
Y-328699D01*
X864976Y-332199D01*
G01Y-346199D02*
X870216D01*
G01X959846Y-328699D02*
X962902Y-346199D01*
X966396Y-328699D01*
X969889Y-346199D01*
X972946Y-328699D01*
G01X979529Y-346199D02*
Y-328699D01*
X984769D01*
X986516Y-329574D01*
X987826Y-331616D01*
X988263Y-333949D01*
X987826Y-336282D01*
X986734Y-338032D01*
X984769Y-338908D01*
X979529D01*
G01X996811Y-346199D02*
Y-328699D01*
G01X1005981D02*
Y-346199D01*
G01Y-337449D02*
X996811D01*
G01X1016058Y-340366D02*
X1021734D01*
G01X1031593Y-346199D02*
Y-328699D01*
G01X1039889D02*
X1031593Y-339491D01*
G01X1041199Y-346199D02*
X1035304Y-334533D01*
G01X1058263Y-346199D02*
X1049529D01*
Y-328699D01*
X1058263D01*
G01X1054769Y-337157D02*
X1049529D01*
G01X1066374Y-346199D02*
Y-328699D01*
X1076418Y-346199D01*
Y-328699D01*
G01X1083874Y-346199D02*
Y-328699D01*
X1093918Y-346199D01*
Y-328699D01*
G01X961593Y-301199D02*
Y-283699D01*
X965959D01*
X967706Y-284574D01*
X969016Y-285741D01*
X970108Y-287490D01*
X970981Y-289533D01*
X971199Y-292449D01*
X970981Y-295366D01*
X970108Y-297408D01*
X969016Y-299158D01*
X967706Y-300324D01*
X965959Y-301199D01*
X961593D01*
G01X980621Y-293324D02*
X987608D01*
X986953Y-291282D01*
X985861Y-290116D01*
X984333Y-289533D01*
X982804Y-289824D01*
X981494Y-290699D01*
X980621Y-292741D01*
X980184Y-294491D01*
Y-296241D01*
X980621Y-297991D01*
X981713Y-299741D01*
X983023Y-300907D01*
X984551Y-301199D01*
X986079Y-300616D01*
X987608Y-298866D01*
G01X998121Y-299158D02*
X999213Y-300324D01*
X1000741Y-301199D01*
X1002051D01*
X1003361Y-300616D01*
X1004234Y-299741D01*
X1004671Y-298575D01*
X1004453Y-296824D01*
X1003579Y-295949D01*
X999649Y-294199D01*
X998776Y-292157D01*
X999213Y-290699D01*
X1000086Y-289824D01*
X1001396Y-289533D01*
X1002706Y-289824D01*
X1004016Y-290699D01*
G01X1018896Y-289533D02*
Y-301199D01*
G01Y-284866D02*
X1018459Y-284574D01*
Y-283991D01*
X1018896Y-283699D01*
X1019333Y-283991D01*
Y-284574D01*
X1018896Y-284866D01*
G01X1033339Y-305574D02*
X1034868Y-306741D01*
X1036614Y-307032D01*
X1038142Y-306741D01*
X1039453Y-305283D01*
X1040326Y-303241D01*
Y-289533D01*
G01Y-291866D02*
X1039453Y-290699D01*
X1038142Y-289824D01*
X1036614Y-289533D01*
X1034868Y-290116D01*
X1033776Y-291282D01*
X1032902Y-293324D01*
X1032466Y-295366D01*
X1032684Y-297116D01*
X1033558Y-299158D01*
X1034868Y-300616D01*
X1036614Y-301199D01*
X1037924Y-300907D01*
X1039453Y-299741D01*
X1040326Y-298575D01*
G01X1050184Y-301199D02*
Y-289533D01*
G01Y-292449D02*
X1051058Y-290991D01*
X1052368Y-289824D01*
X1054114Y-289533D01*
X1055642Y-289824D01*
X1056953Y-290991D01*
X1057608Y-293032D01*
Y-301199D01*
G01X1068121Y-293324D02*
X1075108D01*
X1074453Y-291282D01*
X1073361Y-290116D01*
X1071833Y-289533D01*
X1070304Y-289824D01*
X1068994Y-290699D01*
X1068121Y-292741D01*
X1067684Y-294491D01*
Y-296241D01*
X1068121Y-297991D01*
X1069213Y-299741D01*
X1070523Y-300907D01*
X1072051Y-301199D01*
X1073579Y-300616D01*
X1075108Y-298866D01*
G01X1085839Y-301199D02*
Y-289533D01*
G01Y-291866D02*
X1086931Y-290699D01*
X1088023Y-289824D01*
X1089551Y-289533D01*
X1090642Y-289824D01*
X1091953Y-290699D01*
G01X1132596Y-346199D02*
Y-328699D01*
X1129976Y-332199D01*
G01Y-346199D02*
X1135216D01*
G01X1150096D02*
Y-328699D01*
X1147476Y-332199D01*
G01Y-346199D02*
X1152716D01*
G01X1163666Y-346782D02*
X1171526Y-328699D01*
G01X1185096Y-346199D02*
Y-328699D01*
X1182476Y-332199D01*
G01Y-346199D02*
X1187716D01*
G01X1198448Y-338908D02*
X1199976Y-336866D01*
X1201286Y-335699D01*
X1203033Y-335116D01*
X1204561Y-335699D01*
X1205653Y-336866D01*
X1206526Y-338616D01*
X1206744Y-340657D01*
X1206526Y-342408D01*
X1205653Y-344158D01*
X1204342Y-345616D01*
X1202814Y-346199D01*
X1201068Y-345616D01*
X1199539Y-343866D01*
X1198666Y-341241D01*
X1198448Y-338324D01*
X1198884Y-334533D01*
X1199539Y-332490D01*
X1200631Y-330449D01*
X1202159Y-328991D01*
X1203688Y-328699D01*
X1205216Y-329282D01*
X1206308Y-330741D01*
G01X1216166Y-346782D02*
X1224026Y-328699D01*
G01X1233448Y-331616D02*
X1234758Y-329866D01*
X1236286Y-328991D01*
X1238033Y-328699D01*
X1240216Y-329282D01*
X1241744Y-330741D01*
X1242181Y-332490D01*
X1241963Y-334241D01*
X1241089Y-335699D01*
X1236723Y-338616D01*
X1234758Y-340657D01*
X1233448Y-343575D01*
X1233011Y-346199D01*
X1242181D01*
G01X1255096Y-328699D02*
X1253349Y-329282D01*
X1252039Y-330741D01*
X1251166Y-332490D01*
X1250511Y-334824D01*
X1250293Y-337449D01*
X1250511Y-340074D01*
X1251166Y-342408D01*
X1252039Y-344158D01*
X1253349Y-345616D01*
X1255096Y-346199D01*
X1256842Y-345616D01*
X1258153Y-344158D01*
X1259026Y-342408D01*
X1259681Y-340074D01*
X1259899Y-337449D01*
X1259681Y-334824D01*
X1259026Y-332490D01*
X1258153Y-330741D01*
X1256842Y-329282D01*
X1255096Y-328699D01*
G01X1272596Y-346199D02*
Y-328699D01*
X1269976Y-332199D01*
G01Y-346199D02*
X1275216D01*
G01X1285948Y-338908D02*
X1287476Y-336866D01*
X1288786Y-335699D01*
X1290533Y-335116D01*
X1292061Y-335699D01*
X1293153Y-336866D01*
X1294026Y-338616D01*
X1294244Y-340657D01*
X1294026Y-342408D01*
X1293153Y-344158D01*
X1291842Y-345616D01*
X1290314Y-346199D01*
X1288568Y-345616D01*
X1287039Y-343866D01*
X1286166Y-341241D01*
X1285948Y-338324D01*
X1286384Y-334533D01*
X1287039Y-332490D01*
X1288131Y-330449D01*
X1289659Y-328991D01*
X1291188Y-328699D01*
X1292716Y-329282D01*
X1293808Y-330741D01*
G01X1180293Y-301199D02*
Y-283699D01*
X1184659D01*
X1186406Y-284574D01*
X1187716Y-285741D01*
X1188808Y-287490D01*
X1189681Y-289533D01*
X1189899Y-292449D01*
X1189681Y-295366D01*
X1188808Y-297408D01*
X1187716Y-299158D01*
X1186406Y-300324D01*
X1184659Y-301199D01*
X1180293D01*
G01X1206526D02*
Y-289533D01*
G01Y-291574D02*
X1205653Y-290408D01*
X1204342Y-289824D01*
X1202814Y-289533D01*
X1201286Y-290116D01*
X1199976Y-291282D01*
X1199102Y-293032D01*
X1198666Y-295366D01*
X1199102Y-297699D01*
X1199976Y-299449D01*
X1201286Y-300616D01*
X1202814Y-301199D01*
X1204342Y-300907D01*
X1205653Y-300033D01*
X1206526Y-298866D01*
G01X1220096Y-283699D02*
Y-301199D01*
G01X1217039Y-289533D02*
X1223153D01*
G01X1234321Y-293324D02*
X1241308D01*
X1240653Y-291282D01*
X1239561Y-290116D01*
X1238033Y-289533D01*
X1236504Y-289824D01*
X1235194Y-290699D01*
X1234321Y-292741D01*
X1233884Y-294491D01*
Y-296241D01*
X1234321Y-297991D01*
X1235413Y-299741D01*
X1236723Y-300907D01*
X1238251Y-301199D01*
X1239779Y-300616D01*
X1241308Y-298866D01*
G01X38500Y276750D02*
X35750Y279500D01*
X30500D01*
X28400Y277400D01*
Y270875D01*
G01Y287925D02*
Y283500D01*
X31050Y280850D01*
X38500D01*
G01X27470Y350307D02*
Y358780D01*
X27000Y359250D01*
G01Y362750D02*
X28557Y364307D01*
X34866D01*
G01X42250Y276800D02*
X42200Y276750D01*
X38500D01*
G01X54083Y287073D02*
X51173D01*
X47800Y283700D01*
Y278850D01*
X45750Y276800D01*
G01X54083Y289042D02*
X51444D01*
X46600Y284198D01*
Y281750D01*
X45750Y280900D01*
G01X38500Y280850D02*
X42200D01*
X42250Y280900D01*
G01X35650Y394100D02*
X34866Y393316D01*
Y390400D01*
G01D02*
Y384307D01*
G01X103000Y555500D02*
X102400Y556100D01*
X99400D01*
X98240Y557260D01*
Y560048D01*
X98350Y560158D01*
Y564250D01*
X96400Y566200D01*
Y567650D01*
X98250Y569500D01*
G01Y592500D02*
X96000D01*
X95252Y591752D01*
Y585612D01*
G01X116948Y546791D02*
X113309D01*
X104600Y555500D01*
X103000D01*
G01X101750Y569500D02*
X101748Y569502D01*
Y576388D01*
G01X476614Y157493D02*
X471792D01*
X467169Y162116D01*
X451524D01*
X445717Y156309D01*
X445659D01*
X413281Y123931D01*
X362528D01*
G01X476614Y162493D02*
X475599Y163508D01*
X449678D01*
X412570Y126400D01*
X361195D01*
X358917Y124122D01*
G01X355069D02*
X359447Y128500D01*
X411840D01*
X455169Y171829D01*
X472278D01*
X476614Y167493D01*
G01X493909Y329041D02*
X481845D01*
X481801Y329085D01*
G01X522350Y340500D02*
Y338732D01*
X517659Y334041D01*
X513909D01*
G01X520672Y345868D02*
X522350Y344190D01*
Y340500D01*
G01X525409Y324291D02*
X530059D01*
X532909Y321441D01*
G01X520909Y323541D02*
X524659D01*
X525409Y324291D01*
G01X513909Y324041D02*
X520409D01*
X520909Y323541D01*
G01X525409Y328791D02*
X530059D01*
X532909Y331641D01*
G01X520909Y329541D02*
X524659D01*
X525409Y328791D01*
G01X513909Y329041D02*
X520409D01*
X520909Y329541D01*
G01X609500Y367863D02*
X607964D01*
X606900Y366799D01*
Y363652D01*
X605910Y362662D01*
X599338D01*
X597522Y364478D01*
Y366212D01*
G01X603478Y356988D02*
X606833Y353633D01*
X609500D01*
G01X615100Y365250D02*
X618829Y361521D01*
X623207D01*
G01X615100Y365250D02*
X612487Y367863D01*
X609500D01*
G01Y353633D02*
X613500D01*
G01Y357133D02*
Y360150D01*
X615100Y361750D01*
G01X623207Y359553D02*
X617297D01*
X615100Y361750D01*
G01X997007Y49560D02*
X997054Y49607D01*
X1000276D01*
X1000683Y49200D01*
G01X1005176Y45012D02*
X1004871D01*
X1000683Y49200D01*
G01X1008508Y47704D02*
X1006708D01*
X1004765Y49647D01*
G01X1010676Y45012D02*
X1008508Y47180D01*
Y47704D01*
G01X986614Y149606D02*
X988582Y147638D01*
G01X986614Y145669D02*
X988582Y143701D01*
G01X1011728Y49109D02*
Y46064D01*
X1010676Y45012D01*
G54D66*
X83667Y378687D03*
X79792Y371187D03*
X75917Y378687D03*
X112122Y378656D03*
X108247Y371156D03*
X104372Y378656D03*
X469145Y137332D03*
X465270Y129832D03*
X461395Y137332D03*
X464660Y153259D03*
X460785Y145759D03*
X456910Y153259D03*
X499278Y159142D03*
X495403Y151642D03*
X491528Y159142D03*
X513278D03*
X509403Y151642D03*
X505528Y159142D03*
X663756Y204942D03*
X659881Y197442D03*
X656006Y204942D03*
X670006D03*
X691756D03*
X687881Y197442D03*
X684006Y204942D03*
X677756D03*
X673881Y197442D03*
X1121500Y221250D03*
X1125375Y228750D03*
X1117625D03*
X1136000Y221250D03*
X1139875Y228750D03*
X1132125D03*
X1150500Y221250D03*
X1154375Y228750D03*
X1146625D03*
X1301543Y152335D03*
X1305418Y159835D03*
X1297668D03*
X1325530Y140759D03*
X1325220Y121870D03*
X1329095Y129370D03*
X1321345D03*
X1329405Y148259D03*
X1321655D03*
G54D93*
X164400Y204500D03*
X139600D03*
G54D48*
X58705Y280483D03*
X60673D03*
X62642D03*
Y315317D03*
X60673D03*
X58705D03*
X64610Y280483D03*
X66579D03*
X68547D03*
X70516D03*
X72484D03*
X74453D03*
X76421D03*
X78390D03*
X80358D03*
X82327D03*
X84295D03*
X78390Y315317D03*
X76421D03*
X74453D03*
X72484D03*
X70516D03*
X68547D03*
X66579D03*
X64610D03*
X84295D03*
X82327D03*
X80358D03*
G54D57*
X64050Y739821D03*
Y737853D03*
Y735884D03*
Y733916D03*
Y731947D03*
Y729979D03*
X44550D03*
Y731947D03*
Y733916D03*
Y735884D03*
Y737853D03*
Y739821D03*
G54D159*
X1273486Y243500D03*
X1314514D03*
G54D39*
X41603Y177598D03*
X65579D03*
X57587D03*
X49595D03*
X45559Y187598D03*
X37567D03*
X53551D03*
X73571Y177598D03*
X81563D03*
X77607Y187598D03*
X69615D03*
X85599D03*
G54D84*
G01X85250Y595440D02*
X80960D01*
X80300Y596100D01*
G01X107368Y399042D02*
Y392982D01*
X108400Y391950D01*
G01X116948Y490098D02*
X116950D01*
X118524Y491672D01*
G01D02*
X120098Y490098D01*
G01X126397Y540492D02*
Y540493D01*
X124823Y542067D01*
G01X129547Y534192D02*
X127973Y532618D01*
G01X126397Y540492D02*
X126398D01*
X127973Y542067D01*
G01D02*
X129547Y543641D01*
G01X124823Y542067D02*
X126397Y543641D01*
G01X132696Y534192D02*
X131122Y532618D01*
G01X126397Y546791D02*
X124822Y545216D01*
G01X126397Y534192D02*
X124823Y535766D01*
G01X129547Y540492D02*
X127973Y538918D01*
G01X123247Y540492D02*
X124822Y538917D01*
G01D02*
X126397Y537342D01*
G01X118351Y578186D02*
X113851D01*
G01X118773Y592048D02*
X118311D01*
X117985Y591722D01*
X117918D01*
X116773Y590577D01*
Y584627D01*
X118351Y583049D01*
Y578186D01*
G01X129795Y593622D02*
Y590472D01*
X131369Y588898D01*
G01X123496Y593622D02*
X121922Y592048D01*
G01X117197Y593622D02*
X118771Y595196D01*
G01X126646Y593622D02*
Y592705D01*
X122813Y588872D01*
X121922D01*
G01X120347Y593622D02*
X118773Y592048D01*
G01X129795Y618818D02*
X131369Y617244D01*
G01X128221D02*
X129795Y618818D01*
G01X117197D02*
X118771Y617244D01*
G01X123496Y618818D02*
X125070Y617244D01*
G01X121922D02*
X123496Y618818D01*
G01X126646D02*
X128220Y620392D01*
G01X125072D02*
X126646Y618818D01*
G01X120347D02*
X121921Y620392D01*
G01X145295Y480649D02*
Y480650D01*
X146870Y482225D01*
G01X148444Y508996D02*
X150019Y510571D01*
X150020D01*
G01X154743Y512145D02*
X153169Y510571D01*
G01X145295Y508996D02*
X146870Y510571D01*
G01X145295Y512145D02*
X146870Y513720D01*
Y513721D01*
G01X151594Y512145D02*
X153169Y513720D01*
Y513721D01*
G01X154743Y512145D02*
X157893Y515295D01*
G01X142145Y512145D02*
X145295Y515295D01*
G01X150020Y513721D02*
X148444Y512145D01*
G01X151594D02*
X150020Y513719D01*
Y513721D01*
G01X154743Y508996D02*
X156318Y510571D01*
X156319D01*
X157893Y512145D01*
G01X142145Y508996D02*
X142146D01*
X145295Y512145D01*
G01X151594Y505846D02*
Y505847D01*
X154743Y508996D01*
G01X142145Y505846D02*
X145295Y508996D01*
G01Y505846D02*
Y505847D01*
X148444Y508996D01*
G01Y505846D02*
X151594Y508996D01*
G01X154743Y505846D02*
X156319Y507422D01*
G01X148444Y493248D02*
X146870Y491674D01*
G01X153169Y510571D02*
X151594Y508996D01*
G01X154743D02*
X153169Y510570D01*
Y510571D01*
G01X151594Y512145D02*
X151595D01*
X153169Y510571D01*
G01X146870D02*
X148444Y512145D01*
G01X150020Y510571D02*
X151594Y512145D01*
G01X146870Y482225D02*
X148444Y483799D01*
G01X156319Y507422D02*
X154745Y508996D01*
X154743D01*
G01X157893D02*
X156319Y507422D01*
G01D02*
X157893Y505848D01*
Y505846D01*
G01X140569Y494823D02*
X138995Y496397D01*
G01X142145D02*
X142143D01*
X140569Y494823D01*
G01X134270Y510571D02*
X132696Y512145D01*
G01Y508996D02*
Y508997D01*
X134270Y510571D01*
G01Y504272D02*
X132696Y505846D01*
G01Y502696D02*
Y502698D01*
X134270Y504272D01*
G01X146869Y494823D02*
X145295Y496397D01*
G01X148444D02*
X148443D01*
X146869Y494823D01*
G01X153168D02*
X151594Y496397D01*
G01X154743D02*
X154742D01*
X153168Y494823D01*
G01X159467D02*
X157893Y496397D01*
G01X161043D02*
X161041D01*
X159467Y494823D01*
G01X148444Y515295D02*
X150019Y516870D01*
X150020D01*
G01X142145Y518444D02*
X143721Y520020D01*
G01X151594Y515295D02*
X153169Y516870D01*
G01X151594Y515295D02*
X150020Y513721D01*
G01X148444Y518444D02*
X146870Y516870D01*
G01X154743Y518444D02*
X157893Y521594D01*
G01X151594Y518444D02*
X153169Y520019D01*
Y520020D01*
X154743Y521594D01*
G01X148444Y518444D02*
X151594Y521594D01*
G01X145295Y518444D02*
X146870Y520019D01*
Y520020D01*
X148444Y521594D01*
G01X154743Y515295D02*
X156318Y516870D01*
X156319D01*
X157893Y518444D01*
G01X142145Y515295D02*
X142146D01*
X145295Y518444D01*
G01Y521594D02*
X143721Y520020D01*
G01X148444Y515295D02*
X150018Y513721D01*
X150020D01*
G01X146870Y516870D02*
X145295Y515295D01*
G01X148444D02*
X146870Y516869D01*
Y516870D01*
G01X145295Y518444D02*
X145296D01*
X146870Y516870D01*
G01X143721Y520020D02*
X142147Y521594D01*
X142145D01*
G01X146870Y513721D02*
X148444Y515295D01*
G01X153169Y513721D02*
X154743Y515295D01*
G01X153169Y516870D02*
X154743Y518444D01*
G01X150020Y516870D02*
X151594Y518444D01*
G01X143721Y520020D02*
Y520018D01*
X145295Y518444D01*
G01X146869Y529469D02*
X145295Y531043D01*
G01X148444D02*
X148443D01*
X146869Y529469D01*
G01X132696Y521594D02*
Y521596D01*
X134270Y523170D01*
G01D02*
X132696Y524744D01*
G01X142145Y531043D02*
X142143D01*
X140569Y529469D01*
G01X154743Y531043D02*
X154742D01*
X153168Y529469D01*
G01X140569D02*
X138995Y531043D01*
G01X153168Y529469D02*
X151594Y531043D01*
G01X134270Y516869D02*
X132696Y515295D01*
G01Y518444D02*
Y518443D01*
X134270Y516869D01*
G01X159467Y529469D02*
X157893Y531043D01*
G01X161043D02*
X161041D01*
X159467Y529469D01*
G01X165500Y589413D02*
Y592563D01*
X164441Y593622D01*
G01X153418Y592048D02*
Y579569D01*
X152319Y578470D01*
G01X143968Y592048D02*
X146200Y589816D01*
Y578771D01*
X145809Y578380D01*
G01X159751Y578386D02*
Y592013D01*
X159716Y592048D01*
G01X161291Y593622D02*
X162865Y595196D01*
G01X164441Y593622D02*
X164439D01*
X162865Y595196D01*
G01X151843Y615669D02*
X150269Y614095D01*
G01X153417D02*
X151843Y615669D01*
G01X154992Y596771D02*
X153418Y595197D01*
G01X151843Y596771D02*
X151844D01*
X153418Y595197D01*
G01X161291Y612519D02*
X162865Y610945D01*
G01X139244Y615669D02*
X139234D01*
X137661Y614096D01*
G01X139244Y596771D02*
X137670Y595197D01*
G01X147143Y595184D02*
X145556Y596771D01*
X145543D01*
G01X164441D02*
X164867Y596345D01*
X175780D01*
X177871Y598436D01*
G01X151843Y593622D02*
X151844D01*
X153418Y592048D01*
G01X154992Y593622D02*
X153418Y592048D01*
G01X158142Y593622D02*
X159716Y592048D01*
G01X136095Y596771D02*
X134521Y598345D01*
G01X142394Y593622D02*
X143968Y592048D01*
G01X145543Y599921D02*
X147117Y601495D01*
G01X143319Y636620D02*
X142394Y635695D01*
Y618818D01*
G01X145543D02*
X143969Y617244D01*
G01X161291Y618818D02*
X162843Y617266D01*
X162881D01*
G01X151843Y618818D02*
X153417Y617244D01*
G01X154992Y618818D02*
X154991D01*
X153417Y617244D01*
G01X142394Y615669D02*
Y615693D01*
X140821Y617266D01*
G01X154992Y615669D02*
Y615670D01*
X156566Y617244D01*
G01X161291Y615669D02*
X159716Y617244D01*
G01X148693Y618818D02*
X148713D01*
X150331Y620436D01*
X150351D01*
G01X158142Y618818D02*
X159716Y620392D01*
G01X164441Y618818D02*
X166015Y620392D01*
G01X168916Y510571D02*
X167342Y508997D01*
Y508996D01*
G01Y512145D02*
X168916Y510571D01*
G01Y504272D02*
X167342Y505846D01*
G01Y502696D02*
Y502698D01*
X168916Y504272D01*
G01X176791Y521594D02*
X178365Y520020D01*
G01X179940Y521594D02*
X181514Y520020D01*
G01X170491Y518444D02*
Y518446D01*
X172065Y520020D01*
G01X183090Y518444D02*
Y518443D01*
X184664Y516869D01*
G01X170491Y524744D02*
X172065Y523170D01*
G01X179940Y515295D02*
X183090D01*
G01X176791Y518444D02*
X175216Y520019D01*
G01D02*
X173641Y518444D01*
G01X175216Y520019D02*
X173641Y521594D01*
G01X179940Y518444D02*
X179941D01*
X183090Y515295D01*
G01X172065Y520020D02*
X170491Y521594D01*
G01X184664Y516869D02*
X183090Y515295D01*
G01X168916Y523170D02*
X167342Y524744D01*
G01Y521594D02*
Y521596D01*
X168916Y523170D01*
G01Y516870D02*
X167342Y518444D01*
G01Y515295D02*
Y515296D01*
X168916Y516870D01*
G01X183090Y521594D02*
X184665Y520019D01*
G01X176791Y527893D02*
X178365Y526319D01*
G01X203250Y580500D02*
Y583261D01*
X204910Y584921D01*
Y586660D01*
G01X221090Y594340D02*
X216493D01*
X216090Y593937D01*
G01X461440Y106800D02*
Y110000D01*
X459442Y111998D01*
Y114254D01*
G01X459071Y118791D02*
X459442Y118420D01*
Y114254D01*
G01X491326Y809498D02*
X487552D01*
X485300Y811750D01*
G01X752763Y38638D02*
X749750Y35625D01*
Y33760D01*
G01X773638Y80140D02*
X776540D01*
X781500Y85100D01*
G01X776538Y111540D02*
Y107162D01*
G01X798738Y129460D02*
X795360D01*
X793930Y128030D01*
G01X859000Y791000D02*
X860826Y789174D01*
Y786498D01*
G01X1012253Y34307D02*
Y37691D01*
X1014451Y39889D01*
G01X1013132Y18367D02*
X1012253Y17488D01*
Y13707D01*
G01X1264820Y377500D02*
X1258500D01*
X1257500Y378500D01*
G01D02*
Y390250D01*
X116948Y512145D03*
X120098D03*
X123247D03*
X126397D03*
X129547D03*
X116948Y508996D03*
X120098D03*
X123247D03*
X126397D03*
X129547D03*
X116948Y505846D03*
X120098D03*
X123247D03*
X126397D03*
X129547D03*
X116948Y502696D03*
X120098D03*
X123247D03*
X126397D03*
X129547D03*
X116948Y499547D03*
X120098D03*
X123247D03*
X126397D03*
X129547D03*
X116948Y496397D03*
X120098D03*
X123247D03*
X126397D03*
X129547D03*
X116948Y493248D03*
X120098D03*
X123247D03*
X126397D03*
X129547D03*
X116948Y490098D03*
X120098D03*
X123247D03*
X126397D03*
X129547D03*
X126397Y486948D03*
X129547D03*
X126397Y483799D03*
X129547D03*
X126397Y480649D03*
X129547D03*
X126397Y546791D03*
X129547D03*
X126397Y543641D03*
X129547D03*
X126397Y540492D03*
X129547D03*
X116948Y537342D03*
X120098D03*
X123247D03*
X126397D03*
X129547D03*
X116948Y534192D03*
X120098D03*
X123247D03*
X126397D03*
X129547D03*
X116948Y531043D03*
X120098D03*
X123247D03*
X126397D03*
X129547D03*
X116948Y527893D03*
X120098D03*
X123247D03*
X126397D03*
X129547D03*
X116948Y524744D03*
X120098D03*
X123247D03*
X126397D03*
X129547D03*
X116948Y521594D03*
X120098D03*
X123247D03*
X126397D03*
X129547D03*
X116948Y518444D03*
X120098D03*
X123247D03*
X126397D03*
X129547D03*
X116948Y515295D03*
X120098D03*
X123247D03*
X126397D03*
X129547D03*
X117197Y593622D03*
Y596771D03*
Y599921D03*
Y612519D03*
X120347Y593622D03*
Y596771D03*
Y599921D03*
Y612519D03*
X123496Y593622D03*
Y596771D03*
Y599921D03*
Y612519D03*
X126646Y593622D03*
Y596771D03*
Y599921D03*
Y612519D03*
X129795Y593622D03*
Y596771D03*
Y599921D03*
Y612519D03*
X117197Y615669D03*
Y618818D03*
X120347Y615669D03*
Y618818D03*
X123496Y615669D03*
Y618818D03*
X126646Y615669D03*
Y618818D03*
X129795Y615669D03*
Y618818D03*
X132696Y512145D03*
X142145D03*
X145295D03*
X148444D03*
X151594D03*
X154743D03*
X157893D03*
X132696Y508996D03*
X142145D03*
X145295D03*
X148444D03*
X151594D03*
X154743D03*
X157893D03*
X132696Y505846D03*
X142145D03*
X145295D03*
X148444D03*
X151594D03*
X154743D03*
X157893D03*
X132696Y502696D03*
X138995Y496397D03*
X142145D03*
X145295D03*
X148444D03*
X151594D03*
X154743D03*
X157893D03*
X161043D03*
X132696Y493248D03*
X135846D03*
X138995D03*
X142145D03*
X145295D03*
X148444D03*
X151594D03*
X154743D03*
X157893D03*
X161043D03*
X164192D03*
X132696Y490098D03*
X135846D03*
X138995D03*
X142145D03*
X145295D03*
X148444D03*
X151594D03*
X154743D03*
X157893D03*
X161043D03*
X164192D03*
X132696Y486948D03*
X135846D03*
X138995D03*
X142145D03*
X145295D03*
X148444D03*
X151594D03*
X154743D03*
X157893D03*
X161043D03*
X164192D03*
X132696Y483799D03*
X135846D03*
X138995D03*
X142145D03*
X145295D03*
X148444D03*
X151594D03*
X154743D03*
X157893D03*
X161043D03*
X164192D03*
X132696Y480649D03*
X135846D03*
X138995D03*
X142145D03*
X145295D03*
X148444D03*
X151594D03*
X154743D03*
X157893D03*
X161043D03*
X164192D03*
X132696Y546791D03*
X135846D03*
X138995D03*
X142145D03*
X145295D03*
X148444D03*
X151594D03*
X154743D03*
X157893D03*
X161043D03*
X164192D03*
X132696Y543641D03*
X135846D03*
X138995D03*
X142145D03*
X145295D03*
X148444D03*
X151594D03*
X154743D03*
X157893D03*
X161043D03*
X164192D03*
X132696Y540492D03*
X135846D03*
X138995D03*
X142145D03*
X145295D03*
X148444D03*
X151594D03*
X154743D03*
X157893D03*
X161043D03*
X164192D03*
X132696Y537342D03*
X135846D03*
X138995D03*
X142145D03*
X145295D03*
X148444D03*
X151594D03*
X154743D03*
X157893D03*
X161043D03*
X164192D03*
X132696Y534192D03*
X135846D03*
X138995D03*
X142145D03*
X145295D03*
X148444D03*
X151594D03*
X154743D03*
X157893D03*
X161043D03*
X164192D03*
X138995Y531043D03*
X142145D03*
X145295D03*
X148444D03*
X151594D03*
X154743D03*
X157893D03*
X161043D03*
X132696Y524744D03*
Y521594D03*
X142145D03*
X145295D03*
X148444D03*
X151594D03*
X154743D03*
X157893D03*
X132696Y518444D03*
X142145D03*
X145295D03*
X148444D03*
X151594D03*
X154743D03*
X157893D03*
X132696Y515295D03*
X142145D03*
X145295D03*
X148444D03*
X151594D03*
X154743D03*
X157893D03*
X132945Y593622D03*
Y596771D03*
Y599921D03*
Y612519D03*
X136095Y593622D03*
Y596771D03*
Y599921D03*
Y612519D03*
X139244Y593622D03*
Y596771D03*
Y599921D03*
Y612519D03*
X142394Y593622D03*
Y596771D03*
Y599921D03*
Y612519D03*
X145543Y593622D03*
Y596771D03*
Y599921D03*
Y612519D03*
X148693Y593622D03*
Y596771D03*
Y599921D03*
Y612519D03*
X151843Y593622D03*
Y596771D03*
Y599921D03*
Y612519D03*
X154992Y593622D03*
Y596771D03*
Y599921D03*
Y612519D03*
X158142Y593622D03*
Y596771D03*
Y599921D03*
Y612519D03*
X161291Y593622D03*
Y596771D03*
Y599921D03*
Y612519D03*
X164441Y593622D03*
Y596771D03*
Y599921D03*
Y612519D03*
X132945Y615669D03*
Y618818D03*
X136095Y615669D03*
Y618818D03*
X139244Y615669D03*
Y618818D03*
X142394Y615669D03*
Y618818D03*
X145543Y615669D03*
Y618818D03*
X148693Y615669D03*
Y618818D03*
X151843Y615669D03*
Y618818D03*
X154992Y615669D03*
Y618818D03*
X158142Y615669D03*
Y618818D03*
X161291Y615669D03*
Y618818D03*
X164441Y615669D03*
Y618818D03*
X167342Y512145D03*
X170491D03*
X173641D03*
X176791D03*
X179940D03*
X183090D03*
X167342Y508996D03*
X170491D03*
X173641D03*
X176791D03*
X179940D03*
X183090D03*
X167342Y505846D03*
X170491D03*
X173641D03*
X176791D03*
X179940D03*
X183090D03*
X167342Y502696D03*
X170491D03*
X173641D03*
X176791D03*
X179940D03*
X183090D03*
X170491Y499547D03*
X173641D03*
X176791D03*
X179940D03*
X183090D03*
X170491Y496397D03*
X173641D03*
X176791D03*
X179940D03*
X183090D03*
X167342Y493248D03*
X170491D03*
X173641D03*
X176791D03*
X179940D03*
X183090D03*
X167342Y490098D03*
X170491D03*
X173641D03*
X176791D03*
X179940D03*
X183090D03*
X167342Y486948D03*
X170491D03*
X173641D03*
X167342Y483799D03*
X170491D03*
X173641D03*
X167342Y480649D03*
X170491D03*
X173641D03*
X167342Y546791D03*
X170491D03*
X173641D03*
X167342Y543641D03*
X170491D03*
X173641D03*
X167342Y540492D03*
X170491D03*
X173641D03*
X167342Y537342D03*
X170491D03*
X173641D03*
X176791D03*
X179940D03*
X183090D03*
X167342Y534192D03*
X170491D03*
X173641D03*
X176791D03*
X179940D03*
X183090D03*
X170491Y531043D03*
X173641D03*
X176791D03*
X179940D03*
X183090D03*
X170491Y527893D03*
X173641D03*
X176791D03*
X179940D03*
X183090D03*
X167342Y524744D03*
X170491D03*
X173641D03*
X176791D03*
X179940D03*
X183090D03*
X167342Y521594D03*
X170491D03*
X173641D03*
X176791D03*
X179940D03*
X183090D03*
X167342Y518444D03*
X170491D03*
X173641D03*
X176791D03*
X179940D03*
X183090D03*
X167342Y515295D03*
X170491D03*
X173641D03*
X176791D03*
X179940D03*
X183090D03*
G54D75*
X86678Y722200D03*
Y720600D03*
G54D169*
G01X186808Y512691D02*
X184663Y510546D01*
X181490D01*
X179940Y508996D01*
G54D58*
X61190Y724850D03*
X47410D03*
Y744950D03*
X61190D03*
X562501Y351980D03*
X560531D03*
X558561D03*
X556596D03*
Y364180D03*
X558561D03*
X560531D03*
X562501D03*
X564466Y351980D03*
Y364180D03*
G54D94*
X149260Y228500D03*
X156740D03*
Y219500D03*
X153000D03*
X149260D03*
G54D76*
X83922Y721400D03*
G54D49*
X31600Y321200D03*
X46900Y394400D03*
X90830Y273800D03*
X68300Y417000D03*
X91285Y489504D03*
Y486004D03*
X79300Y719300D03*
X104400Y306700D03*
X112351Y638436D03*
X127700Y714300D03*
Y710800D03*
X146869Y640420D03*
X146851Y648436D03*
X137351Y643936D03*
X146851D03*
X181421Y598436D03*
X281300Y122000D03*
X278100Y634900D03*
X328892Y295900D03*
X319300Y534500D03*
X623363Y213608D03*
X891200Y51500D03*
X908300Y45000D03*
Y48500D03*
X945581Y25374D03*
X1022663Y17398D03*
X1080300Y57000D03*
Y60500D03*
Y53500D03*
Y50000D03*
X1129700Y129800D03*
Y133300D03*
X1320800Y286500D03*
G54D67*
X90093Y371207D03*
X93968Y378707D03*
X97843Y371207D03*
X85950Y695400D03*
X82075Y687900D03*
X89825D03*
X96075D03*
X99950Y695400D03*
X103825Y687900D03*
X218979Y145011D03*
X222854Y152511D03*
X226729Y145011D03*
X1364343Y173852D03*
X1372093D03*
X1368218Y181352D03*
G54D85*
G01X92588Y405615D02*
Y410753D01*
X92580Y410761D01*
G01X71709Y599470D02*
Y601791D01*
X70500Y603000D01*
X69258D01*
G01X76829Y592970D02*
Y586421D01*
X77250Y586000D01*
G01X92060Y628750D02*
X94860D01*
G01X86940Y635250D02*
Y641810D01*
X86750Y642000D01*
G01X102248Y405542D02*
Y408624D01*
X100904Y409968D01*
X100924D01*
G01X260929Y345571D02*
X258729D01*
X257200Y347100D01*
Y348840D01*
G01X249800Y353960D02*
Y357130D01*
X248930Y358000D01*
G01X269000Y498800D02*
X266336D01*
X265019Y497483D01*
G01X269000Y496240D02*
X268545Y495785D01*
X266717D01*
X265019Y497483D01*
G01X264522Y511690D02*
X263030Y510198D01*
X259857D01*
G01X264522Y511690D02*
X265212Y511000D01*
X269000D01*
G01X282300Y499450D02*
X285277D01*
X286181Y498546D01*
G01X269000Y508440D02*
Y504962D01*
G01X275286Y504392D02*
X276400Y503278D01*
Y501360D01*
G01Y513560D02*
X279933D01*
X280749Y512744D01*
G01X276400Y511000D02*
X279005D01*
X280749Y512744D01*
G01X282300Y502950D02*
X281627D01*
X279730Y501053D01*
Y499523D01*
X279007Y498800D01*
X276400D01*
G01X282300Y502950D02*
X285219D01*
X286169Y502000D01*
G01X793930Y128030D02*
X791200Y125300D01*
X116948Y486948D03*
X120098D03*
X123247D03*
X116948Y483799D03*
X120098D03*
X123247D03*
X116948Y480649D03*
X120098D03*
X123247D03*
X116948Y546791D03*
X120098D03*
X123247D03*
X116948Y543641D03*
X120098D03*
X123247D03*
X116948Y540492D03*
X120098D03*
X123247D03*
X176791Y486948D03*
X179940D03*
X183090D03*
X176791Y483799D03*
X179940D03*
X183090D03*
X176791Y480649D03*
X179940D03*
X183090D03*
X176791Y546791D03*
X179940D03*
X183090D03*
X176791Y543641D03*
X179940D03*
X183090D03*
X176791Y540492D03*
X179940D03*
X183090D03*
G54D95*
X139000Y218419D03*
Y229581D03*
G54D68*
X95148Y399115D03*
X90028D03*
Y405615D03*
X92588D03*
X95148D03*
X76829Y592970D03*
X71709D03*
Y599470D03*
X74269D03*
X76829D03*
X86940Y635250D03*
X92060D03*
Y628750D03*
X89500D03*
X86940D03*
X107368Y399042D03*
X102248D03*
Y405542D03*
X104808D03*
X107368D03*
X296122Y490150D03*
X293562D03*
X291002D03*
Y483650D03*
X296122D03*
G54D86*
X125740Y721650D03*
X123180D03*
X120620D03*
X118060D03*
Y737950D03*
X120620D03*
X123180D03*
X125740D03*
G54D77*
X97248Y813797D03*
Y820203D03*
G54D59*
X59221Y725150D03*
X57253D03*
X55284D03*
X53316D03*
X51347D03*
X49379D03*
Y744650D03*
X51347D03*
X53316D03*
X55284D03*
X57253D03*
X59221D03*
G54D96*
X141060Y243523D03*
X152028D03*
X140907Y255980D03*
X151875D03*
X566079Y264008D03*
Y276308D03*
Y300908D03*
Y288608D03*
X591079Y274408D03*
X602047D03*
X577047Y264008D03*
Y276308D03*
X591079Y299008D03*
X602047D03*
X591079Y286708D03*
X602047D03*
X577047Y300908D03*
Y288608D03*
X1334016Y192500D03*
X1344984D03*
X1334016Y205000D03*
X1344984D03*
X1334016Y230000D03*
X1344984D03*
X1334016Y217500D03*
X1344984D03*
X1369484Y203500D03*
X1358516D03*
X1369484Y217000D03*
X1358516D03*
X1369484Y230500D03*
X1358516D03*
G54D78*
X122165Y142874D03*
X173897D03*
G54D87*
X103200Y782300D03*
X108200D03*
X113200D03*
X118200D03*
G54D69*
X96860Y494107D03*
Y496307D03*
G54D88*
X104750Y813797D03*
Y820203D03*
G54D97*
X154369Y286183D03*
X140069D03*
G54D79*
X134251Y153543D03*
X161811D03*
X151968D03*
X144094D03*
G54D89*
X110700Y796865D03*
G54D98*
X143000Y388000D03*
G54D99*
X150000Y392921D03*
Y390953D03*
Y388984D03*
Y387016D03*
Y385047D03*
Y383079D03*
X136000D03*
Y385047D03*
Y387016D03*
Y388984D03*
Y390953D03*
Y392921D03*
M02*
